G04 ================== begin FILE IDENTIFICATION RECORD ==================*
G04 Layout Name:  9127_F0T_Expander_BD_F_v02_0110_1240.brd*
G04 Film Name:    gnd1*
G04 File Format:  Gerber RS274X*
G04 File Origin:  Cadence Allegro 17.2-S081*
G04 Origin Date:  Wed Jan 11 16:06:27 2023*
G04 *
G04 Layer:  VIA CLASS/GND1*
G04 Layer:  PIN/GND1*
G04 Layer:  ETCH/GND1*
G04 Layer:  DRAWING FORMAT/TITLE_BLOCK_A*
G04 Layer:  PIN/SPECIAL_DRILL*
G04 Layer:  MANUFACTURING/PHOTOPLOT_OUTLINE*
G04 Layer:  DRAWING FORMAT/TITLE_BLOCK*
G04 Layer:  DRAWING FORMAT/TITLE_DATA_GND1*
G04 *
G04 Offset:    (0.00 0.00)*
G04 Mirror:    No*
G04 Mode:      Negative*
G04 Rotation:  0*
G04 FullContactRelief:  No*
G04 UndefLineWidth:     6.00*
G04 ================== end FILE IDENTIFICATION RECORD ====================*
%FSLAX25Y25*MOIN*%
%IR0*IPPOS*OFA0.00000B0.00000*MIA0B0*SFA1.00000B1.00000*%
%ADD15C,.03*%
%ADD50C,.06*%
%ADD22C,.024*%
%ADD52C,.061*%
%ADD32C,.0322*%
%ADD42C,.071*%
%AMMACRO28*
4,1,36,0.0,.01,
-.001736,.009848,
-.00342,.009397,
-.005,.00866,
-.006428,.00766,
-.00766,.006428,
-.00866,.005,
-.009397,.00342,
-.009848,.001736,
-.01,0.0,
-.009848,-.001736,
-.009397,-.00342,
-.00866,-.005,
-.00766,-.006428,
-.006428,-.00766,
-.005,-.00866,
-.00342,-.009397,
-.001736,-.009848,
0.0,-.01,
.001736,-.009848,
.00342,-.009397,
.005,-.00866,
.006428,-.00766,
.00766,-.006428,
.00866,-.005,
.009397,-.00342,
.009848,-.001736,
.01,0.0,
.009848,.001736,
.009397,.00342,
.00866,.005,
.00766,.006428,
.006428,.00766,
.005,.00866,
.00342,.009397,
.001736,.009848,
0.0,.01,
0.0*
%
%ADD28MACRO28*%
%ADD27C,.026*%
%ADD48C,.082*%
%ADD40C,.028*%
%AMMACRO36*
4,1,20,-.0075,-.05555,
-.0075,-.06273,
-.013677,-.060878,
-.019439,-.057981,
-.024611,-.054127,
-.029034,-.049434,
-.032576,-.044045,
-.035127,-.038122,
-.036612,-.031846,
-.037,-.0265,
-.037,-.0075,
-.03,-.0075,
-.03,-.0265,
-.029544,-.03171,
-.028191,-.036762,
-.02598,-.041502,
-.022981,-.045786,
-.019282,-.049484,
-.014998,-.052484,
-.010258,-.054694,
-.0075,-.05555,
270.*
4,1,20,.0075,-.06273,
.0075,-.05555,
.01243,-.053806,
.016983,-.051232,
.02102,-.047906,
.024418,-.043931,
.027073,-.039425,
.028906,-.034527,
.029861,-.029385,
.03,-.0265,
.03,-.0075,
.037,-.0075,
.037,-.0265,
.036438,-.032925,
.034769,-.039154,
.032043,-.044999,
.028344,-.050282,
.023784,-.054842,
.018501,-.058541,
.012656,-.061266,
.0075,-.06273,
270.*
4,1,20,-.0075,.06273,
-.0075,.05555,
-.01243,.053806,
-.016983,.051232,
-.02102,.047906,
-.024418,.043931,
-.027073,.039425,
-.028906,.034527,
-.029861,.029385,
-.03,.0265,
-.03,.0075,
-.037,.0075,
-.037,.0265,
-.036438,.032925,
-.034769,.039154,
-.032043,.044999,
-.028344,.050282,
-.023784,.054842,
-.018501,.058541,
-.012656,.061266,
-.0075,.06273,
270.*
4,1,20,.0075,.05555,
.0075,.06273,
.013677,.060878,
.019439,.057981,
.024611,.054127,
.029034,.049434,
.032576,.044045,
.035127,.038122,
.036612,.031846,
.037,.0265,
.037,.0075,
.03,.0075,
.03,.0265,
.029544,.03171,
.028191,.036762,
.02598,.041502,
.022981,.045786,
.019282,.049484,
.014998,.052484,
.010258,.054694,
.0075,.05555,
270.*
%
%ADD36MACRO36*%
%AMMACRO30*
4,1,36,.0025,0.0,
.002462,.000434,
.002349,.000855,
.002165,.00125,
.001915,.001607,
.001607,.001915,
.00125,.002165,
.000855,.002349,
.000434,.002462,
0.0,.0025,
-.000434,.002462,
-.000855,.002349,
-.00125,.002165,
-.001607,.001915,
-.001915,.001607,
-.002165,.00125,
-.002349,.000855,
-.002462,.000434,
-.0025,0.0,
-.002462,-.000434,
-.002349,-.000855,
-.002165,-.00125,
-.001915,-.001607,
-.001607,-.001915,
-.00125,-.002165,
-.000855,-.002349,
-.000434,-.002462,
0.0,-.0025,
.000434,-.002462,
.000855,-.002349,
.00125,-.002165,
.001607,-.001915,
.001915,-.001607,
.002165,-.00125,
.002349,-.000855,
.002462,-.000434,
.0025,0.0,
315.*
%
%ADD30MACRO30*%
%AMMACRO14*
4,1,36,.0025,0.0,
.002462,.000434,
.002349,.000855,
.002165,.00125,
.001915,.001607,
.001607,.001915,
.00125,.002165,
.000855,.002349,
.000434,.002462,
0.0,.0025,
-.000434,.002462,
-.000855,.002349,
-.00125,.002165,
-.001607,.001915,
-.001915,.001607,
-.002165,.00125,
-.002349,.000855,
-.002462,.000434,
-.0025,0.0,
-.002462,-.000434,
-.002349,-.000855,
-.002165,-.00125,
-.001915,-.001607,
-.001607,-.001915,
-.00125,-.002165,
-.000855,-.002349,
-.000434,-.002462,
0.0,-.0025,
.000434,-.002462,
.000855,-.002349,
.00125,-.002165,
.001607,-.001915,
.001915,-.001607,
.002165,-.00125,
.002349,-.000855,
.002462,-.000434,
.0025,0.0,
180.*
%
%ADD14MACRO14*%
%AMMACRO10*
4,1,36,.0025,0.0,
.002462,.000434,
.002349,.000855,
.002165,.00125,
.001915,.001607,
.001607,.001915,
.00125,.002165,
.000855,.002349,
.000434,.002462,
0.0,.0025,
-.000434,.002462,
-.000855,.002349,
-.00125,.002165,
-.001607,.001915,
-.001915,.001607,
-.002165,.00125,
-.002349,.000855,
-.002462,.000434,
-.0025,0.0,
-.002462,-.000434,
-.002349,-.000855,
-.002165,-.00125,
-.001915,-.001607,
-.001607,-.001915,
-.00125,-.002165,
-.000855,-.002349,
-.000434,-.002462,
0.0,-.0025,
.000434,-.002462,
.000855,-.002349,
.00125,-.002165,
.001607,-.001915,
.001915,-.001607,
.002165,-.00125,
.002349,-.000855,
.002462,-.000434,
.0025,0.0,
270.*
%
%ADD10MACRO10*%
%AMMACRO43*
4,1,36,-.0025,0.0,
-.002462,.000434,
-.002349,.000855,
-.002165,.00125,
-.001915,.001607,
-.001607,.001915,
-.00125,.002165,
-.000855,.002349,
-.000434,.002462,
0.0,.0025,
.000434,.002462,
.000855,.002349,
.00125,.002165,
.001607,.001915,
.001915,.001607,
.002165,.00125,
.002349,.000855,
.002462,.000434,
.0025,0.0,
.002462,-.000434,
.002349,-.000855,
.002165,-.00125,
.001915,-.001607,
.001607,-.001915,
.00125,-.002165,
.000855,-.002349,
.000434,-.002462,
0.0,-.0025,
-.000434,-.002462,
-.000855,-.002349,
-.00125,-.002165,
-.001607,-.001915,
-.001915,-.001607,
-.002165,-.00125,
-.002349,-.000855,
-.002462,-.000434,
-.0025,0.0,
180.*
%
%ADD43MACRO43*%
%AMMACRO34*
4,1,36,.003,0.0,
.002954,.000521,
.002819,.001026,
.002598,.0015,
.002298,.001928,
.001928,.002298,
.0015,.002598,
.001026,.002819,
.000521,.002954,
0.0,.003,
-.000521,.002954,
-.001026,.002819,
-.0015,.002598,
-.001928,.002298,
-.002298,.001928,
-.002598,.0015,
-.002819,.001026,
-.002954,.000521,
-.003,0.0,
-.002954,-.000521,
-.002819,-.001026,
-.002598,-.0015,
-.002298,-.001928,
-.001928,-.002298,
-.0015,-.002598,
-.001026,-.002819,
-.000521,-.002954,
0.0,-.003,
.000521,-.002954,
.001026,-.002819,
.0015,-.002598,
.001928,-.002298,
.002298,-.001928,
.002598,-.0015,
.002819,-.001026,
.002954,-.000521,
.003,0.0,
270.*
%
%ADD34MACRO34*%
%AMMACRO24*
4,1,36,.003,0.0,
.002954,.000521,
.002819,.001026,
.002598,.0015,
.002298,.001928,
.001928,.002298,
.0015,.002598,
.001026,.002819,
.000521,.002954,
0.0,.003,
-.000521,.002954,
-.001026,.002819,
-.0015,.002598,
-.001928,.002298,
-.002298,.001928,
-.002598,.0015,
-.002819,.001026,
-.002954,.000521,
-.003,0.0,
-.002954,-.000521,
-.002819,-.001026,
-.002598,-.0015,
-.002298,-.001928,
-.001928,-.002298,
-.0015,-.002598,
-.001026,-.002819,
-.000521,-.002954,
0.0,-.003,
.000521,-.002954,
.001026,-.002819,
.0015,-.002598,
.001928,-.002298,
.002298,-.001928,
.002598,-.0015,
.002819,-.001026,
.002954,-.000521,
.003,0.0,
180.*
%
%ADD24MACRO24*%
%ADD21C,.074*%
%AMMACRO39*
4,1,36,-.003,0.0,
-.002954,.000521,
-.002819,.001026,
-.002598,.0015,
-.002298,.001928,
-.001928,.002298,
-.0015,.002598,
-.001026,.002819,
-.000521,.002954,
0.0,.003,
.000521,.002954,
.001026,.002819,
.0015,.002598,
.001928,.002298,
.002298,.001928,
.002598,.0015,
.002819,.001026,
.002954,.000521,
.003,0.0,
.002954,-.000521,
.002819,-.001026,
.002598,-.0015,
.002298,-.001928,
.001928,-.002298,
.0015,-.002598,
.001026,-.002819,
.000521,-.002954,
0.0,-.003,
-.000521,-.002954,
-.001026,-.002819,
-.0015,-.002598,
-.001928,-.002298,
-.002298,-.001928,
-.002598,-.0015,
-.002819,-.001026,
-.002954,-.000521,
-.003,0.0,
180.*
%
%ADD39MACRO39*%
%ADD25C,.0435*%
%ADD56C,.087*%
%ADD51C,.0277*%
%AMMACRO41*
4,1,18,.09673,.06845,
.107147,.050613,
.114308,.031238,
.117996,.010914,
.118098,-.009741,
.114613,-.030101,
.107644,-.049546,
.097406,-.067485,
.09673,-.06845,
.10175,-.07347,
.112962,-.054685,
.120742,-.034239,
.124853,-.012752,
.125171,.009122,
.121685,.030719,
.114502,.051383,
.10384,.070486,
.10175,.07347,
.09673,.06845,
90.*
4,1,18,.06845,-.09673,
.050613,-.107147,
.031238,-.114308,
.010914,-.117996,
-.009741,-.118098,
-.030101,-.114613,
-.049546,-.107644,
-.067485,-.097406,
-.06845,-.09673,
-.07347,-.10175,
-.054685,-.112962,
-.034239,-.120742,
-.012752,-.124853,
.009122,-.125171,
.030719,-.121685,
.051383,-.114502,
.070486,-.10384,
.07347,-.10175,
.06845,-.09673,
90.*
4,1,18,-.09673,-.06845,
-.107147,-.050613,
-.114308,-.031238,
-.117996,-.010914,
-.118098,.009741,
-.114613,.030101,
-.107644,.049546,
-.097406,.067485,
-.09673,.06845,
-.10175,.07347,
-.112962,.054685,
-.120742,.034239,
-.124853,.012752,
-.125171,-.009122,
-.121685,-.030719,
-.114502,-.051383,
-.10384,-.070486,
-.10175,-.07347,
-.09673,-.06845,
90.*
4,1,18,-.06845,.09673,
-.050613,.107147,
-.031238,.114308,
-.010914,.117996,
.009741,.118098,
.030101,.114613,
.049546,.107644,
.067485,.097406,
.06845,.09673,
.07347,.10175,
.054685,.112962,
.034239,.120742,
.012752,.124853,
-.009122,.125171,
-.030719,.121685,
-.051383,.114502,
-.070486,.10384,
-.07347,.10175,
-.06845,.09673,
90.*
%
%ADD41MACRO41*%
%AMMACRO11*
4,1,15,.06231,.03403,
.067273,.022693,
.070191,.010666,
.070977,-.001684,
.069606,-.013984,
.066121,-.025858,
.06231,-.03403,
.06745,-.03917,
.073227,-.026862,
.076779,-.013739,
.077998,-.000197,
.076848,.01335,
.073362,.026492,
.067647,.038828,
.06745,.03917,
.06231,.03403,
0.0*
4,1,15,.03403,-.06231,
.022693,-.067273,
.010666,-.070191,
-.001684,-.070977,
-.013984,-.069606,
-.025858,-.066121,
-.03403,-.06231,
-.03917,-.06745,
-.026862,-.073227,
-.013739,-.076779,
-.000197,-.077998,
.01335,-.076848,
.026492,-.073362,
.038828,-.067647,
.03917,-.06745,
.03403,-.06231,
0.0*
4,1,15,-.06231,-.03403,
-.067273,-.022693,
-.070191,-.010666,
-.070977,.001684,
-.069606,.013984,
-.066121,.025858,
-.06231,.03403,
-.06745,.03917,
-.073227,.026862,
-.076779,.013739,
-.077998,.000197,
-.076848,-.01335,
-.073362,-.026492,
-.067647,-.038828,
-.06745,-.03917,
-.06231,-.03403,
0.0*
4,1,15,-.03403,.06231,
-.022693,.067273,
-.010666,.070191,
.001684,.070977,
.013984,.069606,
.025858,.066121,
.03403,.06231,
.03917,.06745,
.026862,.073227,
.013739,.076779,
.000197,.077998,
-.01335,.076848,
-.026492,.073362,
-.038828,.067647,
-.03917,.06745,
-.03403,.06231,
0.0*
%
%ADD11MACRO11*%
%ADD19C,.099*%
%AMMACRO18*
4,1,18,.09673,.06845,
.107147,.050613,
.114308,.031238,
.117996,.010914,
.118098,-.009741,
.114613,-.030101,
.107644,-.049546,
.097406,-.067485,
.09673,-.06845,
.10175,-.07347,
.112962,-.054685,
.120742,-.034239,
.124853,-.012752,
.125171,.009122,
.121685,.030719,
.114502,.051383,
.10384,.070486,
.10175,.07347,
.09673,.06845,
0.0*
4,1,18,.06845,-.09673,
.050613,-.107147,
.031238,-.114308,
.010914,-.117996,
-.009741,-.118098,
-.030101,-.114613,
-.049546,-.107644,
-.067485,-.097406,
-.06845,-.09673,
-.07347,-.10175,
-.054685,-.112962,
-.034239,-.120742,
-.012752,-.124853,
.009122,-.125171,
.030719,-.121685,
.051383,-.114502,
.070486,-.10384,
.07347,-.10175,
.06845,-.09673,
0.0*
4,1,18,-.09673,-.06845,
-.107147,-.050613,
-.114308,-.031238,
-.117996,-.010914,
-.118098,.009741,
-.114613,.030101,
-.107644,.049546,
-.097406,.067485,
-.09673,.06845,
-.10175,.07347,
-.112962,.054685,
-.120742,.034239,
-.124853,.012752,
-.125171,-.009122,
-.121685,-.030719,
-.114502,-.051383,
-.10384,-.070486,
-.10175,-.07347,
-.09673,-.06845,
0.0*
4,1,18,-.06845,.09673,
-.050613,.107147,
-.031238,.114308,
-.010914,.117996,
.009741,.118098,
.030101,.114613,
.049546,.107644,
.067485,.097406,
.06845,.09673,
.07347,.10175,
.054685,.112962,
.034239,.120742,
.012752,.124853,
-.009122,.125171,
-.030719,.121685,
-.051383,.114502,
-.070486,.10384,
-.07347,.10175,
-.06845,.09673,
0.0*
%
%ADD18MACRO18*%
%AMMACRO59*
4,1,19,-.0075,-.03785,
-.011528,-.036185,
-.015205,-.033846,
-.01842,-.030904,
-.021075,-.027448,
-.02309,-.023584,
-.024404,-.019428,
-.024975,-.015108,
-.025,-.014,
-.025,-.0075,
-.018,-.0075,
-.018,-.014,
-.017727,-.017125,
-.016915,-.020155,
-.015589,-.022998,
-.01379,-.025567,
-.011572,-.027785,
-.009002,-.029584,
-.0075,-.03036,
-.0075,-.03785,
180.*
4,1,19,.0075,-.03785,
.0075,-.03036,
.010227,-.02881,
.012643,-.02681,
.014676,-.024421,
.016262,-.021715,
.017355,-.018774,
.017921,-.015689,
.018,-.014,
.018,-.0075,
.025,-.0075,
.025,-.014,
.02462,-.018342,
.023492,-.022551,
.02165,-.026501,
.019151,-.030071,
.016069,-.033153,
.012499,-.035652,
.008549,-.037494,
.0075,-.03785,
180.*
4,1,19,-.025,.0075,
-.025,.014,
-.02462,.018342,
-.023492,.022551,
-.02165,.026501,
-.019151,.030071,
-.016069,.033153,
-.012499,.035652,
-.008549,.037494,
-.0075,.03785,
-.0075,.03036,
-.010227,.02881,
-.012643,.02681,
-.014676,.024421,
-.016262,.021715,
-.017355,.018774,
-.017921,.015689,
-.018,.014,
-.018,.0075,
-.025,.0075,
180.*
4,1,19,.018,.0075,
.018,.014,
.017727,.017125,
.016915,.020155,
.015589,.022998,
.01379,.025567,
.011572,.027785,
.009002,.029584,
.0075,.03036,
.0075,.03785,
.011528,.036185,
.015205,.033846,
.01842,.030904,
.021075,.027448,
.02309,.023584,
.024404,.019428,
.024975,.015108,
.025,.014,
.025,.0075,
.018,.0075,
180.*
%
%ADD59MACRO59*%
%AMMACRO35*
4,1,16,.02584,.01524,
.028094,.010521,
.029494,.005483,
.029998,.000278,
.029591,-.004935,
.028284,-.009999,
.026118,-.014758,
.02584,-.01524,
.03092,-.02032,
.033979,-.014642,
.036005,-.008519,
.036938,-.002138,
.036748,.004309,
.035441,.010625,
.033058,.016618,
.03092,.02032,
.02584,.01524,
0.0*
4,1,16,.01524,-.02584,
.010521,-.028094,
.005483,-.029494,
.000278,-.029998,
-.004935,-.029591,
-.009999,-.028284,
-.014758,-.026118,
-.01524,-.02584,
-.02032,-.03092,
-.014642,-.033979,
-.008519,-.036005,
-.002138,-.036938,
.004309,-.036748,
.010625,-.035441,
.016618,-.033058,
.02032,-.03092,
.01524,-.02584,
0.0*
4,1,16,-.02584,-.01524,
-.028094,-.010521,
-.029494,-.005483,
-.029998,-.000278,
-.029591,.004935,
-.028284,.009999,
-.026118,.014758,
-.02584,.01524,
-.03092,.02032,
-.033979,.014642,
-.036005,.008519,
-.036938,.002138,
-.036748,-.004309,
-.035441,-.010625,
-.033058,-.016618,
-.03092,-.02032,
-.02584,-.01524,
0.0*
4,1,16,-.01524,.02584,
-.010521,.028094,
-.005483,.029494,
-.000278,.029998,
.004935,.029591,
.009999,.028284,
.014758,.026118,
.01524,.02584,
.02032,.03092,
.014642,.033979,
.008519,.036005,
.002138,.036938,
-.004309,.036748,
-.010625,.035441,
-.016618,.033058,
-.02032,.03092,
-.01524,.02584,
0.0*
%
%ADD35MACRO35*%
%AMMACRO47*
4,1,15,.02142,.01082,
.022973,.006936,
.023829,.002841,
.02396,-.00134,
.023364,-.00548,
.022057,-.009454,
.02142,-.01082,
.02657,-.01597,
.02894,-.011114,
.03043,-.005919,
.030995,-.000545,
.030619,.004845,
.029313,.010088,
.027115,.015025,
.02657,.01597,
.02142,.01082,
90.*
4,1,15,.01082,-.02142,
.006936,-.022973,
.002841,-.023829,
-.00134,-.02396,
-.00548,-.023364,
-.009454,-.022057,
-.01082,-.02142,
-.01597,-.02657,
-.011114,-.02894,
-.005919,-.03043,
-.000545,-.030995,
.004845,-.030619,
.010088,-.029313,
.015025,-.027115,
.01597,-.02657,
.01082,-.02142,
90.*
4,1,15,-.02142,-.01082,
-.022973,-.006936,
-.023829,-.002841,
-.02396,.00134,
-.023364,.00548,
-.022057,.009454,
-.02142,.01082,
-.02657,.01597,
-.02894,.011114,
-.03043,.005919,
-.030995,.000545,
-.030619,-.004845,
-.029313,-.010088,
-.027115,-.015025,
-.02657,-.01597,
-.02142,-.01082,
90.*
4,1,15,-.01082,.02142,
-.006936,.022973,
-.002841,.023829,
.00134,.02396,
.00548,.023364,
.009454,.022057,
.01082,.02142,
.01597,.02657,
.011114,.02894,
.005919,.03043,
.000545,.030995,
-.004845,.030619,
-.010088,.029313,
-.015025,.027115,
-.01597,.02657,
-.01082,.02142,
90.*
%
%ADD47MACRO47*%
%AMMACRO45*
4,1,18,.07103,.05689,
.07983,.043691,
.086204,.029165,
.089959,.013753,
.09098,-.002077,
.089237,-.017844,
.084783,-.033069,
.077753,-.047289,
.07103,-.05689,
.07601,-.06186,
.085597,-.047721,
.092583,-.032132,
.096757,-.015567,
.09799,.001471,
.096246,.018464,
.091577,.034897,
.084126,.050269,
.07601,.06186,
.07103,.05689,
90.*
4,1,18,.05689,-.07103,
.043691,-.07983,
.029165,-.086204,
.013753,-.089959,
-.002077,-.09098,
-.017844,-.089237,
-.033069,-.084783,
-.047289,-.077753,
-.05689,-.07103,
-.06186,-.07601,
-.047721,-.085597,
-.032132,-.092583,
-.015567,-.096757,
.001471,-.09799,
.018464,-.096246,
.034897,-.091577,
.050269,-.084126,
.06186,-.07601,
.05689,-.07103,
90.*
4,1,18,-.07103,-.05689,
-.07983,-.043691,
-.086204,-.029165,
-.089959,-.013753,
-.09098,.002077,
-.089237,.017844,
-.084783,.033069,
-.077753,.047289,
-.07103,.05689,
-.07601,.06186,
-.085597,.047721,
-.092583,.032132,
-.096757,.015567,
-.09799,-.001471,
-.096246,-.018464,
-.091577,-.034897,
-.084126,-.050269,
-.07601,-.06186,
-.07103,-.05689,
90.*
4,1,18,-.05689,.07103,
-.043691,.07983,
-.029165,.086204,
-.013753,.089959,
.002077,.09098,
.017844,.089237,
.033069,.084783,
.047289,.077753,
.05689,.07103,
.06186,.07601,
.047721,.085597,
.032132,.092583,
.015567,.096757,
-.001471,.09799,
-.018464,.096246,
-.034897,.091577,
-.050269,.084126,
-.06186,.07601,
-.05689,.07103,
90.*
%
%ADD45MACRO45*%
%AMMACRO60*
4,1,19,-.0075,-.04535,
-.011528,-.043685,
-.015205,-.041346,
-.01842,-.038404,
-.021075,-.034948,
-.02309,-.031084,
-.024404,-.026928,
-.024975,-.022608,
-.025,-.0215,
-.025,-.0075,
-.018,-.0075,
-.018,-.0215,
-.017727,-.024625,
-.016915,-.027655,
-.015589,-.030498,
-.01379,-.033067,
-.011572,-.035285,
-.009002,-.037084,
-.0075,-.03786,
-.0075,-.04535,
180.*
4,1,19,.0075,-.04535,
.0075,-.03786,
.010227,-.03631,
.012643,-.03431,
.014676,-.031921,
.016262,-.029215,
.017355,-.026274,
.017921,-.023189,
.018,-.0215,
.018,-.0075,
.025,-.0075,
.025,-.0215,
.02462,-.025842,
.023492,-.030051,
.02165,-.034001,
.019151,-.037571,
.016069,-.040653,
.012499,-.043152,
.008549,-.044994,
.0075,-.04535,
180.*
4,1,19,-.025,.0075,
-.025,.0215,
-.02462,.025842,
-.023492,.030051,
-.02165,.034001,
-.019151,.037571,
-.016069,.040653,
-.012499,.043152,
-.008549,.044994,
-.0075,.04535,
-.0075,.03786,
-.010227,.03631,
-.012643,.03431,
-.014676,.031921,
-.016262,.029215,
-.017355,.026274,
-.017921,.023189,
-.018,.0215,
-.018,.0075,
-.025,.0075,
180.*
4,1,19,.018,.0075,
.018,.0215,
.017727,.024625,
.016915,.027655,
.015589,.030498,
.01379,.033067,
.011572,.035285,
.009002,.037084,
.0075,.03786,
.0075,.04535,
.011528,.043685,
.015205,.041346,
.01842,.038404,
.021075,.034948,
.02309,.031084,
.024404,.026928,
.024975,.022608,
.025,.0215,
.025,.0075,
.018,.0075,
180.*
%
%ADD60MACRO60*%
%AMMACRO53*
4,1,15,.02475,.01414,
.026829,.009627,
.028094,.004822,
.028504,-.000129,
.028049,-.005077,
.026741,-.009871,
.02475,-.01414,
.02984,-.01923,
.032726,-.013756,
.034617,-.007864,
.035457,-.001734,
.03522,.00445,
.033912,.010498,
.031574,.016227,
.02984,.01923,
.02475,.01414,
0.0*
4,1,15,.01414,-.02475,
.009627,-.026829,
.004822,-.028094,
-.000129,-.028504,
-.005077,-.028049,
-.009871,-.026741,
-.01414,-.02475,
-.01923,-.02984,
-.013756,-.032726,
-.007864,-.034617,
-.001734,-.035457,
.00445,-.03522,
.010498,-.033912,
.016227,-.031574,
.01923,-.02984,
.01414,-.02475,
0.0*
4,1,15,-.02475,-.01414,
-.026829,-.009627,
-.028094,-.004822,
-.028504,.000129,
-.028049,.005077,
-.026741,.009871,
-.02475,.01414,
-.02984,.01923,
-.032726,.013756,
-.034617,.007864,
-.035457,.001734,
-.03522,-.00445,
-.033912,-.010498,
-.031574,-.016227,
-.02984,-.01923,
-.02475,-.01414,
0.0*
4,1,15,-.01414,.02475,
-.009627,.026829,
-.004822,.028094,
.000129,.028504,
.005077,.028049,
.009871,.026741,
.01414,.02475,
.01923,.02984,
.013756,.032726,
.007864,.034617,
.001734,.035457,
-.00445,.03522,
-.010498,.033912,
-.016227,.031574,
-.01923,.02984,
-.01414,.02475,
0.0*
%
%ADD53MACRO53*%
%AMMACRO57*
4,1,15,.03682,.01914,
.039584,.012455,
.041146,.005393,
.041457,-.001834,
.040509,-.009005,
.03833,-.015903,
.03682,-.01914,
.04197,-.0243,
.045552,-.016643,
.04775,-.00848,
.048497,-.000059,
.047771,.008363,
.045593,.016531,
.042029,.024197,
.04197,.0243,
.03682,.01914,
90.*
4,1,15,.01914,-.03682,
.012455,-.039584,
.005393,-.041146,
-.001834,-.041457,
-.009005,-.040509,
-.015903,-.03833,
-.01914,-.03682,
-.0243,-.04197,
-.016643,-.045552,
-.00848,-.04775,
-.000059,-.048497,
.008363,-.047771,
.016531,-.045593,
.024197,-.042029,
.0243,-.04197,
.01914,-.03682,
90.*
4,1,15,-.03682,-.01914,
-.039584,-.012455,
-.041146,-.005393,
-.041457,.001834,
-.040509,.009005,
-.03833,.015903,
-.03682,.01914,
-.04197,.0243,
-.045552,.016643,
-.04775,.00848,
-.048497,.000059,
-.047771,-.008363,
-.045593,-.016531,
-.042029,-.024197,
-.04197,-.0243,
-.03682,-.01914,
90.*
4,1,15,-.01914,.03682,
-.012455,.039584,
-.005393,.041146,
.001834,.041457,
.009005,.040509,
.015903,.03833,
.01914,.03682,
.0243,.04197,
.016643,.045552,
.00848,.04775,
.000059,.048497,
-.008363,.047771,
-.016531,.045593,
-.024197,.042029,
-.0243,.04197,
-.01914,.03682,
90.*
%
%ADD57MACRO57*%
%AMMACRO58*
4,1,15,-.03682,.01914,
-.039584,.012455,
-.041146,.005393,
-.041457,-.001834,
-.040509,-.009005,
-.03833,-.015903,
-.03682,-.01914,
-.04197,-.0243,
-.045552,-.016643,
-.04775,-.00848,
-.048497,-.000059,
-.047771,.008363,
-.045593,.016531,
-.042029,.024197,
-.04197,.0243,
-.03682,.01914,
90.*
4,1,15,-.01914,-.03682,
-.012455,-.039584,
-.005393,-.041146,
.001834,-.041457,
.009005,-.040509,
.015903,-.03833,
.01914,-.03682,
.0243,-.04197,
.016643,-.045552,
.00848,-.04775,
.000059,-.048497,
-.008363,-.047771,
-.016531,-.045593,
-.024197,-.042029,
-.0243,-.04197,
-.01914,-.03682,
90.*
4,1,15,.03682,-.01914,
.039584,-.012455,
.041146,-.005393,
.041457,.001834,
.040509,.009005,
.03833,.015903,
.03682,.01914,
.04197,.0243,
.045552,.016643,
.04775,.00848,
.048497,.000059,
.047771,-.008363,
.045593,-.016531,
.042029,-.024197,
.04197,-.0243,
.03682,-.01914,
90.*
4,1,15,.01914,.03682,
.012455,.039584,
.005393,.041146,
-.001834,.041457,
-.009005,.040509,
-.015903,.03833,
-.01914,.03682,
-.0243,.04197,
-.016643,.045552,
-.00848,.04775,
-.000059,.048497,
.008363,.047771,
.016531,.045593,
.024197,.042029,
.0243,.04197,
.01914,.03682,
90.*
%
%ADD58MACRO58*%
%ADD61C,.142*%
%ADD13C,.125*%
%ADD29C,.208*%
%ADD44C,.164*%
%ADD17C,.155*%
%ADD37C,.256*%
%AMMACRO31*
4,1,36,0.0,.0085,
.001476,.008371,
.002907,.007987,
.00425,.007361,
.005464,.006511,
.006511,.005464,
.007361,.00425,
.007987,.002907,
.008371,.001476,
.0085,0.0,
.008371,-.001476,
.007987,-.002907,
.007361,-.00425,
.006511,-.005464,
.005464,-.006511,
.00425,-.007361,
.002907,-.007987,
.001476,-.008371,
0.0,-.0085,
-.001476,-.008371,
-.002907,-.007987,
-.00425,-.007361,
-.005464,-.006511,
-.006511,-.005464,
-.007361,-.00425,
-.007987,-.002907,
-.008371,-.001476,
-.0085,0.0,
-.008371,.001476,
-.007987,.002907,
-.007361,.00425,
-.006511,.005464,
-.005464,.006511,
-.00425,.007361,
-.002907,.007987,
-.001476,.008371,
0.0,.0085,
180.*
%
%ADD31MACRO31*%
%AMMACRO46*
4,1,36,0.0,.0185,
-.003212,.018219,
-.006327,.017384,
-.00925,.016021,
-.011892,.014172,
-.014172,.011892,
-.016021,.00925,
-.017384,.006327,
-.018219,.003212,
-.0185,0.0,
-.018219,-.003212,
-.017384,-.006327,
-.016021,-.00925,
-.014172,-.011892,
-.011892,-.014172,
-.00925,-.016021,
-.006327,-.017384,
-.003212,-.018219,
0.0,-.0185,
.003212,-.018219,
.006327,-.017384,
.00925,-.016021,
.011892,-.014172,
.014172,-.011892,
.016021,-.00925,
.017384,-.006327,
.018219,-.003212,
.0185,0.0,
.018219,.003212,
.017384,.006327,
.016021,.00925,
.014172,.011892,
.011892,.014172,
.00925,.016021,
.006327,.017384,
.003212,.018219,
0.0,.0185,
270.*
%
%ADD46MACRO46*%
%AMMACRO20*
4,1,20,-.0075,-.05555,
-.0075,-.06273,
-.013677,-.060878,
-.019439,-.057981,
-.024611,-.054127,
-.029034,-.049434,
-.032576,-.044045,
-.035127,-.038122,
-.036612,-.031846,
-.037,-.0265,
-.037,-.0075,
-.03,-.0075,
-.03,-.0265,
-.029544,-.03171,
-.028191,-.036762,
-.02598,-.041502,
-.022981,-.045786,
-.019282,-.049484,
-.014998,-.052484,
-.010258,-.054694,
-.0075,-.05555,
90.*
4,1,20,.0075,-.06273,
.0075,-.05555,
.01243,-.053806,
.016983,-.051232,
.02102,-.047906,
.024418,-.043931,
.027073,-.039425,
.028906,-.034527,
.029861,-.029385,
.03,-.0265,
.03,-.0075,
.037,-.0075,
.037,-.0265,
.036438,-.032925,
.034769,-.039154,
.032043,-.044999,
.028344,-.050282,
.023784,-.054842,
.018501,-.058541,
.012656,-.061266,
.0075,-.06273,
90.*
4,1,20,-.0075,.06273,
-.0075,.05555,
-.01243,.053806,
-.016983,.051232,
-.02102,.047906,
-.024418,.043931,
-.027073,.039425,
-.028906,.034527,
-.029861,.029385,
-.03,.0265,
-.03,.0075,
-.037,.0075,
-.037,.0265,
-.036438,.032925,
-.034769,.039154,
-.032043,.044999,
-.028344,.050282,
-.023784,.054842,
-.018501,.058541,
-.012656,.061266,
-.0075,.06273,
90.*
4,1,20,.0075,.05555,
.0075,.06273,
.013677,.060878,
.019439,.057981,
.024611,.054127,
.029034,.049434,
.032576,.044045,
.035127,.038122,
.036612,.031846,
.037,.0265,
.037,.0075,
.03,.0075,
.03,.0265,
.029544,.03171,
.028191,.036762,
.02598,.041502,
.022981,.045786,
.019282,.049484,
.014998,.052484,
.010258,.054694,
.0075,.05555,
90.*
%
%ADD20MACRO20*%
%AMMACRO16*
4,1,36,.0025,0.0,
.002462,.000434,
.002349,.000855,
.002165,.00125,
.001915,.001607,
.001607,.001915,
.00125,.002165,
.000855,.002349,
.000434,.002462,
0.0,.0025,
-.000434,.002462,
-.000855,.002349,
-.00125,.002165,
-.001607,.001915,
-.001915,.001607,
-.002165,.00125,
-.002349,.000855,
-.002462,.000434,
-.0025,0.0,
-.002462,-.000434,
-.002349,-.000855,
-.002165,-.00125,
-.001915,-.001607,
-.001607,-.001915,
-.00125,-.002165,
-.000855,-.002349,
-.000434,-.002462,
0.0,-.0025,
.000434,-.002462,
.000855,-.002349,
.00125,-.002165,
.001607,-.001915,
.001915,-.001607,
.002165,-.00125,
.002349,-.000855,
.002462,-.000434,
.0025,0.0,
90.*
%
%ADD16MACRO16*%
%AMMACRO33*
4,1,36,.003,0.0,
.002954,.000521,
.002819,.001026,
.002598,.0015,
.002298,.001928,
.001928,.002298,
.0015,.002598,
.001026,.002819,
.000521,.002954,
0.0,.003,
-.000521,.002954,
-.001026,.002819,
-.0015,.002598,
-.001928,.002298,
-.002298,.001928,
-.002598,.0015,
-.002819,.001026,
-.002954,.000521,
-.003,0.0,
-.002954,-.000521,
-.002819,-.001026,
-.002598,-.0015,
-.002298,-.001928,
-.001928,-.002298,
-.0015,-.002598,
-.001026,-.002819,
-.000521,-.002954,
0.0,-.003,
.000521,-.002954,
.001026,-.002819,
.0015,-.002598,
.001928,-.002298,
.002298,-.001928,
.002598,-.0015,
.002819,-.001026,
.002954,-.000521,
.003,0.0,
90.*
%
%ADD33MACRO33*%
%AMMACRO12*
4,1,36,.0025,0.0,
.002462,.000434,
.002349,.000855,
.002165,.00125,
.001915,.001607,
.001607,.001915,
.00125,.002165,
.000855,.002349,
.000434,.002462,
0.0,.0025,
-.000434,.002462,
-.000855,.002349,
-.00125,.002165,
-.001607,.001915,
-.001915,.001607,
-.002165,.00125,
-.002349,.000855,
-.002462,.000434,
-.0025,0.0,
-.002462,-.000434,
-.002349,-.000855,
-.002165,-.00125,
-.001915,-.001607,
-.001607,-.001915,
-.00125,-.002165,
-.000855,-.002349,
-.000434,-.002462,
0.0,-.0025,
.000434,-.002462,
.000855,-.002349,
.00125,-.002165,
.001607,-.001915,
.001915,-.001607,
.002165,-.00125,
.002349,-.000855,
.002462,-.000434,
.0025,0.0,
0.0*
%
%ADD12MACRO12*%
%AMMACRO49*
4,1,36,-.0025,0.0,
-.002462,.000434,
-.002349,.000855,
-.002165,.00125,
-.001915,.001607,
-.001607,.001915,
-.00125,.002165,
-.000855,.002349,
-.000434,.002462,
0.0,.0025,
.000434,.002462,
.000855,.002349,
.00125,.002165,
.001607,.001915,
.001915,.001607,
.002165,.00125,
.002349,.000855,
.002462,.000434,
.0025,0.0,
.002462,-.000434,
.002349,-.000855,
.002165,-.00125,
.001915,-.001607,
.001607,-.001915,
.00125,-.002165,
.000855,-.002349,
.000434,-.002462,
0.0,-.0025,
-.000434,-.002462,
-.000855,-.002349,
-.00125,-.002165,
-.001607,-.001915,
-.001915,-.001607,
-.002165,-.00125,
-.002349,-.000855,
-.002462,-.000434,
-.0025,0.0,
0.0*
%
%ADD49MACRO49*%
%AMMACRO26*
4,1,36,.003,0.0,
.002954,.000521,
.002819,.001026,
.002598,.0015,
.002298,.001928,
.001928,.002298,
.0015,.002598,
.001026,.002819,
.000521,.002954,
0.0,.003,
-.000521,.002954,
-.001026,.002819,
-.0015,.002598,
-.001928,.002298,
-.002298,.001928,
-.002598,.0015,
-.002819,.001026,
-.002954,.000521,
-.003,0.0,
-.002954,-.000521,
-.002819,-.001026,
-.002598,-.0015,
-.002298,-.001928,
-.001928,-.002298,
-.0015,-.002598,
-.001026,-.002819,
-.000521,-.002954,
0.0,-.003,
.000521,-.002954,
.001026,-.002819,
.0015,-.002598,
.001928,-.002298,
.002298,-.001928,
.002598,-.0015,
.002819,-.001026,
.002954,-.000521,
.003,0.0,
0.0*
%
%ADD26MACRO26*%
%AMMACRO23*
4,1,36,-.003,0.0,
-.002954,.000521,
-.002819,.001026,
-.002598,.0015,
-.002298,.001928,
-.001928,.002298,
-.0015,.002598,
-.001026,.002819,
-.000521,.002954,
0.0,.003,
.000521,.002954,
.001026,.002819,
.0015,.002598,
.001928,.002298,
.002298,.001928,
.002598,.0015,
.002819,.001026,
.002954,.000521,
.003,0.0,
.002954,-.000521,
.002819,-.001026,
.002598,-.0015,
.002298,-.001928,
.001928,-.002298,
.0015,-.002598,
.001026,-.002819,
.000521,-.002954,
0.0,-.003,
-.000521,-.002954,
-.001026,-.002819,
-.0015,-.002598,
-.001928,-.002298,
-.002298,-.001928,
-.002598,-.0015,
-.002819,-.001026,
-.002954,-.000521,
-.003,0.0,
0.0*
%
%ADD23MACRO23*%
%AMMACRO38*
4,1,16,.02584,.01524,
.028094,.010521,
.029494,.005483,
.029998,.000278,
.029591,-.004935,
.028284,-.009999,
.026118,-.014758,
.02584,-.01524,
.03092,-.02032,
.033979,-.014642,
.036005,-.008519,
.036938,-.002138,
.036748,.004309,
.035441,.010625,
.033058,.016618,
.03092,.02032,
.02584,.01524,
180.*
4,1,16,.01524,-.02584,
.010521,-.028094,
.005483,-.029494,
.000278,-.029998,
-.004935,-.029591,
-.009999,-.028284,
-.014758,-.026118,
-.01524,-.02584,
-.02032,-.03092,
-.014642,-.033979,
-.008519,-.036005,
-.002138,-.036938,
.004309,-.036748,
.010625,-.035441,
.016618,-.033058,
.02032,-.03092,
.01524,-.02584,
180.*
4,1,16,-.02584,-.01524,
-.028094,-.010521,
-.029494,-.005483,
-.029998,-.000278,
-.029591,.004935,
-.028284,.009999,
-.026118,.014758,
-.02584,.01524,
-.03092,.02032,
-.033979,.014642,
-.036005,.008519,
-.036938,.002138,
-.036748,-.004309,
-.035441,-.010625,
-.033058,-.016618,
-.03092,-.02032,
-.02584,-.01524,
180.*
4,1,16,-.01524,.02584,
-.010521,.028094,
-.005483,.029494,
-.000278,.029998,
.004935,.029591,
.009999,.028284,
.014758,.026118,
.01524,.02584,
.02032,.03092,
.014642,.033979,
.008519,.036005,
.002138,.036938,
-.004309,.036748,
-.010625,.035441,
-.016618,.033058,
-.02032,.03092,
-.01524,.02584,
180.*
%
%ADD38MACRO38*%
%AMMACRO54*
4,1,15,.03682,.01914,
.039584,.012455,
.041146,.005393,
.041457,-.001834,
.040509,-.009005,
.03833,-.015903,
.03682,-.01914,
.04197,-.0243,
.045552,-.016643,
.04775,-.00848,
.048497,-.000059,
.047771,.008363,
.045593,.016531,
.042029,.024197,
.04197,.0243,
.03682,.01914,
270.*
4,1,15,.01914,-.03682,
.012455,-.039584,
.005393,-.041146,
-.001834,-.041457,
-.009005,-.040509,
-.015903,-.03833,
-.01914,-.03682,
-.0243,-.04197,
-.016643,-.045552,
-.00848,-.04775,
-.000059,-.048497,
.008363,-.047771,
.016531,-.045593,
.024197,-.042029,
.0243,-.04197,
.01914,-.03682,
270.*
4,1,15,-.03682,-.01914,
-.039584,-.012455,
-.041146,-.005393,
-.041457,.001834,
-.040509,.009005,
-.03833,.015903,
-.03682,.01914,
-.04197,.0243,
-.045552,.016643,
-.04775,.00848,
-.048497,.000059,
-.047771,-.008363,
-.045593,-.016531,
-.042029,-.024197,
-.04197,-.0243,
-.03682,-.01914,
270.*
4,1,15,-.01914,.03682,
-.012455,.039584,
-.005393,.041146,
.001834,.041457,
.009005,.040509,
.015903,.03833,
.01914,.03682,
.0243,.04197,
.016643,.045552,
.00848,.04775,
.000059,.048497,
-.008363,.047771,
-.016531,.045593,
-.024197,.042029,
-.0243,.04197,
-.01914,.03682,
270.*
%
%ADD54MACRO54*%
%AMMACRO55*
4,1,15,-.03682,.01914,
-.039584,.012455,
-.041146,.005393,
-.041457,-.001834,
-.040509,-.009005,
-.03833,-.015903,
-.03682,-.01914,
-.04197,-.0243,
-.045552,-.016643,
-.04775,-.00848,
-.048497,-.000059,
-.047771,.008363,
-.045593,.016531,
-.042029,.024197,
-.04197,.0243,
-.03682,.01914,
270.*
4,1,15,-.01914,-.03682,
-.012455,-.039584,
-.005393,-.041146,
.001834,-.041457,
.009005,-.040509,
.015903,-.03833,
.01914,-.03682,
.0243,-.04197,
.016643,-.045552,
.00848,-.04775,
.000059,-.048497,
-.008363,-.047771,
-.016531,-.045593,
-.024197,-.042029,
-.0243,-.04197,
-.01914,-.03682,
270.*
4,1,15,.03682,-.01914,
.039584,-.012455,
.041146,-.005393,
.041457,.001834,
.040509,.009005,
.03833,.015903,
.03682,.01914,
.04197,.0243,
.045552,.016643,
.04775,.00848,
.048497,.000059,
.047771,-.008363,
.045593,-.016531,
.042029,-.024197,
.04197,-.0243,
.03682,-.01914,
270.*
4,1,15,.01914,.03682,
.012455,.039584,
.005393,.041146,
-.001834,.041457,
-.009005,.040509,
-.015903,.03833,
-.01914,.03682,
-.0243,.04197,
-.016643,.045552,
-.00848,.04775,
-.000059,.048497,
.008363,.047771,
.016531,.045593,
.024197,.042029,
.0243,.04197,
.01914,.03682,
270.*
%
%ADD55MACRO55*%
%ADD62C,.006*%
%ADD74C,.03006*%
%ADD80C,.02404*%
%ADD78C,.07005*%
%ADD71C,.08404*%
%ADD64C,.07306*%
%ADD77C,.09208*%
%ADD72C,.07606*%
%ADD70C,.08408*%
%ADD76C,.07608*%
%ADD69C,.08409*%
%ADD68O,.1621X.2251*%
%ADD67O,.03604X.07004*%
%ADD65O,.03006X.06406*%
%ADD79C,.16206*%
%ADD66O,.03606X.07006*%
%ADD75C,.17406*%
%ADD63C,.16506*%
%ADD73C,.21786*%
G75*
%LPD*%
G75*
G36*
G01X-1490433Y-1677216D02*
X4496476D01*
Y3837819D01*
X-1490433D01*
Y-1677216D01*
G37*
%LPC*%
G75*
G36*
G01X630370Y-100983D02*
G02X624496Y-95109I0J5874D01*
G01Y-32983D01*
G03X614622Y-23109I-9874J0D01*
G01X68874D01*
G03X59000Y-32983I0J-9874D01*
G01Y-95109D01*
G02X53126Y-100983I-5874J0D01*
G01X7874D01*
G02X2000Y-95109I0J5874D01*
G01Y-15748D01*
G02X7874Y-9874I5874J0D01*
G01X31358D01*
G03X41232Y0I0J9874D01*
G01Y34843D01*
G02X47106Y40717I5874J0D01*
G01X54980D01*
G02X60854Y34843I0J-5874D01*
G01Y0D01*
G03X70728Y-9874I9874J0D01*
G01X133720D01*
G03X143594Y0I0J9874D01*
G01Y34843D01*
G02X149468Y40717I5874J0D01*
G01X157343D01*
G02X163217Y34843I0J-5874D01*
G01Y0D01*
G03X173091Y-9874I9874J0D01*
G01X236083D01*
G03X245957Y0I0J9874D01*
G01Y34843D01*
G02X251831Y40717I5874J0D01*
G01X259705D01*
G02X265579Y34843I0J-5874D01*
G01Y0D01*
G03X275453Y-9874I9874J0D01*
G01X338445D01*
G03X348319Y0I0J9874D01*
G01Y34843D01*
G02X354193Y40717I5874J0D01*
G01X362067D01*
G02X367941Y34843I0J-5874D01*
G01Y0D01*
G03X377815Y-9874I9874J0D01*
G01X488445D01*
G03X498319Y0I0J9874D01*
G01Y34843D01*
G02X504193Y40717I5874J0D01*
G01X512067D01*
G02X517941Y34843I0J-5874D01*
G01Y0D01*
G03X527815Y-9874I9874J0D01*
G01X590807D01*
G03X600681Y0I0J9874D01*
G01Y34843D01*
G02X606555Y40717I5874J0D01*
G01X614429D01*
G02X620303Y34843I0J-5874D01*
G01Y0D01*
G03X630177Y-9874I9874J0D01*
G01X693169D01*
G03X703043Y0I0J9874D01*
G01Y34843D01*
G02X708917Y40717I5874J0D01*
G01X716791D01*
G02X722665Y34843I0J-5874D01*
G01Y0D01*
G03X732539Y-9874I9874J0D01*
G01X795531D01*
G03X805405Y0I0J9874D01*
G01Y34843D01*
G02X811279Y40717I5874J0D01*
G01X819154D01*
G02X825028Y34843I0J-5874D01*
G01Y0D01*
G03X834902Y-9874I9874J0D01*
G01X945531D01*
G03X955405Y0I0J9874D01*
G01Y34843D01*
G02X961279Y40717I5874J0D01*
G01X969154D01*
G02X975028Y34843I0J-5874D01*
G01Y0D01*
G03X984902Y-9874I9874J0D01*
G01X1047894D01*
G03X1057768Y0I0J9874D01*
G01Y34843D01*
G02X1063642Y40717I5874J0D01*
G01X1071516D01*
G02X1077390Y34843I0J-5874D01*
G01Y0D01*
G03X1087264Y-9874I9874J0D01*
G01X1150256D01*
G03X1160130Y0I0J9874D01*
G01Y34843D01*
G02X1166004Y40717I5874J0D01*
G01X1173878D01*
G02X1179752Y34843I0J-5874D01*
G01Y0D01*
G03X1189626Y-9874I9874J0D01*
G01X1252618D01*
G03X1262492Y0I0J9874D01*
G01Y34843D01*
G02X1268366Y40717I5874J0D01*
G01X1276240D01*
G02X1282114Y34843I0J-5874D01*
G01Y0D01*
G03X1291988Y-9874I9874J0D01*
G01X1402618D01*
G03X1412492Y0I0J9874D01*
G01Y34843D01*
G02X1418366Y40717I5874J0D01*
G01X1426240D01*
G02X1432114Y34843I0J-5874D01*
G01Y0D01*
G03X1441988Y-9874I9874J0D01*
G01X1504980D01*
G03X1514854Y0I0J9874D01*
G01Y34843D01*
G02X1520728Y40717I5874J0D01*
G01X1528602D01*
G02X1534476Y34843I0J-5874D01*
G01Y0D01*
G03X1544350Y-9874I9874J0D01*
G01X1607343D01*
G03X1617217Y0I0J9874D01*
G01Y34843D01*
G02X1623091Y40717I5874J0D01*
G01X1630965D01*
G02X1636839Y34843I0J-5874D01*
G01Y0D01*
G03X1646713Y-9874I9874J0D01*
G01X1709705D01*
G03X1719579Y0I0J9874D01*
G01Y34843D01*
G02X1725453Y40717I5874J0D01*
G01X1733327D01*
G02X1739201Y34843I0J-5874D01*
G01Y0D01*
G03X1749075Y-9874I9874J0D01*
G01X1833071D01*
G02X1838945Y-15748I0J-5874D01*
G01Y-95109D01*
G02X1833071Y-100983I-5874J0D01*
G01X630370D01*
G37*
G36*
G01X1833071Y1645992D02*
G02X1838945Y1640118I0J-5874D01*
G01Y970425D01*
G02X1837225Y966273I-5874J1D01*
G01X1826876Y955925D01*
G03X1823984Y948943I6982J-6982D01*
G01Y344836D01*
G03X1826876Y337855I9873J0D01*
G01X1837225Y327506D01*
G02X1838945Y323354I-4153J-4153D01*
G01Y7874D01*
G02X1833071Y2000I-5874J0D01*
G01X1756949D01*
G02X1751075Y7874I0J5874D01*
G01Y46654D01*
G03X1745138Y52591I-5937J0D01*
G01X1713642D01*
G03X1707705Y46654I0J-5937D01*
G01Y7874D01*
G02X1701831Y2000I-5874J0D01*
G01X1654587D01*
G02X1648713Y7874I0J5874D01*
G01Y46654D01*
G03X1642776Y52591I-5937J0D01*
G01X1611280D01*
G03X1605343Y46654I0J-5937D01*
G01Y7874D01*
G02X1599469Y2000I-5874J0D01*
G01X1552224D01*
G02X1546350Y7874I0J5874D01*
G01Y46654D01*
G03X1540413Y52591I-5937J0D01*
G01X1508917D01*
G03X1502980Y46654I0J-5937D01*
G01Y7874D01*
G02X1497106Y2000I-5874J0D01*
G01X1449862D01*
G02X1443988Y7874I0J5874D01*
G01Y46654D01*
G03X1438051Y52591I-5937J0D01*
G01X1406555D01*
G03X1400618Y46654I0J-5937D01*
G01Y7874D01*
G02X1394744Y2000I-5874J0D01*
G01X1299862D01*
G02X1293988Y7874I0J5874D01*
G01Y46654D01*
G03X1288051Y52591I-5937J0D01*
G01X1256555D01*
G03X1250618Y46654I0J-5937D01*
G01Y7874D01*
G02X1244744Y2000I-5874J0D01*
G01X1197500D01*
G02X1191626Y7874I0J5874D01*
G01Y46654D01*
G03X1185689Y52591I-5937J0D01*
G01X1154193D01*
G03X1148256Y46654I0J-5937D01*
G01Y7874D01*
G02X1142382Y2000I-5874J0D01*
G01X1095138D01*
G02X1089264Y7874I0J5874D01*
G01Y46654D01*
G03X1083327Y52591I-5937J0D01*
G01X1051831D01*
G03X1045894Y46654I0J-5937D01*
G01Y7874D01*
G02X1040020Y2000I-5874J0D01*
G01X992776D01*
G02X986902Y7874I0J5874D01*
G01Y46654D01*
G03X980965Y52591I-5937J0D01*
G01X949468D01*
G03X943531Y46654I0J-5937D01*
G01Y7874D01*
G02X937657Y2000I-5874J0D01*
G01X842776D01*
G02X836902Y7874I0J5874D01*
G01Y46654D01*
G03X830965Y52591I-5937J0D01*
G01X799468D01*
G03X793531Y46654I0J-5937D01*
G01Y7874D01*
G02X787657Y2000I-5874J0D01*
G01X740413D01*
G02X734539Y7874I0J5874D01*
G01Y46654D01*
G03X728602Y52591I-5937J0D01*
G01X697106D01*
G03X691169Y46654I0J-5937D01*
G01Y7874D01*
G02X685295Y2000I-5874J0D01*
G01X638051D01*
G02X632177Y7874I0J5874D01*
G01Y46654D01*
G03X626240Y52591I-5937J0D01*
G01X594744D01*
G03X588807Y46654I0J-5937D01*
G01Y7874D01*
G02X582933Y2000I-5874J0D01*
G01X535689D01*
G02X529815Y7874I0J5874D01*
G01Y46654D01*
G03X523878Y52591I-5937J0D01*
G01X492382D01*
G03X486445Y46654I0J-5937D01*
G01Y7874D01*
G02X480571Y2000I-5874J0D01*
G01X385689D01*
G02X379815Y7874I0J5874D01*
G01Y46654D01*
G03X373878Y52591I-5937J0D01*
G01X342382D01*
G03X336445Y46654I0J-5937D01*
G01Y7874D01*
G02X330571Y2000I-5874J0D01*
G01X283327D01*
G02X277453Y7874I0J5874D01*
G01Y46654D01*
G03X271516Y52591I-5937J0D01*
G01X240020D01*
G03X234083Y46654I0J-5937D01*
G01Y7874D01*
G02X228209Y2000I-5874J0D01*
G01X180965D01*
G02X175091Y7874I0J5874D01*
G01Y46654D01*
G03X169154Y52591I-5937J0D01*
G01X137657D01*
G03X131720Y46654I0J-5937D01*
G01Y7874D01*
G02X125846Y2000I-5874J0D01*
G01X78602D01*
G02X72728Y7874I0J5874D01*
G01Y46654D01*
G03X66791Y52591I-5937J0D01*
G01X35295D01*
G03X29358Y46654I0J-5937D01*
G01Y7874D01*
G02X23484Y2000I-5874J0D01*
G01X7874D01*
G02X2000Y7874I0J5874D01*
G01Y323354D01*
G02X3720Y327506I5873J-1D01*
G01X14068Y337855D01*
G03X16961Y344836I-6980J6983D01*
G01Y948943D01*
G03X14068Y955925I-9875J-1D01*
G01X3720Y966273D01*
G02X2000Y970425I4154J4153D01*
G01Y1640118D01*
G02X7874Y1645992I5874J0D01*
G01X789298D01*
G02X793649Y1644063I-1J-5873D01*
G03X800966Y1640819I7317J6631D01*
G01X1070058D01*
G03X1077374Y1644063I-1J9873D01*
G02X1081725Y1645992I4352J-3945D01*
G01X1833071D01*
G37*
G36*
G01Y1818880D02*
G02X1838945Y1813006I0J-5874D01*
G01Y1663740D01*
G02X1833071Y1657866I-5874J0D01*
G01X1763543D01*
G02X1757669Y1663740I0J5874D01*
G01Y1689331D01*
G03X1747795Y1699205I-9874J0D01*
G01X1461575D01*
G03X1451701Y1689331I0J-9874D01*
G01Y1663740D01*
G02X1445827Y1657866I-5874J0D01*
G01X1417087D01*
G02X1411213Y1663740I0J5874D01*
G01Y1689331D01*
G03X1401339Y1699205I-9874J0D01*
G01X1115118D01*
G03X1105244Y1689331I0J-9874D01*
G01Y1663740D01*
G02X1099370Y1657866I-5874J0D01*
G01X1090079D01*
G02X1084205Y1663740I0J5874D01*
G01Y1695110D01*
G03X1074331Y1704984I-9874J0D01*
G01X796693D01*
G03X786819Y1695110I0J-9874D01*
G01Y1663740D01*
G02X780945Y1657866I-5874J0D01*
G01X741575D01*
G02X735701Y1663740I0J5874D01*
G01Y1689331D01*
G03X725827Y1699205I-9874J0D01*
G01X439607D01*
G03X429733Y1689331I0J-9874D01*
G01Y1663740D01*
G02X423859Y1657866I-5874J0D01*
G01X395118D01*
G02X389244Y1663740I0J5874D01*
G01Y1689331D01*
G03X379370Y1699205I-9874J0D01*
G01X93150D01*
G03X83276Y1689331I0J-9874D01*
G01Y1663740D01*
G02X77402Y1657866I-5874J0D01*
G01X7874D01*
G02X2000Y1663740I0J5874D01*
G01Y1813006D01*
G02X7874Y1818880I5874J0D01*
G01X1833071D01*
G37*
%LPD*%
G75*
G36*
G01X607977Y1552080D02*
X555513D01*
G02X555210Y1552383I0J303D01*
G01Y1643194D01*
G02X555513Y1643498I303J1D01*
G01X608266D01*
G02X608570Y1643194I0J-304D01*
G01Y1552672D01*
X607977Y1552080D01*
G37*
G36*
G01X208954Y1643834D02*
G02X209256Y1644136I302J0D01*
G01X261611D01*
G02X261912Y1643834I-1J-302D01*
G01Y1642872D01*
Y1552470D01*
X261722Y1552280D01*
X208952D01*
Y1642872D01*
X208954D01*
Y1643834D01*
G37*
G36*
G01X1232576D02*
G02X1232878Y1644136I302J0D01*
G01X1285233D01*
G02X1285534Y1643834I-1J-302D01*
G01Y1643226D01*
Y1552461D01*
X1285353Y1552280D01*
X1232574D01*
Y1643226D01*
X1232576D01*
Y1643834D01*
G37*
G36*
G01X1579032D02*
G02X1579335Y1644136I303J-1D01*
G01X1631688D01*
G02X1631990Y1643834I0J-302D01*
G01Y1643174D01*
X1631992D01*
Y1552573D01*
X1631698Y1552280D01*
X1579032D01*
Y1643174D01*
Y1643834D01*
G37*
G36*
G01X177763Y1512216D02*
X180583D01*
G02X180786Y1512014I1J-202D01*
G01Y1511392D01*
G03X180836Y1511260I200J0D01*
G02Y1508348I-1664J-1456D01*
G03X180786Y1508216I150J-132D01*
G01Y1506273D01*
G03X180836Y1506141I200J0D01*
G02Y1503229I-1664J-1456D01*
G03X180786Y1503097I150J-132D01*
G01Y1502476D01*
G02X180583Y1502274I-203J1D01*
G01X177763D01*
G02X177560Y1502476I-1J202D01*
G01Y1503097D01*
G03X177510Y1503229I-200J0D01*
G02Y1506141I1664J1456D01*
G03X177560Y1506273I-150J132D01*
G01Y1508216D01*
G03X177510Y1508348I-200J0D01*
G02Y1511260I1664J1456D01*
G03X177560Y1511392I-150J132D01*
G01Y1512014D01*
G02X177763Y1512216I203J-1D01*
G37*
G36*
G01X350991D02*
X353811D01*
G02X354014Y1512014I1J-202D01*
G01Y1511392D01*
G03X354064Y1511260I200J0D01*
G02Y1508348I-1664J-1456D01*
G03X354014Y1508216I150J-132D01*
G01Y1506273D01*
G03X354064Y1506141I200J0D01*
G02Y1503229I-1664J-1456D01*
G03X354014Y1503097I150J-132D01*
G01Y1502476D01*
G02X353811Y1502274I-203J1D01*
G01X350991D01*
G02X350788Y1502476I-1J202D01*
G01Y1503097D01*
G03X350738Y1503229I-200J0D01*
G02Y1506141I1664J1456D01*
G03X350788Y1506273I-150J132D01*
G01Y1508216D01*
G03X350738Y1508348I-200J0D01*
G02Y1511260I1664J1456D01*
G03X350788Y1511392I-150J132D01*
G01Y1512014D01*
G02X350991Y1512216I203J-1D01*
G37*
G36*
G01X186425Y1516546D02*
X189245D01*
G02X189448Y1516344I1J-202D01*
G01Y1515722D01*
G03X189498Y1515590I200J0D01*
G02Y1512678I-1664J-1456D01*
G03X189448Y1512546I150J-132D01*
G01Y1510604D01*
G03X189498Y1510472I200J0D01*
G02Y1507560I-1664J-1456D01*
G03X189448Y1507428I150J-132D01*
G01Y1506806D01*
G02X189245Y1506604I-203J1D01*
G01X186425D01*
G02X186222Y1506806I-1J202D01*
G01Y1507428D01*
G03X186172Y1507560I-200J0D01*
G02Y1510472I1664J1456D01*
G03X186222Y1510604I-150J132D01*
G01Y1512546D01*
G03X186172Y1512678I-200J0D01*
G02Y1515590I1664J1456D01*
G03X186222Y1515722I-150J132D01*
G01Y1516344D01*
G02X186425Y1516546I203J-1D01*
G37*
G36*
G01X359653D02*
X362473D01*
G02X362676Y1516344I1J-202D01*
G01Y1515722D01*
G03X362726Y1515590I200J0D01*
G02Y1512678I-1664J-1456D01*
G03X362676Y1512546I150J-132D01*
G01Y1510604D01*
G03X362726Y1510472I200J0D01*
G02Y1507560I-1664J-1456D01*
G03X362676Y1507428I150J-132D01*
G01Y1506806D01*
G02X362473Y1506604I-203J1D01*
G01X359653D01*
G02X359450Y1506806I-1J202D01*
G01Y1507428D01*
G03X359400Y1507560I-200J0D01*
G02Y1510472I1664J1456D01*
G03X359450Y1510604I-150J132D01*
G01Y1512546D01*
G03X359400Y1512678I-200J0D01*
G02Y1515590I1664J1456D01*
G03X359450Y1515722I-150J132D01*
G01Y1516344D01*
G02X359653Y1516546I203J-1D01*
G37*
G36*
G01X177763Y1568516D02*
X180583D01*
G02X180786Y1568313I0J-203D01*
G01Y1567691D01*
G03X180836Y1567559I200J0D01*
G02Y1564647I-1664J-1456D01*
G03X180786Y1564515I150J-132D01*
G01Y1562573D01*
G03X180836Y1562441I200J0D01*
G02Y1559529I-1664J-1456D01*
G03X180786Y1559397I150J-132D01*
G01Y1558775D01*
G02X180583Y1558572I-203J0D01*
G01X177763D01*
G02X177560Y1558775I0J203D01*
G01Y1559397D01*
G03X177510Y1559529I-200J0D01*
G02Y1562441I1664J1456D01*
G03X177560Y1562573I-150J132D01*
G01Y1564515D01*
G03X177510Y1564647I-200J0D01*
G02Y1567559I1664J1456D01*
G03X177560Y1567691I-150J132D01*
G01Y1568313D01*
G02X177763Y1568516I203J0D01*
G37*
G36*
G01X350991D02*
X353811D01*
G02X354014Y1568313I0J-203D01*
G01Y1567691D01*
G03X354064Y1567559I200J0D01*
G02Y1564647I-1664J-1456D01*
G03X354014Y1564515I150J-132D01*
G01Y1562573D01*
G03X354064Y1562441I200J0D01*
G02Y1559529I-1664J-1456D01*
G03X354014Y1559397I150J-132D01*
G01Y1558775D01*
G02X353811Y1558572I-203J0D01*
G01X350991D01*
G02X350788Y1558775I0J203D01*
G01Y1559397D01*
G03X350738Y1559529I-200J0D01*
G02Y1562441I1664J1456D01*
G03X350788Y1562573I-150J132D01*
G01Y1564515D01*
G03X350738Y1564647I-200J0D01*
G02Y1567559I1664J1456D01*
G03X350788Y1567691I-150J132D01*
G01Y1568313D01*
G02X350991Y1568516I203J0D01*
G37*
G36*
G01X186425Y1572846D02*
X189245D01*
G02X189448Y1572644I1J-202D01*
G01Y1572022D01*
G03X189498Y1571890I200J0D01*
G02Y1568978I-1664J-1456D01*
G03X189448Y1568846I150J-132D01*
G01Y1566903D01*
G03X189498Y1566771I200J0D01*
G02Y1563859I-1664J-1456D01*
G03X189448Y1563727I150J-132D01*
G01Y1563106D01*
G02X189245Y1562904I-203J1D01*
G01X186425D01*
G02X186222Y1563106I-1J202D01*
G01Y1563727D01*
G03X186172Y1563859I-200J0D01*
G02Y1566771I1664J1456D01*
G03X186222Y1566903I-150J132D01*
G01Y1568846D01*
G03X186172Y1568978I-200J0D01*
G02Y1571890I1664J1456D01*
G03X186222Y1572022I-150J132D01*
G01Y1572644D01*
G02X186425Y1572846I203J-1D01*
G37*
G36*
G01X359653D02*
X362473D01*
G02X362676Y1572644I1J-202D01*
G01Y1572022D01*
G03X362726Y1571890I200J0D01*
G02Y1568978I-1664J-1456D01*
G03X362676Y1568846I150J-132D01*
G01Y1566903D01*
G03X362726Y1566771I200J0D01*
G02Y1563859I-1664J-1456D01*
G03X362676Y1563727I150J-132D01*
G01Y1563106D01*
G02X362473Y1562904I-203J1D01*
G01X359653D01*
G02X359450Y1563106I-1J202D01*
G01Y1563727D01*
G03X359400Y1563859I-200J0D01*
G02Y1566771I1664J1456D01*
G03X359450Y1566903I-150J132D01*
G01Y1568846D01*
G03X359400Y1568978I-200J0D01*
G02Y1571890I1664J1456D01*
G03X359450Y1572022I-150J132D01*
G01Y1572644D01*
G02X359653Y1572846I203J-1D01*
G37*
G36*
G01X177763Y1583870D02*
X180583D01*
G02X180786Y1583667I0J-203D01*
G01Y1583045D01*
G03X180836Y1582913I200J0D01*
G02Y1580001I-1664J-1456D01*
G03X180786Y1579869I150J-132D01*
G01Y1577927D01*
G03X180836Y1577795I200J0D01*
G02Y1574883I-1664J-1456D01*
G03X180786Y1574751I150J-132D01*
G01Y1574129D01*
G02X180583Y1573926I-203J0D01*
G01X177763D01*
G02X177560Y1574129I0J203D01*
G01Y1574751D01*
G03X177510Y1574883I-200J0D01*
G02Y1577795I1664J1456D01*
G03X177560Y1577927I-150J132D01*
G01Y1579869D01*
G03X177510Y1580001I-200J0D01*
G02Y1582913I1664J1456D01*
G03X177560Y1583045I-150J132D01*
G01Y1583667D01*
G02X177763Y1583870I203J0D01*
G37*
G36*
G01X404759Y1350874D02*
X408159D01*
G02Y1347270I0J-1802D01*
G01X404759D01*
G02Y1350874I0J1802D01*
G37*
G36*
G01X402489Y1419078D02*
X405889D01*
G02Y1415472I0J-1803D01*
G01X402489D01*
G02Y1419078I0J1803D01*
G37*
G36*
G01X1443660Y1308896D02*
X1440260D01*
G02Y1312500I0J1802D01*
G01X1443660D01*
G02Y1308896I0J-1802D01*
G37*
G36*
G01X970197Y665850D02*
X966797D01*
G02Y669456I0J1803D01*
G01X970197D01*
G02Y665850I0J-1803D01*
G37*
G36*
G01X501495Y772260D02*
X504895D01*
G02Y768654I0J-1803D01*
G01X501495D01*
G02Y772260I0J1803D01*
G37*
G36*
G01X909508Y623418D02*
X912908D01*
G02Y619814I0J-1802D01*
G01X909508D01*
G02Y623418I0J1802D01*
G37*
G36*
G01X900676Y623338D02*
X904076D01*
G02Y619734I0J-1802D01*
G01X900676D01*
G02Y623338I0J1802D01*
G37*
G36*
G01X526264Y665858D02*
X529664D01*
G02Y662254I0J-1802D01*
G01X526264D01*
G02Y665858I0J1802D01*
G37*
G36*
G01X534264Y663358D02*
X537664D01*
G02Y659754I0J-1802D01*
G01X534264D01*
G02Y663358I0J1802D01*
G37*
G36*
G01X538985Y734790D02*
X535585D01*
G02Y738396I0J1803D01*
G01X538985D01*
G02Y734790I0J-1803D01*
G37*
G36*
G01X530985Y739790D02*
X527585D01*
G02Y743396I0J1803D01*
G01X530985D01*
G02Y739790I0J-1803D01*
G37*
G36*
G01X517731Y742874D02*
X521131D01*
G02Y739268I0J-1803D01*
G01X517731D01*
G02Y742874I0J1803D01*
G37*
G36*
G01X511724Y739232D02*
X508324D01*
G02Y742838I0J1803D01*
G01X511724D01*
G02Y739232I0J-1803D01*
G37*
G36*
G01X415777Y306272D02*
X419177D01*
G02Y302668I0J-1802D01*
G01X415777D01*
G02Y306272I0J1802D01*
G37*
G36*
G01X423651Y309272D02*
X427051D01*
G02Y305668I0J-1802D01*
G01X423651D01*
G02Y309272I0J1802D01*
G37*
G36*
G01X431525Y306272D02*
X434925D01*
G02Y302668I0J-1802D01*
G01X431525D01*
G02Y306272I0J1802D01*
G37*
G36*
G01X434924Y368506D02*
X431524D01*
G02Y372112I0J1803D01*
G01X434924D01*
G02Y368506I0J-1803D01*
G37*
G36*
G01X933247Y1585829D02*
X940733Y1578343D01*
G03X940735Y1578341I142J140D01*
G03X940910Y1578270I174J178D01*
G01X956757D01*
G02X956899Y1578211I0J-200D01*
G01X960831Y1574278D01*
G02X960890Y1574136I-141J-142D01*
G01Y1543680D01*
G03X960963Y1543504I249J0D01*
G01X965002Y1539465D01*
G03X965004Y1539463I142J140D01*
G03X965179Y1539392I174J178D01*
G01X1020321D01*
G02X1020463Y1539333I0J-200D01*
G01X1032517Y1527279D01*
G02X1032576Y1527137I-141J-142D01*
G01Y1492489D01*
G02X1032517Y1492347I-200J0D01*
G01X1031783Y1491613D01*
G02X1031641Y1491554I-142J141D01*
G01X946768D01*
G02X946626Y1491613I0J200D01*
G01X944169Y1494071D01*
G03X944167Y1494073I-142J-140D01*
G03X943992Y1494144I-174J-178D01*
G01X933579D01*
G03X933404Y1494073I-1J-249D01*
G03X933402Y1494071I140J-142D01*
G01X917849Y1478518D01*
G03X917776Y1478342I176J-176D01*
G01Y1464605D01*
G02X917717Y1464463I-200J0D01*
G01X914897Y1461643D01*
G03X914895Y1461641I140J-142D01*
G03X914824Y1461466I178J-174D01*
G01Y1460513D01*
G02X914765Y1460371I-200J0D01*
G01X914235Y1459842D01*
G03X914162Y1459666I176J-176D01*
G01Y1446033D01*
G02X914104Y1445891I-200J-1D01*
G01X913370Y1445157D01*
G02X913228Y1445098I-142J141D01*
G01X900144D01*
G02X900002Y1445157I0J200D01*
G01X899268Y1445891D01*
G02X899210Y1446033I142J141D01*
G01Y1459640D01*
G03X899137Y1459816I-249J0D01*
G01X898531Y1460422D01*
G02X898472Y1460564I141J142D01*
G01Y1462024D01*
G03X898399Y1462200I-249J0D01*
G01X893401Y1467197D01*
G02X893342Y1467339I141J142D01*
G01Y1473096D01*
G03X893271Y1473271I-249J1D01*
G03X893269Y1473273I-142J-140D01*
G01X888245Y1478297D01*
G03X888069Y1478370I-176J-176D01*
G01X880504D01*
G03X880328Y1478297I0J-249D01*
G01X872973Y1470942D01*
G03X872900Y1470766I176J-176D01*
G01Y1460576D01*
G02X872841Y1460434I-200J0D01*
G01X872211Y1459804D01*
G03X872209Y1459802I140J-142D01*
G03X872138Y1459627I178J-174D01*
G01Y1446008D01*
G02X872079Y1445866I-200J0D01*
G01X871383Y1445170D01*
G02X871241Y1445112I-141J142D01*
G01X858287D01*
G02X858145Y1445171I0J200D01*
G01X857137Y1446178D01*
G02X857078Y1446320I141J142D01*
G01Y1459524D01*
G03X857007Y1459699I-249J1D01*
G03X857005Y1459701I-142J-140D01*
G01X852953Y1463753D01*
G03X852951Y1463755I-142J-140D01*
G03X852776Y1463826I-174J-178D01*
G01X828441D01*
G03X828266Y1463755I-1J-249D01*
G03X828264Y1463753I140J-142D01*
G01X827747Y1463236D01*
G03X827674Y1463060I176J-176D01*
G01Y1461432D01*
G02X827615Y1461290I-200J0D01*
G01X826986Y1460661D01*
G02X826844Y1460602I-142J141D01*
G01X825036D01*
G03X824860Y1460529I0J-249D01*
G01X821948Y1457617D01*
G02X821806Y1457558I-142J141D01*
G01X820451D01*
G03X820275Y1457485I0J-249D01*
G01X820069Y1457279D01*
G03X820067Y1457277I140J-142D01*
G03X819996Y1457102I178J-174D01*
G01Y1446047D01*
G02X819937Y1445905I-200J0D01*
G01X819241Y1445209D01*
G02X819099Y1445150I-142J141D01*
G01X805978D01*
G02X805836Y1445209I0J200D01*
G01X805061Y1445984D01*
G02X805002Y1446126I141J142D01*
G01Y1460243D01*
G02X805061Y1460385I200J0D01*
G01X805487Y1460810D01*
G03X805560Y1460986I-176J176D01*
G01Y1474724D01*
G02X805619Y1474866I200J0D01*
G01X805875Y1475122D01*
G03X805877Y1475124I-140J142D01*
G03X805948Y1475299I-178J174D01*
G01Y1524130D01*
G02X806007Y1524272I200J0D01*
G01X816121Y1534385D01*
G03X816123Y1534387I-140J142D01*
G03X816194Y1534562I-178J174D01*
G01Y1621268D01*
G02X816253Y1621410I200J0D01*
G01X822113Y1627269D01*
G02X822255Y1627328I142J-141D01*
G01X927980D01*
G02X928122Y1627269I0J-200D01*
G01X933115Y1622276D01*
G02X933174Y1622134I-141J-142D01*
G01Y1586005D01*
G03X933247Y1585829I249J0D01*
G37*
G36*
G01X1047661Y1451746D02*
X1045748Y1449833D01*
G02X1045606Y1449774I-142J141D01*
G01X955889D01*
G02X955747Y1449833I0J200D01*
G01X954749Y1450831D01*
G02X954690Y1450973I141J142D01*
G01Y1485726D01*
G02X954749Y1485868I200J0D01*
G01X956753Y1487871D01*
G02X956895Y1487930I142J-141D01*
G01X1046147D01*
G02X1046289Y1487871I0J-200D01*
G01X1047661Y1486500D01*
G02X1047720Y1486358I-141J-142D01*
G01Y1451888D01*
G02X1047661Y1451746I-200J0D01*
G37*
G36*
G01X952704Y1482405D02*
X953818Y1481291D01*
G03X953834Y1481276I178J174D01*
G01X954122Y1481036D01*
G02X954194Y1480882I-128J-154D01*
G01Y1451027D01*
G02X954135Y1450885I-200J0D01*
G01X953083Y1449833D01*
G02X952941Y1449774I-142J141D01*
G01X930177D01*
G02X930035Y1449833I0J200D01*
G01X928619Y1451249D01*
G02X928560Y1451391I141J142D01*
G01Y1481306D01*
G02X928619Y1481448I200J0D01*
G01X930003Y1482831D01*
G02X930145Y1482890I142J-141D01*
G01X952269D01*
G02X952435Y1482801I0J-200D01*
G01X952673Y1482443D01*
G03X952703Y1482406I207J137D01*
G01X952704Y1482405D01*
G37*
G36*
G01X26772Y1559218D02*
X20472D01*
G02Y1575428I0J8105D01*
G01X26772D01*
G02Y1559218I0J-8105D01*
G37*
G36*
G01X216125Y1441832D02*
X219525D01*
G02Y1438226I0J-1803D01*
G01X216125D01*
G02Y1441832I0J1803D01*
G37*
G36*
G01X413753Y1518690D02*
X417153D01*
G02Y1515084I0J-1803D01*
G01X413753D01*
G02Y1518690I0J1803D01*
G37*
G36*
G01X417334Y1475298D02*
X413934D01*
G02Y1478902I0J1802D01*
G01X417334D01*
G02Y1475298I0J-1802D01*
G37*
G36*
G01X919628Y334530D02*
X916228D01*
G02Y338136I0J1803D01*
G01X919628D01*
G02Y334530I0J-1803D01*
G37*
G36*
G01X905899Y304150D02*
X909299D01*
G02Y300544I0J-1803D01*
G01X905899D01*
G02Y304150I0J1803D01*
G37*
G36*
G01X1033891Y298096D02*
X1037291D01*
G02Y294490I0J-1803D01*
G01X1033891D01*
G02Y298096I0J1803D01*
G37*
G36*
G01X1318363Y312364D02*
X1321763D01*
G02Y308760I0J-1802D01*
G01X1318363D01*
G02Y312364I0J1802D01*
G37*
G36*
G01X1337508Y371598D02*
X1334108D01*
G02Y375204I0J1803D01*
G01X1337508D01*
G02Y371598I0J-1803D01*
G37*
G36*
G01X1326237Y309364D02*
X1329637D01*
G02Y305760I0J-1802D01*
G01X1326237D01*
G02Y309364I0J1802D01*
G37*
G36*
G01X1334111Y312364D02*
X1337511D01*
G02Y308760I0J-1802D01*
G01X1334111D01*
G02Y312364I0J1802D01*
G37*
G36*
G01X1518207Y1176748D02*
X1514467D01*
G02Y1179354I0J1303D01*
G01X1518207D01*
G02Y1176748I0J-1303D01*
G37*
G36*
G01Y1169268D02*
X1514467D01*
G02Y1171872I0J1302D01*
G01X1518207D01*
G02Y1169268I0J-1302D01*
G37*
G36*
G01X1513926Y907148D02*
X1510526D01*
G02Y910754I0J1803D01*
G01X1513926D01*
G02Y907148I0J-1803D01*
G37*
G36*
G01X1531299Y1174878D02*
X1527559D01*
G02Y1177482I0J1302D01*
G01X1531299D01*
G02Y1174878I0J-1302D01*
G37*
G36*
G01X146947Y1176748D02*
X143207D01*
G02Y1179354I0J1303D01*
G01X146947D01*
G02Y1176748I0J-1303D01*
G37*
G36*
G01Y1169268D02*
X143207D01*
G02Y1171872I0J1302D01*
G01X146947D01*
G02Y1169268I0J-1302D01*
G37*
G36*
G01X160039Y1174878D02*
X156299D01*
G02Y1177482I0J1302D01*
G01X160039D01*
G02Y1174878I0J-1302D01*
G37*
G36*
G01X604034Y1176748D02*
X600294D01*
G02Y1179354I0J1303D01*
G01X604034D01*
G02Y1176748I0J-1303D01*
G37*
G36*
G01Y1169268D02*
X600294D01*
G02Y1171872I0J1302D01*
G01X604034D01*
G02Y1169268I0J-1302D01*
G37*
G36*
G01X605733Y942940D02*
X609133D01*
G02Y939336I0J-1802D01*
G01X605733D01*
G02Y942940I0J1802D01*
G37*
G36*
G01X615256Y1176748D02*
X611516D01*
G02Y1179354I0J1303D01*
G01X615256D01*
G02Y1176748I0J-1303D01*
G37*
G36*
G01X1061120D02*
X1057380D01*
G02Y1179354I0J1303D01*
G01X1061120D01*
G02Y1176748I0J-1303D01*
G37*
G36*
G01Y1169268D02*
X1057380D01*
G02Y1171872I0J1302D01*
G01X1061120D01*
G02Y1169268I0J-1302D01*
G37*
G36*
G01X1769063Y921922D02*
X1765663D01*
G02Y925526I0J1802D01*
G01X1769063D01*
G02Y921922I0J-1802D01*
G37*
G36*
G01X1072342Y1176748D02*
X1068602D01*
G02Y1179354I0J1303D01*
G01X1072342D01*
G02Y1176748I0J-1303D01*
G37*
G36*
G01X647411Y379065D02*
X647412D01*
G02Y370659I0J-4203D01*
G01X647411D01*
G02Y379065I0J4203D01*
G37*
G36*
G01X111494Y1456412D02*
G02X111292Y1456210I-202J0D01*
G01X108472D01*
G02X108270Y1456413I1J203D01*
G01Y1457032D01*
G03X108220Y1457164I-200J0D01*
G02Y1460080I1661J1458D01*
G03X108270Y1460212I-150J132D01*
G01Y1462151D01*
G03X108220Y1462283I-200J0D01*
G02Y1465199I1661J1458D01*
G03X108270Y1465331I-150J132D01*
G01Y1465952D01*
G02X108472Y1466154I202J0D01*
G01X111292D01*
G02X111494Y1465951I-1J-203D01*
G01Y1465331D01*
G03X111544Y1465199I200J0D01*
G02Y1462283I-1661J-1458D01*
G03X111494Y1462151I150J-132D01*
G01Y1460212D01*
G03X111544Y1460080I200J0D01*
G02Y1457164I-1661J-1458D01*
G03X111494Y1457032I150J-132D01*
G01Y1456412D01*
G37*
G36*
G01X319368D02*
G02X319166Y1456210I-202J0D01*
G01X316346D01*
G02X316144Y1456413I1J203D01*
G01Y1457032D01*
G03X316094Y1457164I-200J0D01*
G02Y1460080I1661J1458D01*
G03X316144Y1460212I-150J132D01*
G01Y1462151D01*
G03X316094Y1462283I-200J0D01*
G02Y1465199I1661J1458D01*
G03X316144Y1465331I-150J132D01*
G01Y1465952D01*
G02X316346Y1466154I202J0D01*
G01X319166D01*
G02X319368Y1465951I-1J-203D01*
G01Y1465331D01*
G03X319418Y1465199I200J0D01*
G02Y1462283I-1661J-1458D01*
G03X319368Y1462151I150J-132D01*
G01Y1460212D01*
G03X319418Y1460080I200J0D01*
G02Y1457164I-1661J-1458D01*
G03X319368Y1457032I150J-132D01*
G01Y1456412D01*
G37*
G36*
G01X336690D02*
G02X336488Y1456210I-202J0D01*
G01X333668D01*
G02X333466Y1456413I1J203D01*
G01Y1457032D01*
G03X333416Y1457164I-200J0D01*
G02Y1460080I1661J1458D01*
G03X333466Y1460212I-150J132D01*
G01Y1462151D01*
G03X333416Y1462283I-200J0D01*
G02Y1465199I1661J1458D01*
G03X333466Y1465331I-150J132D01*
G01Y1465952D01*
G02X333668Y1466154I202J0D01*
G01X336488D01*
G02X336690Y1465951I-1J-203D01*
G01Y1465331D01*
G03X336740Y1465199I200J0D01*
G02Y1462283I-1661J-1458D01*
G03X336690Y1462151I150J-132D01*
G01Y1460212D01*
G03X336740Y1460080I200J0D01*
G02Y1457164I-1661J-1458D01*
G03X336690Y1457032I150J-132D01*
G01Y1456412D01*
G37*
G36*
G01X628157Y1466154D02*
X630977D01*
G02X631180Y1465951I0J-203D01*
G01Y1465329D01*
G03X631230Y1465197I200J0D01*
G02Y1462285I-1664J-1456D01*
G03X631180Y1462153I150J-132D01*
G01Y1460210D01*
G03X631230Y1460078I200J0D01*
G02Y1457166I-1664J-1456D01*
G03X631180Y1457034I150J-132D01*
G01Y1456413D01*
G02X630977Y1456210I-203J0D01*
G01X628157D01*
G02X627954Y1456413I0J203D01*
G01Y1457034D01*
G03X627904Y1457166I-200J0D01*
G02Y1460078I1664J1456D01*
G03X627954Y1460210I-150J132D01*
G01Y1462153D01*
G03X627904Y1462285I-200J0D01*
G02Y1465197I1664J1456D01*
G03X627954Y1465329I-150J132D01*
G01Y1465951D01*
G02X628157Y1466154I203J0D01*
G37*
G36*
G01X1133462Y1456412D02*
G02X1133260Y1456210I-202J0D01*
G01X1130440D01*
G02X1130238Y1456413I1J203D01*
G01Y1457032D01*
G03X1130188Y1457164I-200J0D01*
G02Y1460080I1661J1458D01*
G03X1130238Y1460212I-150J132D01*
G01Y1462151D01*
G03X1130188Y1462283I-200J0D01*
G02Y1465199I1661J1458D01*
G03X1130238Y1465331I-150J132D01*
G01Y1465952D01*
G02X1130440Y1466154I202J0D01*
G01X1133260D01*
G02X1133462Y1465951I-1J-203D01*
G01Y1465331D01*
G03X1133512Y1465199I200J0D01*
G02Y1462283I-1661J-1458D01*
G03X1133462Y1462151I150J-132D01*
G01Y1460212D01*
G03X1133512Y1460080I200J0D01*
G02Y1457164I-1661J-1458D01*
G03X1133462Y1457032I150J-132D01*
G01Y1456412D01*
G37*
G36*
G01X1147763Y1466154D02*
X1150583D01*
G02X1150786Y1465951I0J-203D01*
G01Y1465329D01*
G03X1150836Y1465197I200J0D01*
G02Y1462285I-1664J-1456D01*
G03X1150786Y1462153I150J-132D01*
G01Y1460210D01*
G03X1150836Y1460078I200J0D01*
G02Y1457166I-1664J-1456D01*
G03X1150786Y1457034I150J-132D01*
G01Y1456413D01*
G02X1150583Y1456210I-203J0D01*
G01X1147763D01*
G02X1147560Y1456413I0J203D01*
G01Y1457034D01*
G03X1147510Y1457166I-200J0D01*
G02Y1460078I1664J1456D01*
G03X1147560Y1460210I-150J132D01*
G01Y1462153D01*
G03X1147510Y1462285I-200J0D01*
G02Y1465197I1664J1456D01*
G03X1147560Y1465329I-150J132D01*
G01Y1465951D01*
G02X1147763Y1466154I203J0D01*
G37*
G36*
G01X1650125D02*
X1652945D01*
G02X1653148Y1465951I0J-203D01*
G01Y1465329D01*
G03X1653198Y1465197I200J0D01*
G02Y1462285I-1664J-1456D01*
G03X1653148Y1462153I150J-132D01*
G01Y1460210D01*
G03X1653198Y1460078I200J0D01*
G02Y1457166I-1664J-1456D01*
G03X1653148Y1457034I150J-132D01*
G01Y1456413D01*
G02X1652945Y1456210I-203J0D01*
G01X1650125D01*
G02X1649922Y1456413I0J203D01*
G01Y1457034D01*
G03X1649872Y1457166I-200J0D01*
G02Y1460078I1664J1456D01*
G03X1649922Y1460210I-150J132D01*
G01Y1462153D01*
G03X1649872Y1462285I-200J0D01*
G02Y1465197I1664J1456D01*
G03X1649922Y1465329I-150J132D01*
G01Y1465951D01*
G02X1650125Y1466154I203J0D01*
G37*
G36*
G01X1670470Y1456412D02*
G02X1670268Y1456210I-202J0D01*
G01X1667448D01*
G02X1667246Y1456413I1J203D01*
G01Y1457032D01*
G03X1667196Y1457164I-200J0D01*
G02Y1460080I1661J1458D01*
G03X1667246Y1460212I-150J132D01*
G01Y1462151D01*
G03X1667196Y1462283I-200J0D01*
G02Y1465199I1661J1458D01*
G03X1667246Y1465331I-150J132D01*
G01Y1465952D01*
G02X1667448Y1466154I202J0D01*
G01X1670268D01*
G02X1670470Y1465951I-1J-203D01*
G01Y1465331D01*
G03X1670520Y1465199I200J0D01*
G02Y1462283I-1661J-1458D01*
G03X1670470Y1462151I150J-132D01*
G01Y1460212D01*
G03X1670520Y1460080I200J0D01*
G02Y1457164I-1661J-1458D01*
G03X1670470Y1457032I150J-132D01*
G01Y1456412D01*
G37*
G36*
G01X117133Y1470484D02*
X119953D01*
G02X120156Y1470281I0J-203D01*
G01Y1469659D01*
G03X120206Y1469527I200J0D01*
G02Y1466615I-1664J-1456D01*
G03X120156Y1466483I150J-132D01*
G01Y1464541D01*
G03X120206Y1464409I200J0D01*
G02Y1461497I-1664J-1456D01*
G03X120156Y1461365I150J-132D01*
G01Y1460743D01*
G02X119953Y1460540I-203J0D01*
G01X117133D01*
G02X116930Y1460743I0J203D01*
G01Y1461365D01*
G03X116880Y1461497I-200J0D01*
G02Y1464409I1664J1456D01*
G03X116930Y1464541I-150J132D01*
G01Y1466483D01*
G03X116880Y1466615I-200J0D01*
G02Y1469527I1664J1456D01*
G03X116930Y1469659I-150J132D01*
G01Y1470281D01*
G02X117133Y1470484I203J0D01*
G37*
G36*
G01X310706Y1460742D02*
G02X310504Y1460540I-202J0D01*
G01X307684D01*
G02X307482Y1460743I1J203D01*
G01Y1461363D01*
G03X307432Y1461495I-200J0D01*
G02Y1464411I1661J1458D01*
G03X307482Y1464543I-150J132D01*
G01Y1466481D01*
G03X307432Y1466613I-200J0D01*
G02Y1469529I1661J1458D01*
G03X307482Y1469661I-150J132D01*
G01Y1470282D01*
G02X307684Y1470484I202J0D01*
G01X310504D01*
G02X310706Y1470281I-1J-203D01*
G01Y1469661D01*
G03X310756Y1469529I200J0D01*
G02Y1466613I-1661J-1458D01*
G03X310706Y1466481I150J-132D01*
G01Y1464543D01*
G03X310756Y1464411I200J0D01*
G02Y1461495I-1661J-1458D01*
G03X310706Y1461363I150J-132D01*
G01Y1460742D01*
G37*
G36*
G01X325007Y1470484D02*
X327827D01*
G02X328030Y1470281I0J-203D01*
G01Y1469659D01*
G03X328080Y1469527I200J0D01*
G02Y1466615I-1664J-1456D01*
G03X328030Y1466483I150J-132D01*
G01Y1464541D01*
G03X328080Y1464409I200J0D01*
G02Y1461497I-1664J-1456D01*
G03X328030Y1461365I150J-132D01*
G01Y1460743D01*
G02X327827Y1460540I-203J0D01*
G01X325007D01*
G02X324804Y1460743I0J203D01*
G01Y1461365D01*
G03X324754Y1461497I-200J0D01*
G02Y1464409I1664J1456D01*
G03X324804Y1464541I-150J132D01*
G01Y1466483D01*
G03X324754Y1466615I-200J0D01*
G02Y1469527I1664J1456D01*
G03X324804Y1469659I-150J132D01*
G01Y1470281D01*
G02X325007Y1470484I203J0D01*
G37*
G36*
G01X345352Y1460742D02*
G02X345150Y1460540I-202J0D01*
G01X342330D01*
G02X342128Y1460743I1J203D01*
G01Y1461363D01*
G03X342078Y1461495I-200J0D01*
G02Y1464411I1661J1458D01*
G03X342128Y1464543I-150J132D01*
G01Y1466481D01*
G03X342078Y1466613I-200J0D01*
G02Y1469529I1661J1458D01*
G03X342128Y1469661I-150J132D01*
G01Y1470282D01*
G02X342330Y1470484I202J0D01*
G01X345150D01*
G02X345352Y1470281I-1J-203D01*
G01Y1469661D01*
G03X345402Y1469529I200J0D01*
G02Y1466613I-1661J-1458D01*
G03X345352Y1466481I150J-132D01*
G01Y1464543D01*
G03X345402Y1464411I200J0D01*
G02Y1461495I-1661J-1458D01*
G03X345352Y1461363I150J-132D01*
G01Y1460742D01*
G37*
G36*
G01X639840D02*
G02X639638Y1460540I-202J0D01*
G01X636818D01*
G02X636616Y1460743I1J203D01*
G01Y1461363D01*
G03X636566Y1461495I-200J0D01*
G02Y1464411I1661J1458D01*
G03X636616Y1464543I-150J132D01*
G01Y1466481D01*
G03X636566Y1466613I-200J0D01*
G02Y1469529I1661J1458D01*
G03X636616Y1469661I-150J132D01*
G01Y1470282D01*
G02X636818Y1470484I202J0D01*
G01X639638D01*
G02X639840Y1470281I-1J-203D01*
G01Y1469661D01*
G03X639890Y1469529I200J0D01*
G02Y1466613I-1661J-1458D01*
G03X639840Y1466481I150J-132D01*
G01Y1464543D01*
G03X639890Y1464411I200J0D01*
G02Y1461495I-1661J-1458D01*
G03X639840Y1461363I150J-132D01*
G01Y1460742D01*
G37*
G36*
G01X1139101Y1470484D02*
X1141921D01*
G02X1142124Y1470281I0J-203D01*
G01Y1469659D01*
G03X1142174Y1469527I200J0D01*
G02Y1466615I-1664J-1456D01*
G03X1142124Y1466483I150J-132D01*
G01Y1464541D01*
G03X1142174Y1464409I200J0D01*
G02Y1461497I-1664J-1456D01*
G03X1142124Y1461365I150J-132D01*
G01Y1460743D01*
G02X1141921Y1460540I-203J0D01*
G01X1139101D01*
G02X1138898Y1460743I0J203D01*
G01Y1461365D01*
G03X1138848Y1461497I-200J0D01*
G02Y1464409I1664J1456D01*
G03X1138898Y1464541I-150J132D01*
G01Y1466483D01*
G03X1138848Y1466615I-200J0D01*
G02Y1469527I1664J1456D01*
G03X1138898Y1469659I-150J132D01*
G01Y1470281D01*
G02X1139101Y1470484I203J0D01*
G37*
G36*
G01X1159446Y1460742D02*
G02X1159244Y1460540I-202J0D01*
G01X1156424D01*
G02X1156222Y1460743I1J203D01*
G01Y1461363D01*
G03X1156172Y1461495I-200J0D01*
G02Y1464411I1661J1458D01*
G03X1156222Y1464543I-150J132D01*
G01Y1466481D01*
G03X1156172Y1466613I-200J0D01*
G02Y1469529I1661J1458D01*
G03X1156222Y1469661I-150J132D01*
G01Y1470282D01*
G02X1156424Y1470484I202J0D01*
G01X1159244D01*
G02X1159446Y1470281I-1J-203D01*
G01Y1469661D01*
G03X1159496Y1469529I200J0D01*
G02Y1466613I-1661J-1458D01*
G03X1159446Y1466481I150J-132D01*
G01Y1464543D01*
G03X1159496Y1464411I200J0D01*
G02Y1461495I-1661J-1458D01*
G03X1159446Y1461363I150J-132D01*
G01Y1460742D01*
G37*
G36*
G01X1661808D02*
G02X1661606Y1460540I-202J0D01*
G01X1658786D01*
G02X1658584Y1460743I1J203D01*
G01Y1461363D01*
G03X1658534Y1461495I-200J0D01*
G02Y1464411I1661J1458D01*
G03X1658584Y1464543I-150J132D01*
G01Y1466481D01*
G03X1658534Y1466613I-200J0D01*
G02Y1469529I1661J1458D01*
G03X1658584Y1469661I-150J132D01*
G01Y1470282D01*
G02X1658786Y1470484I202J0D01*
G01X1661606D01*
G02X1661808Y1470281I-1J-203D01*
G01Y1469661D01*
G03X1661858Y1469529I200J0D01*
G02Y1466613I-1661J-1458D01*
G03X1661808Y1466481I150J-132D01*
G01Y1464543D01*
G03X1661858Y1464411I200J0D01*
G02Y1461495I-1661J-1458D01*
G03X1661808Y1461363I150J-132D01*
G01Y1460742D01*
G37*
G36*
G01X1676109Y1470484D02*
X1678929D01*
G02X1679132Y1470281I0J-203D01*
G01Y1469659D01*
G03X1679182Y1469527I200J0D01*
G02Y1466615I-1664J-1456D01*
G03X1679132Y1466483I150J-132D01*
G01Y1464541D01*
G03X1679182Y1464409I200J0D01*
G02Y1461497I-1664J-1456D01*
G03X1679132Y1461365I150J-132D01*
G01Y1460743D01*
G02X1678929Y1460540I-203J0D01*
G01X1676109D01*
G02X1675906Y1460743I0J203D01*
G01Y1461365D01*
G03X1675856Y1461497I-200J0D01*
G02Y1464409I1664J1456D01*
G03X1675906Y1464541I-150J132D01*
G01Y1466483D01*
G03X1675856Y1466615I-200J0D01*
G02Y1469527I1664J1456D01*
G03X1675906Y1469659I-150J132D01*
G01Y1470281D01*
G02X1676109Y1470484I203J0D01*
G37*
G36*
G01X111494Y1471766D02*
G02X111292Y1471564I-202J0D01*
G01X108472D01*
G02X108270Y1471767I1J203D01*
G01Y1472387D01*
G03X108220Y1472519I-200J0D01*
G02Y1475435I1661J1458D01*
G03X108270Y1475567I-150J132D01*
G01Y1477505D01*
G03X108220Y1477637I-200J0D01*
G02Y1480553I1661J1458D01*
G03X108270Y1480685I-150J132D01*
G01Y1481306D01*
G02X108472Y1481508I202J0D01*
G01X111292D01*
G02X111494Y1481305I-1J-203D01*
G01Y1480685D01*
G03X111544Y1480553I200J0D01*
G02Y1477637I-1661J-1458D01*
G03X111494Y1477505I150J-132D01*
G01Y1475567D01*
G03X111544Y1475435I200J0D01*
G02Y1472519I-1661J-1458D01*
G03X111494Y1472387I150J-132D01*
G01Y1471766D01*
G37*
G36*
G01X319368D02*
G02X319166Y1471564I-202J0D01*
G01X316346D01*
G02X316144Y1471767I1J203D01*
G01Y1472387D01*
G03X316094Y1472519I-200J0D01*
G02Y1475435I1661J1458D01*
G03X316144Y1475567I-150J132D01*
G01Y1477505D01*
G03X316094Y1477637I-200J0D01*
G02Y1480553I1661J1458D01*
G03X316144Y1480685I-150J132D01*
G01Y1481306D01*
G02X316346Y1481508I202J0D01*
G01X319166D01*
G02X319368Y1481305I-1J-203D01*
G01Y1480685D01*
G03X319418Y1480553I200J0D01*
G02Y1477637I-1661J-1458D01*
G03X319368Y1477505I150J-132D01*
G01Y1475567D01*
G03X319418Y1475435I200J0D01*
G02Y1472519I-1661J-1458D01*
G03X319368Y1472387I150J-132D01*
G01Y1471766D01*
G37*
G36*
G01X336690D02*
G02X336488Y1471564I-202J0D01*
G01X333668D01*
G02X333466Y1471767I1J203D01*
G01Y1472387D01*
G03X333416Y1472519I-200J0D01*
G02Y1475435I1661J1458D01*
G03X333466Y1475567I-150J132D01*
G01Y1477505D01*
G03X333416Y1477637I-200J0D01*
G02Y1480553I1661J1458D01*
G03X333466Y1480685I-150J132D01*
G01Y1481306D01*
G02X333668Y1481508I202J0D01*
G01X336488D01*
G02X336690Y1481305I-1J-203D01*
G01Y1480685D01*
G03X336740Y1480553I200J0D01*
G02Y1477637I-1661J-1458D01*
G03X336690Y1477505I150J-132D01*
G01Y1475567D01*
G03X336740Y1475435I200J0D01*
G02Y1472519I-1661J-1458D01*
G03X336690Y1472387I150J-132D01*
G01Y1471766D01*
G37*
G36*
G01X628157Y1481508D02*
X630977D01*
G02X631180Y1481305I0J-203D01*
G01Y1480683D01*
G03X631230Y1480551I200J0D01*
G02Y1477639I-1664J-1456D01*
G03X631180Y1477507I150J-132D01*
G01Y1475565D01*
G03X631230Y1475433I200J0D01*
G02Y1472521I-1664J-1456D01*
G03X631180Y1472389I150J-132D01*
G01Y1471767D01*
G02X630977Y1471564I-203J0D01*
G01X628157D01*
G02X627954Y1471767I0J203D01*
G01Y1472389D01*
G03X627904Y1472521I-200J0D01*
G02Y1475433I1664J1456D01*
G03X627954Y1475565I-150J132D01*
G01Y1477507D01*
G03X627904Y1477639I-200J0D01*
G02Y1480551I1664J1456D01*
G03X627954Y1480683I-150J132D01*
G01Y1481305D01*
G02X628157Y1481508I203J0D01*
G37*
G36*
G01X1133462Y1471766D02*
G02X1133260Y1471564I-202J0D01*
G01X1130440D01*
G02X1130238Y1471767I1J203D01*
G01Y1472387D01*
G03X1130188Y1472519I-200J0D01*
G02Y1475435I1661J1458D01*
G03X1130238Y1475567I-150J132D01*
G01Y1477505D01*
G03X1130188Y1477637I-200J0D01*
G02Y1480553I1661J1458D01*
G03X1130238Y1480685I-150J132D01*
G01Y1481306D01*
G02X1130440Y1481508I202J0D01*
G01X1133260D01*
G02X1133462Y1481305I-1J-203D01*
G01Y1480685D01*
G03X1133512Y1480553I200J0D01*
G02Y1477637I-1661J-1458D01*
G03X1133462Y1477505I150J-132D01*
G01Y1475567D01*
G03X1133512Y1475435I200J0D01*
G02Y1472519I-1661J-1458D01*
G03X1133462Y1472387I150J-132D01*
G01Y1471766D01*
G37*
G36*
G01X1147763Y1481508D02*
X1150583D01*
G02X1150786Y1481305I0J-203D01*
G01Y1480683D01*
G03X1150836Y1480551I200J0D01*
G02Y1477639I-1664J-1456D01*
G03X1150786Y1477507I150J-132D01*
G01Y1475565D01*
G03X1150836Y1475433I200J0D01*
G02Y1472521I-1664J-1456D01*
G03X1150786Y1472389I150J-132D01*
G01Y1471767D01*
G02X1150583Y1471564I-203J0D01*
G01X1147763D01*
G02X1147560Y1471767I0J203D01*
G01Y1472389D01*
G03X1147510Y1472521I-200J0D01*
G02Y1475433I1664J1456D01*
G03X1147560Y1475565I-150J132D01*
G01Y1477507D01*
G03X1147510Y1477639I-200J0D01*
G02Y1480551I1664J1456D01*
G03X1147560Y1480683I-150J132D01*
G01Y1481305D01*
G02X1147763Y1481508I203J0D01*
G37*
G36*
G01X1650125D02*
X1652945D01*
G02X1653148Y1481305I0J-203D01*
G01Y1480683D01*
G03X1653198Y1480551I200J0D01*
G02Y1477639I-1664J-1456D01*
G03X1653148Y1477507I150J-132D01*
G01Y1475565D01*
G03X1653198Y1475433I200J0D01*
G02Y1472521I-1664J-1456D01*
G03X1653148Y1472389I150J-132D01*
G01Y1471767D01*
G02X1652945Y1471564I-203J0D01*
G01X1650125D01*
G02X1649922Y1471767I0J203D01*
G01Y1472389D01*
G03X1649872Y1472521I-200J0D01*
G02Y1475433I1664J1456D01*
G03X1649922Y1475565I-150J132D01*
G01Y1477507D01*
G03X1649872Y1477639I-200J0D01*
G02Y1480551I1664J1456D01*
G03X1649922Y1480683I-150J132D01*
G01Y1481305D01*
G02X1650125Y1481508I203J0D01*
G37*
G36*
G01X1670470Y1471766D02*
G02X1670268Y1471564I-202J0D01*
G01X1667448D01*
G02X1667246Y1471767I1J203D01*
G01Y1472387D01*
G03X1667196Y1472519I-200J0D01*
G02Y1475435I1661J1458D01*
G03X1667246Y1475567I-150J132D01*
G01Y1477505D01*
G03X1667196Y1477637I-200J0D01*
G02Y1480553I1661J1458D01*
G03X1667246Y1480685I-150J132D01*
G01Y1481306D01*
G02X1667448Y1481508I202J0D01*
G01X1670268D01*
G02X1670470Y1481305I-1J-203D01*
G01Y1480685D01*
G03X1670520Y1480553I200J0D01*
G02Y1477637I-1661J-1458D01*
G03X1670470Y1477505I150J-132D01*
G01Y1475567D01*
G03X1670520Y1475435I200J0D01*
G02Y1472519I-1661J-1458D01*
G03X1670470Y1472387I150J-132D01*
G01Y1471766D01*
G37*
G36*
G01X117133Y1485838D02*
X119953D01*
G02X120156Y1485635I0J-203D01*
G01Y1485014D01*
G03X120206Y1484882I200J0D01*
G02Y1481970I-1664J-1456D01*
G03X120156Y1481838I150J-132D01*
G01Y1479896D01*
G03X120206Y1479764I200J0D01*
G02Y1476852I-1664J-1456D01*
G03X120156Y1476720I150J-132D01*
G01Y1476097D01*
G02X119953Y1475894I-203J0D01*
G01X117133D01*
G02X116930Y1476097I0J203D01*
G01Y1476720D01*
G03X116880Y1476852I-200J0D01*
G02Y1479764I1664J1456D01*
G03X116930Y1479896I-150J132D01*
G01Y1481838D01*
G03X116880Y1481970I-200J0D01*
G02Y1484882I1664J1456D01*
G03X116930Y1485014I-150J132D01*
G01Y1485635D01*
G02X117133Y1485838I203J0D01*
G37*
G36*
G01X310706Y1476096D02*
G02X310504Y1475894I-202J0D01*
G01X307684D01*
G02X307482Y1476097I1J203D01*
G01Y1476718D01*
G03X307432Y1476850I-200J0D01*
G02Y1479766I1661J1458D01*
G03X307482Y1479898I-150J132D01*
G01Y1481836D01*
G03X307432Y1481968I-200J0D01*
G02Y1484884I1661J1458D01*
G03X307482Y1485016I-150J132D01*
G01Y1485636D01*
G02X307684Y1485838I202J0D01*
G01X310504D01*
G02X310706Y1485635I-1J-203D01*
G01Y1485016D01*
G03X310756Y1484884I200J0D01*
G02Y1481968I-1661J-1458D01*
G03X310706Y1481836I150J-132D01*
G01Y1479898D01*
G03X310756Y1479766I200J0D01*
G02Y1476850I-1661J-1458D01*
G03X310706Y1476718I150J-132D01*
G01Y1476096D01*
G37*
G36*
G01X325007Y1485838D02*
X327827D01*
G02X328030Y1485635I0J-203D01*
G01Y1485014D01*
G03X328080Y1484882I200J0D01*
G02Y1481970I-1664J-1456D01*
G03X328030Y1481838I150J-132D01*
G01Y1479896D01*
G03X328080Y1479764I200J0D01*
G02Y1476852I-1664J-1456D01*
G03X328030Y1476720I150J-132D01*
G01Y1476097D01*
G02X327827Y1475894I-203J0D01*
G01X325007D01*
G02X324804Y1476097I0J203D01*
G01Y1476720D01*
G03X324754Y1476852I-200J0D01*
G02Y1479764I1664J1456D01*
G03X324804Y1479896I-150J132D01*
G01Y1481838D01*
G03X324754Y1481970I-200J0D01*
G02Y1484882I1664J1456D01*
G03X324804Y1485014I-150J132D01*
G01Y1485635D01*
G02X325007Y1485838I203J0D01*
G37*
G36*
G01X345352Y1476096D02*
G02X345150Y1475894I-202J0D01*
G01X342330D01*
G02X342128Y1476097I1J203D01*
G01Y1476718D01*
G03X342078Y1476850I-200J0D01*
G02Y1479766I1661J1458D01*
G03X342128Y1479898I-150J132D01*
G01Y1481836D01*
G03X342078Y1481968I-200J0D01*
G02Y1484884I1661J1458D01*
G03X342128Y1485016I-150J132D01*
G01Y1485636D01*
G02X342330Y1485838I202J0D01*
G01X345150D01*
G02X345352Y1485635I-1J-203D01*
G01Y1485016D01*
G03X345402Y1484884I200J0D01*
G02Y1481968I-1661J-1458D01*
G03X345352Y1481836I150J-132D01*
G01Y1479898D01*
G03X345402Y1479766I200J0D01*
G02Y1476850I-1661J-1458D01*
G03X345352Y1476718I150J-132D01*
G01Y1476096D01*
G37*
G36*
G01X639840D02*
G02X639638Y1475894I-202J0D01*
G01X636818D01*
G02X636616Y1476097I1J203D01*
G01Y1476718D01*
G03X636566Y1476850I-200J0D01*
G02Y1479766I1661J1458D01*
G03X636616Y1479898I-150J132D01*
G01Y1481836D01*
G03X636566Y1481968I-200J0D01*
G02Y1484884I1661J1458D01*
G03X636616Y1485016I-150J132D01*
G01Y1485636D01*
G02X636818Y1485838I202J0D01*
G01X639638D01*
G02X639840Y1485635I-1J-203D01*
G01Y1485016D01*
G03X639890Y1484884I200J0D01*
G02Y1481968I-1661J-1458D01*
G03X639840Y1481836I150J-132D01*
G01Y1479898D01*
G03X639890Y1479766I200J0D01*
G02Y1476850I-1661J-1458D01*
G03X639840Y1476718I150J-132D01*
G01Y1476096D01*
G37*
G36*
G01X1139101Y1485838D02*
X1141921D01*
G02X1142124Y1485635I0J-203D01*
G01Y1485014D01*
G03X1142174Y1484882I200J0D01*
G02Y1481970I-1664J-1456D01*
G03X1142124Y1481838I150J-132D01*
G01Y1479896D01*
G03X1142174Y1479764I200J0D01*
G02Y1476852I-1664J-1456D01*
G03X1142124Y1476720I150J-132D01*
G01Y1476097D01*
G02X1141921Y1475894I-203J0D01*
G01X1139101D01*
G02X1138898Y1476097I0J203D01*
G01Y1476720D01*
G03X1138848Y1476852I-200J0D01*
G02Y1479764I1664J1456D01*
G03X1138898Y1479896I-150J132D01*
G01Y1481838D01*
G03X1138848Y1481970I-200J0D01*
G02Y1484882I1664J1456D01*
G03X1138898Y1485014I-150J132D01*
G01Y1485635D01*
G02X1139101Y1485838I203J0D01*
G37*
G36*
G01X1159446Y1476096D02*
G02X1159244Y1475894I-202J0D01*
G01X1156424D01*
G02X1156222Y1476097I1J203D01*
G01Y1476718D01*
G03X1156172Y1476850I-200J0D01*
G02Y1479766I1661J1458D01*
G03X1156222Y1479898I-150J132D01*
G01Y1481836D01*
G03X1156172Y1481968I-200J0D01*
G02Y1484884I1661J1458D01*
G03X1156222Y1485016I-150J132D01*
G01Y1485636D01*
G02X1156424Y1485838I202J0D01*
G01X1159244D01*
G02X1159446Y1485635I-1J-203D01*
G01Y1485016D01*
G03X1159496Y1484884I200J0D01*
G02Y1481968I-1661J-1458D01*
G03X1159446Y1481836I150J-132D01*
G01Y1479898D01*
G03X1159496Y1479766I200J0D01*
G02Y1476850I-1661J-1458D01*
G03X1159446Y1476718I150J-132D01*
G01Y1476096D01*
G37*
G36*
G01X1661808D02*
G02X1661606Y1475894I-202J0D01*
G01X1658786D01*
G02X1658584Y1476097I1J203D01*
G01Y1476718D01*
G03X1658534Y1476850I-200J0D01*
G02Y1479766I1661J1458D01*
G03X1658584Y1479898I-150J132D01*
G01Y1481836D01*
G03X1658534Y1481968I-200J0D01*
G02Y1484884I1661J1458D01*
G03X1658584Y1485016I-150J132D01*
G01Y1485636D01*
G02X1658786Y1485838I202J0D01*
G01X1661606D01*
G02X1661808Y1485635I-1J-203D01*
G01Y1485016D01*
G03X1661858Y1484884I200J0D01*
G02Y1481968I-1661J-1458D01*
G03X1661808Y1481836I150J-132D01*
G01Y1479898D01*
G03X1661858Y1479766I200J0D01*
G02Y1476850I-1661J-1458D01*
G03X1661808Y1476718I150J-132D01*
G01Y1476096D01*
G37*
G36*
G01X1676109Y1485838D02*
X1678929D01*
G02X1679132Y1485635I0J-203D01*
G01Y1485014D01*
G03X1679182Y1484882I200J0D01*
G02Y1481970I-1664J-1456D01*
G03X1679132Y1481838I150J-132D01*
G01Y1479896D01*
G03X1679182Y1479764I200J0D01*
G02Y1476852I-1664J-1456D01*
G03X1679132Y1476720I150J-132D01*
G01Y1476097D01*
G02X1678929Y1475894I-203J0D01*
G01X1676109D01*
G02X1675906Y1476097I0J203D01*
G01Y1476720D01*
G03X1675856Y1476852I-200J0D01*
G02Y1479764I1664J1456D01*
G03X1675906Y1479896I-150J132D01*
G01Y1481838D01*
G03X1675856Y1481970I-200J0D01*
G02Y1484882I1664J1456D01*
G03X1675906Y1485014I-150J132D01*
G01Y1485635D01*
G02X1676109Y1485838I203J0D01*
G37*
G36*
G01X111494Y1487120D02*
G02X111292Y1486918I-202J0D01*
G01X108472D01*
G02X108270Y1487121I1J203D01*
G01Y1487741D01*
G03X108220Y1487873I-200J0D01*
G02Y1490789I1661J1458D01*
G03X108270Y1490921I-150J132D01*
G01Y1492859D01*
G03X108220Y1492991I-200J0D01*
G02Y1495907I1661J1458D01*
G03X108270Y1496039I-150J132D01*
G01Y1496660D01*
G02X108472Y1496862I202J0D01*
G01X111292D01*
G02X111494Y1496659I-1J-203D01*
G01Y1496039D01*
G03X111544Y1495907I200J0D01*
G02Y1492991I-1661J-1458D01*
G03X111494Y1492859I150J-132D01*
G01Y1490921D01*
G03X111544Y1490789I200J0D01*
G02Y1487873I-1661J-1458D01*
G03X111494Y1487741I150J-132D01*
G01Y1487120D01*
G37*
G36*
G01X319368D02*
G02X319166Y1486918I-202J0D01*
G01X316346D01*
G02X316144Y1487121I1J203D01*
G01Y1487741D01*
G03X316094Y1487873I-200J0D01*
G02Y1490789I1661J1458D01*
G03X316144Y1490921I-150J132D01*
G01Y1492859D01*
G03X316094Y1492991I-200J0D01*
G02Y1495907I1661J1458D01*
G03X316144Y1496039I-150J132D01*
G01Y1496660D01*
G02X316346Y1496862I202J0D01*
G01X319166D01*
G02X319368Y1496659I-1J-203D01*
G01Y1496039D01*
G03X319418Y1495907I200J0D01*
G02Y1492991I-1661J-1458D01*
G03X319368Y1492859I150J-132D01*
G01Y1490921D01*
G03X319418Y1490789I200J0D01*
G02Y1487873I-1661J-1458D01*
G03X319368Y1487741I150J-132D01*
G01Y1487120D01*
G37*
G36*
G01X336690D02*
G02X336488Y1486918I-202J0D01*
G01X333668D01*
G02X333466Y1487121I1J203D01*
G01Y1487741D01*
G03X333416Y1487873I-200J0D01*
G02Y1490789I1661J1458D01*
G03X333466Y1490921I-150J132D01*
G01Y1492859D01*
G03X333416Y1492991I-200J0D01*
G02Y1495907I1661J1458D01*
G03X333466Y1496039I-150J132D01*
G01Y1496660D01*
G02X333668Y1496862I202J0D01*
G01X336488D01*
G02X336690Y1496659I-1J-203D01*
G01Y1496039D01*
G03X336740Y1495907I200J0D01*
G02Y1492991I-1661J-1458D01*
G03X336690Y1492859I150J-132D01*
G01Y1490921D01*
G03X336740Y1490789I200J0D01*
G02Y1487873I-1661J-1458D01*
G03X336690Y1487741I150J-132D01*
G01Y1487120D01*
G37*
G36*
G01X628157Y1496862D02*
X630977D01*
G02X631180Y1496659I0J-203D01*
G01Y1496037D01*
G03X631230Y1495905I200J0D01*
G02Y1492993I-1664J-1456D01*
G03X631180Y1492861I150J-132D01*
G01Y1490919D01*
G03X631230Y1490787I200J0D01*
G02Y1487875I-1664J-1456D01*
G03X631180Y1487743I150J-132D01*
G01Y1487121D01*
G02X630977Y1486918I-203J0D01*
G01X628157D01*
G02X627954Y1487121I0J203D01*
G01Y1487743D01*
G03X627904Y1487875I-200J0D01*
G02Y1490787I1664J1456D01*
G03X627954Y1490919I-150J132D01*
G01Y1492861D01*
G03X627904Y1492993I-200J0D01*
G02Y1495905I1664J1456D01*
G03X627954Y1496037I-150J132D01*
G01Y1496659D01*
G02X628157Y1496862I203J0D01*
G37*
G36*
G01X1133462Y1487120D02*
G02X1133260Y1486918I-202J0D01*
G01X1130440D01*
G02X1130238Y1487121I1J203D01*
G01Y1487741D01*
G03X1130188Y1487873I-200J0D01*
G02Y1490789I1661J1458D01*
G03X1130238Y1490921I-150J132D01*
G01Y1492859D01*
G03X1130188Y1492991I-200J0D01*
G02Y1495907I1661J1458D01*
G03X1130238Y1496039I-150J132D01*
G01Y1496660D01*
G02X1130440Y1496862I202J0D01*
G01X1133260D01*
G02X1133462Y1496659I-1J-203D01*
G01Y1496039D01*
G03X1133512Y1495907I200J0D01*
G02Y1492991I-1661J-1458D01*
G03X1133462Y1492859I150J-132D01*
G01Y1490921D01*
G03X1133512Y1490789I200J0D01*
G02Y1487873I-1661J-1458D01*
G03X1133462Y1487741I150J-132D01*
G01Y1487120D01*
G37*
G36*
G01X1147763Y1496862D02*
X1150583D01*
G02X1150786Y1496659I0J-203D01*
G01Y1496037D01*
G03X1150836Y1495905I200J0D01*
G02Y1492993I-1664J-1456D01*
G03X1150786Y1492861I150J-132D01*
G01Y1490919D01*
G03X1150836Y1490787I200J0D01*
G02Y1487875I-1664J-1456D01*
G03X1150786Y1487743I150J-132D01*
G01Y1487121D01*
G02X1150583Y1486918I-203J0D01*
G01X1147763D01*
G02X1147560Y1487121I0J203D01*
G01Y1487743D01*
G03X1147510Y1487875I-200J0D01*
G02Y1490787I1664J1456D01*
G03X1147560Y1490919I-150J132D01*
G01Y1492861D01*
G03X1147510Y1492993I-200J0D01*
G02Y1495905I1664J1456D01*
G03X1147560Y1496037I-150J132D01*
G01Y1496659D01*
G02X1147763Y1496862I203J0D01*
G37*
G36*
G01X1650125D02*
X1652945D01*
G02X1653148Y1496659I0J-203D01*
G01Y1496037D01*
G03X1653198Y1495905I200J0D01*
G02Y1492993I-1664J-1456D01*
G03X1653148Y1492861I150J-132D01*
G01Y1490919D01*
G03X1653198Y1490787I200J0D01*
G02Y1487875I-1664J-1456D01*
G03X1653148Y1487743I150J-132D01*
G01Y1487121D01*
G02X1652945Y1486918I-203J0D01*
G01X1650125D01*
G02X1649922Y1487121I0J203D01*
G01Y1487743D01*
G03X1649872Y1487875I-200J0D01*
G02Y1490787I1664J1456D01*
G03X1649922Y1490919I-150J132D01*
G01Y1492861D01*
G03X1649872Y1492993I-200J0D01*
G02Y1495905I1664J1456D01*
G03X1649922Y1496037I-150J132D01*
G01Y1496659D01*
G02X1650125Y1496862I203J0D01*
G37*
G36*
G01X1670470Y1487120D02*
G02X1670268Y1486918I-202J0D01*
G01X1667448D01*
G02X1667246Y1487121I1J203D01*
G01Y1487741D01*
G03X1667196Y1487873I-200J0D01*
G02Y1490789I1661J1458D01*
G03X1667246Y1490921I-150J132D01*
G01Y1492859D01*
G03X1667196Y1492991I-200J0D01*
G02Y1495907I1661J1458D01*
G03X1667246Y1496039I-150J132D01*
G01Y1496660D01*
G02X1667448Y1496862I202J0D01*
G01X1670268D01*
G02X1670470Y1496659I-1J-203D01*
G01Y1496039D01*
G03X1670520Y1495907I200J0D01*
G02Y1492991I-1661J-1458D01*
G03X1670470Y1492859I150J-132D01*
G01Y1490921D01*
G03X1670520Y1490789I200J0D01*
G02Y1487873I-1661J-1458D01*
G03X1670470Y1487741I150J-132D01*
G01Y1487120D01*
G37*
G36*
G01X117133Y1501192D02*
X119953D01*
G02X120156Y1500989I0J-203D01*
G01Y1500368D01*
G03X120206Y1500236I200J0D01*
G02Y1497324I-1664J-1456D01*
G03X120156Y1497192I150J-132D01*
G01Y1495250D01*
G03X120206Y1495118I200J0D01*
G02Y1492206I-1664J-1456D01*
G03X120156Y1492074I150J-132D01*
G01Y1491451D01*
G02X119953Y1491248I-203J0D01*
G01X117133D01*
G02X116930Y1491451I0J203D01*
G01Y1492074D01*
G03X116880Y1492206I-200J0D01*
G02Y1495118I1664J1456D01*
G03X116930Y1495250I-150J132D01*
G01Y1497192D01*
G03X116880Y1497324I-200J0D01*
G02Y1500236I1664J1456D01*
G03X116930Y1500368I-150J132D01*
G01Y1500989D01*
G02X117133Y1501192I203J0D01*
G37*
G36*
G01X310706Y1491450D02*
G02X310504Y1491248I-202J0D01*
G01X307684D01*
G02X307482Y1491451I1J203D01*
G01Y1492072D01*
G03X307432Y1492204I-200J0D01*
G02Y1495120I1661J1458D01*
G03X307482Y1495252I-150J132D01*
G01Y1497190D01*
G03X307432Y1497322I-200J0D01*
G02Y1500238I1661J1458D01*
G03X307482Y1500370I-150J132D01*
G01Y1500990D01*
G02X307684Y1501192I202J0D01*
G01X310504D01*
G02X310706Y1500989I-1J-203D01*
G01Y1500370D01*
G03X310756Y1500238I200J0D01*
G02Y1497322I-1661J-1458D01*
G03X310706Y1497190I150J-132D01*
G01Y1495252D01*
G03X310756Y1495120I200J0D01*
G02Y1492204I-1661J-1458D01*
G03X310706Y1492072I150J-132D01*
G01Y1491450D01*
G37*
G36*
G01X325007Y1501192D02*
X327827D01*
G02X328030Y1500989I0J-203D01*
G01Y1500368D01*
G03X328080Y1500236I200J0D01*
G02Y1497324I-1664J-1456D01*
G03X328030Y1497192I150J-132D01*
G01Y1495250D01*
G03X328080Y1495118I200J0D01*
G02Y1492206I-1664J-1456D01*
G03X328030Y1492074I150J-132D01*
G01Y1491451D01*
G02X327827Y1491248I-203J0D01*
G01X325007D01*
G02X324804Y1491451I0J203D01*
G01Y1492074D01*
G03X324754Y1492206I-200J0D01*
G02Y1495118I1664J1456D01*
G03X324804Y1495250I-150J132D01*
G01Y1497192D01*
G03X324754Y1497324I-200J0D01*
G02Y1500236I1664J1456D01*
G03X324804Y1500368I-150J132D01*
G01Y1500989D01*
G02X325007Y1501192I203J0D01*
G37*
G36*
G01X345352Y1491450D02*
G02X345150Y1491248I-202J0D01*
G01X342330D01*
G02X342128Y1491451I1J203D01*
G01Y1492072D01*
G03X342078Y1492204I-200J0D01*
G02Y1495120I1661J1458D01*
G03X342128Y1495252I-150J132D01*
G01Y1497190D01*
G03X342078Y1497322I-200J0D01*
G02Y1500238I1661J1458D01*
G03X342128Y1500370I-150J132D01*
G01Y1500990D01*
G02X342330Y1501192I202J0D01*
G01X345150D01*
G02X345352Y1500989I-1J-203D01*
G01Y1500370D01*
G03X345402Y1500238I200J0D01*
G02Y1497322I-1661J-1458D01*
G03X345352Y1497190I150J-132D01*
G01Y1495252D01*
G03X345402Y1495120I200J0D01*
G02Y1492204I-1661J-1458D01*
G03X345352Y1492072I150J-132D01*
G01Y1491450D01*
G37*
G36*
G01X639840D02*
G02X639638Y1491248I-202J0D01*
G01X636818D01*
G02X636616Y1491451I1J203D01*
G01Y1492072D01*
G03X636566Y1492204I-200J0D01*
G02Y1495120I1661J1458D01*
G03X636616Y1495252I-150J132D01*
G01Y1497190D01*
G03X636566Y1497322I-200J0D01*
G02Y1500238I1661J1458D01*
G03X636616Y1500370I-150J132D01*
G01Y1500990D01*
G02X636818Y1501192I202J0D01*
G01X639638D01*
G02X639840Y1500989I-1J-203D01*
G01Y1500370D01*
G03X639890Y1500238I200J0D01*
G02Y1497322I-1661J-1458D01*
G03X639840Y1497190I150J-132D01*
G01Y1495252D01*
G03X639890Y1495120I200J0D01*
G02Y1492204I-1661J-1458D01*
G03X639840Y1492072I150J-132D01*
G01Y1491450D01*
G37*
G36*
G01X1139101Y1501192D02*
X1141921D01*
G02X1142124Y1500989I0J-203D01*
G01Y1500368D01*
G03X1142174Y1500236I200J0D01*
G02Y1497324I-1664J-1456D01*
G03X1142124Y1497192I150J-132D01*
G01Y1495250D01*
G03X1142174Y1495118I200J0D01*
G02Y1492206I-1664J-1456D01*
G03X1142124Y1492074I150J-132D01*
G01Y1491451D01*
G02X1141921Y1491248I-203J0D01*
G01X1139101D01*
G02X1138898Y1491451I0J203D01*
G01Y1492074D01*
G03X1138848Y1492206I-200J0D01*
G02Y1495118I1664J1456D01*
G03X1138898Y1495250I-150J132D01*
G01Y1497192D01*
G03X1138848Y1497324I-200J0D01*
G02Y1500236I1664J1456D01*
G03X1138898Y1500368I-150J132D01*
G01Y1500989D01*
G02X1139101Y1501192I203J0D01*
G37*
G36*
G01X1159446Y1491450D02*
G02X1159244Y1491248I-202J0D01*
G01X1156424D01*
G02X1156222Y1491451I1J203D01*
G01Y1492072D01*
G03X1156172Y1492204I-200J0D01*
G02Y1495120I1661J1458D01*
G03X1156222Y1495252I-150J132D01*
G01Y1497190D01*
G03X1156172Y1497322I-200J0D01*
G02Y1500238I1661J1458D01*
G03X1156222Y1500370I-150J132D01*
G01Y1500990D01*
G02X1156424Y1501192I202J0D01*
G01X1159244D01*
G02X1159446Y1500989I-1J-203D01*
G01Y1500370D01*
G03X1159496Y1500238I200J0D01*
G02Y1497322I-1661J-1458D01*
G03X1159446Y1497190I150J-132D01*
G01Y1495252D01*
G03X1159496Y1495120I200J0D01*
G02Y1492204I-1661J-1458D01*
G03X1159446Y1492072I150J-132D01*
G01Y1491450D01*
G37*
G36*
G01X1661808D02*
G02X1661606Y1491248I-202J0D01*
G01X1658786D01*
G02X1658584Y1491451I1J203D01*
G01Y1492072D01*
G03X1658534Y1492204I-200J0D01*
G02Y1495120I1661J1458D01*
G03X1658584Y1495252I-150J132D01*
G01Y1497190D01*
G03X1658534Y1497322I-200J0D01*
G02Y1500238I1661J1458D01*
G03X1658584Y1500370I-150J132D01*
G01Y1500990D01*
G02X1658786Y1501192I202J0D01*
G01X1661606D01*
G02X1661808Y1500989I-1J-203D01*
G01Y1500370D01*
G03X1661858Y1500238I200J0D01*
G02Y1497322I-1661J-1458D01*
G03X1661808Y1497190I150J-132D01*
G01Y1495252D01*
G03X1661858Y1495120I200J0D01*
G02Y1492204I-1661J-1458D01*
G03X1661808Y1492072I150J-132D01*
G01Y1491450D01*
G37*
G36*
G01X1676109Y1501192D02*
X1678929D01*
G02X1679132Y1500989I0J-203D01*
G01Y1500368D01*
G03X1679182Y1500236I200J0D01*
G02Y1497324I-1664J-1456D01*
G03X1679132Y1497192I150J-132D01*
G01Y1495250D01*
G03X1679182Y1495118I200J0D01*
G02Y1492206I-1664J-1456D01*
G03X1679132Y1492074I150J-132D01*
G01Y1491451D01*
G02X1678929Y1491248I-203J0D01*
G01X1676109D01*
G02X1675906Y1491451I0J203D01*
G01Y1492074D01*
G03X1675856Y1492206I-200J0D01*
G02Y1495118I1664J1456D01*
G03X1675906Y1495250I-150J132D01*
G01Y1497192D01*
G03X1675856Y1497324I-200J0D01*
G02Y1500236I1664J1456D01*
G03X1675906Y1500368I-150J132D01*
G01Y1500989D01*
G02X1676109Y1501192I203J0D01*
G37*
G36*
G01X108472Y1512216D02*
X111292D01*
G02X111494Y1512014I0J-202D01*
G01Y1511394D01*
G03X111544Y1511262I200J0D01*
G02Y1508346I-1661J-1458D01*
G03X111494Y1508214I150J-132D01*
G01Y1506275D01*
G03X111544Y1506143I200J0D01*
G02Y1503227I-1661J-1458D01*
G03X111494Y1503095I150J-132D01*
G01Y1502476D01*
G02X111292Y1502274I-202J0D01*
G01X108472D01*
G02X108270Y1502476I0J202D01*
G01Y1503095D01*
G03X108220Y1503227I-200J0D01*
G02Y1506143I1661J1458D01*
G03X108270Y1506275I-150J132D01*
G01Y1508214D01*
G03X108220Y1508346I-200J0D01*
G02Y1511262I1661J1458D01*
G03X108270Y1511394I-150J132D01*
G01Y1512014D01*
G02X108472Y1512216I202J0D01*
G37*
G36*
G01X316346D02*
X319166D01*
G02X319368Y1512014I0J-202D01*
G01Y1511394D01*
G03X319418Y1511262I200J0D01*
G02Y1508346I-1661J-1458D01*
G03X319368Y1508214I150J-132D01*
G01Y1506275D01*
G03X319418Y1506143I200J0D01*
G02Y1503227I-1661J-1458D01*
G03X319368Y1503095I150J-132D01*
G01Y1502476D01*
G02X319166Y1502274I-202J0D01*
G01X316346D01*
G02X316144Y1502476I0J202D01*
G01Y1503095D01*
G03X316094Y1503227I-200J0D01*
G02Y1506143I1661J1458D01*
G03X316144Y1506275I-150J132D01*
G01Y1508214D01*
G03X316094Y1508346I-200J0D01*
G02Y1511262I1661J1458D01*
G03X316144Y1511394I-150J132D01*
G01Y1512014D01*
G02X316346Y1512216I202J0D01*
G37*
G36*
G01X333668D02*
X336488D01*
G02X336690Y1512014I0J-202D01*
G01Y1511394D01*
G03X336740Y1511262I200J0D01*
G02Y1508346I-1661J-1458D01*
G03X336690Y1508214I150J-132D01*
G01Y1506275D01*
G03X336740Y1506143I200J0D01*
G02Y1503227I-1661J-1458D01*
G03X336690Y1503095I150J-132D01*
G01Y1502476D01*
G02X336488Y1502274I-202J0D01*
G01X333668D01*
G02X333466Y1502476I0J202D01*
G01Y1503095D01*
G03X333416Y1503227I-200J0D01*
G02Y1506143I1661J1458D01*
G03X333466Y1506275I-150J132D01*
G01Y1508214D01*
G03X333416Y1508346I-200J0D01*
G02Y1511262I1661J1458D01*
G03X333466Y1511394I-150J132D01*
G01Y1512014D01*
G02X333668Y1512216I202J0D01*
G37*
G36*
G01X1130440D02*
X1133260D01*
G02X1133462Y1512014I0J-202D01*
G01Y1511394D01*
G03X1133512Y1511262I200J0D01*
G02Y1508346I-1661J-1458D01*
G03X1133462Y1508214I150J-132D01*
G01Y1506275D01*
G03X1133512Y1506143I200J0D01*
G02Y1503227I-1661J-1458D01*
G03X1133462Y1503095I150J-132D01*
G01Y1502476D01*
G02X1133260Y1502274I-202J0D01*
G01X1130440D01*
G02X1130238Y1502476I0J202D01*
G01Y1503095D01*
G03X1130188Y1503227I-200J0D01*
G02Y1506143I1661J1458D01*
G03X1130238Y1506275I-150J132D01*
G01Y1508214D01*
G03X1130188Y1508346I-200J0D01*
G02Y1511262I1661J1458D01*
G03X1130238Y1511394I-150J132D01*
G01Y1512014D01*
G02X1130440Y1512216I202J0D01*
G37*
G36*
G01X1667448D02*
X1670268D01*
G02X1670470Y1512014I0J-202D01*
G01Y1511394D01*
G03X1670520Y1511262I200J0D01*
G02Y1508346I-1661J-1458D01*
G03X1670470Y1508214I150J-132D01*
G01Y1506275D01*
G03X1670520Y1506143I200J0D01*
G02Y1503227I-1661J-1458D01*
G03X1670470Y1503095I150J-132D01*
G01Y1502476D01*
G02X1670268Y1502274I-202J0D01*
G01X1667448D01*
G02X1667246Y1502476I0J202D01*
G01Y1503095D01*
G03X1667196Y1503227I-200J0D01*
G02Y1506143I1661J1458D01*
G03X1667246Y1506275I-150J132D01*
G01Y1508214D01*
G03X1667196Y1508346I-200J0D01*
G02Y1511262I1661J1458D01*
G03X1667246Y1511394I-150J132D01*
G01Y1512014D01*
G02X1667448Y1512216I202J0D01*
G37*
G36*
G01X628156Y1502274D02*
G02X627954Y1502476I0J202D01*
G01Y1503097D01*
G03X627904Y1503229I-200J0D01*
G02Y1506141I1664J1456D01*
G03X627954Y1506273I-150J132D01*
G01Y1508216D01*
G03X627904Y1508348I-200J0D01*
G02Y1511260I1664J1456D01*
G03X627954Y1511392I-150J132D01*
G01Y1512014D01*
G02X628157Y1512216I203J-1D01*
G01X630978D01*
G02X631180Y1512014I0J-202D01*
G01Y1511392D01*
G03X631230Y1511260I200J0D01*
G02Y1508348I-1664J-1456D01*
G03X631180Y1508216I150J-132D01*
G01Y1506273D01*
G03X631230Y1506141I200J0D01*
G02Y1503229I-1664J-1456D01*
G03X631180Y1503097I150J-132D01*
G01Y1502476D01*
G02X630977Y1502274I-203J1D01*
G01X628156D01*
G37*
G36*
G01X1147762D02*
G02X1147560Y1502476I0J202D01*
G01Y1503097D01*
G03X1147510Y1503229I-200J0D01*
G02Y1506141I1664J1456D01*
G03X1147560Y1506273I-150J132D01*
G01Y1508216D01*
G03X1147510Y1508348I-200J0D01*
G02Y1511260I1664J1456D01*
G03X1147560Y1511392I-150J132D01*
G01Y1512014D01*
G02X1147763Y1512216I203J-1D01*
G01X1150584D01*
G02X1150786Y1512014I0J-202D01*
G01Y1511392D01*
G03X1150836Y1511260I200J0D01*
G02Y1508348I-1664J-1456D01*
G03X1150786Y1508216I150J-132D01*
G01Y1506273D01*
G03X1150836Y1506141I200J0D01*
G02Y1503229I-1664J-1456D01*
G03X1150786Y1503097I150J-132D01*
G01Y1502476D01*
G02X1150583Y1502274I-203J1D01*
G01X1147762D01*
G37*
G36*
G01X1650124D02*
G02X1649922Y1502476I0J202D01*
G01Y1503097D01*
G03X1649872Y1503229I-200J0D01*
G02Y1506141I1664J1456D01*
G03X1649922Y1506273I-150J132D01*
G01Y1508216D01*
G03X1649872Y1508348I-200J0D01*
G02Y1511260I1664J1456D01*
G03X1649922Y1511392I-150J132D01*
G01Y1512014D01*
G02X1650125Y1512216I203J-1D01*
G01X1652946D01*
G02X1653148Y1512014I0J-202D01*
G01Y1511392D01*
G03X1653198Y1511260I200J0D01*
G02Y1508348I-1664J-1456D01*
G03X1653148Y1508216I150J-132D01*
G01Y1506273D01*
G03X1653198Y1506141I200J0D01*
G02Y1503229I-1664J-1456D01*
G03X1653148Y1503097I150J-132D01*
G01Y1502476D01*
G02X1652945Y1502274I-203J1D01*
G01X1650124D01*
G37*
G36*
G01X307684Y1516546D02*
X310504D01*
G02X310706Y1516344I0J-202D01*
G01Y1515724D01*
G03X310756Y1515592I200J0D01*
G02Y1512676I-1661J-1458D01*
G03X310706Y1512544I150J-132D01*
G01Y1510606D01*
G03X310756Y1510474I200J0D01*
G02Y1507558I-1661J-1458D01*
G03X310706Y1507426I150J-132D01*
G01Y1506806D01*
G02X310504Y1506604I-202J0D01*
G01X307684D01*
G02X307482Y1506806I0J202D01*
G01Y1507426D01*
G03X307432Y1507558I-200J0D01*
G02Y1510474I1661J1458D01*
G03X307482Y1510606I-150J132D01*
G01Y1512544D01*
G03X307432Y1512676I-200J0D01*
G02Y1515592I1661J1458D01*
G03X307482Y1515724I-150J132D01*
G01Y1516344D01*
G02X307684Y1516546I202J0D01*
G37*
G36*
G01X342330D02*
X345150D01*
G02X345352Y1516344I0J-202D01*
G01Y1515724D01*
G03X345402Y1515592I200J0D01*
G02Y1512676I-1661J-1458D01*
G03X345352Y1512544I150J-132D01*
G01Y1510606D01*
G03X345402Y1510474I200J0D01*
G02Y1507558I-1661J-1458D01*
G03X345352Y1507426I150J-132D01*
G01Y1506806D01*
G02X345150Y1506604I-202J0D01*
G01X342330D01*
G02X342128Y1506806I0J202D01*
G01Y1507426D01*
G03X342078Y1507558I-200J0D01*
G02Y1510474I1661J1458D01*
G03X342128Y1510606I-150J132D01*
G01Y1512544D01*
G03X342078Y1512676I-200J0D01*
G02Y1515592I1661J1458D01*
G03X342128Y1515724I-150J132D01*
G01Y1516344D01*
G02X342330Y1516546I202J0D01*
G37*
G36*
G01X636818D02*
X639638D01*
G02X639840Y1516344I0J-202D01*
G01Y1515724D01*
G03X639890Y1515592I200J0D01*
G02Y1512676I-1661J-1458D01*
G03X639840Y1512544I150J-132D01*
G01Y1510606D01*
G03X639890Y1510474I200J0D01*
G02Y1507558I-1661J-1458D01*
G03X639840Y1507426I150J-132D01*
G01Y1506806D01*
G02X639638Y1506604I-202J0D01*
G01X636818D01*
G02X636616Y1506806I0J202D01*
G01Y1507426D01*
G03X636566Y1507558I-200J0D01*
G02Y1510474I1661J1458D01*
G03X636616Y1510606I-150J132D01*
G01Y1512544D01*
G03X636566Y1512676I-200J0D01*
G02Y1515592I1661J1458D01*
G03X636616Y1515724I-150J132D01*
G01Y1516344D01*
G02X636818Y1516546I202J0D01*
G37*
G36*
G01X1156424D02*
X1159244D01*
G02X1159446Y1516344I0J-202D01*
G01Y1515724D01*
G03X1159496Y1515592I200J0D01*
G02Y1512676I-1661J-1458D01*
G03X1159446Y1512544I150J-132D01*
G01Y1510606D01*
G03X1159496Y1510474I200J0D01*
G02Y1507558I-1661J-1458D01*
G03X1159446Y1507426I150J-132D01*
G01Y1506806D01*
G02X1159244Y1506604I-202J0D01*
G01X1156424D01*
G02X1156222Y1506806I0J202D01*
G01Y1507426D01*
G03X1156172Y1507558I-200J0D01*
G02Y1510474I1661J1458D01*
G03X1156222Y1510606I-150J132D01*
G01Y1512544D01*
G03X1156172Y1512676I-200J0D01*
G02Y1515592I1661J1458D01*
G03X1156222Y1515724I-150J132D01*
G01Y1516344D01*
G02X1156424Y1516546I202J0D01*
G37*
G36*
G01X1658786D02*
X1661606D01*
G02X1661808Y1516344I0J-202D01*
G01Y1515724D01*
G03X1661858Y1515592I200J0D01*
G02Y1512676I-1661J-1458D01*
G03X1661808Y1512544I150J-132D01*
G01Y1510606D01*
G03X1661858Y1510474I200J0D01*
G02Y1507558I-1661J-1458D01*
G03X1661808Y1507426I150J-132D01*
G01Y1506806D01*
G02X1661606Y1506604I-202J0D01*
G01X1658786D01*
G02X1658584Y1506806I0J202D01*
G01Y1507426D01*
G03X1658534Y1507558I-200J0D01*
G02Y1510474I1661J1458D01*
G03X1658584Y1510606I-150J132D01*
G01Y1512544D01*
G03X1658534Y1512676I-200J0D01*
G02Y1515592I1661J1458D01*
G03X1658584Y1515724I-150J132D01*
G01Y1516344D01*
G02X1658786Y1516546I202J0D01*
G37*
G36*
G01X117132Y1506604D02*
G02X116930Y1506806I0J202D01*
G01Y1507428D01*
G03X116880Y1507560I-200J0D01*
G02Y1510472I1664J1456D01*
G03X116930Y1510604I-150J132D01*
G01Y1512546D01*
G03X116880Y1512678I-200J0D01*
G02Y1515590I1664J1456D01*
G03X116930Y1515722I-150J132D01*
G01Y1516344D01*
G02X117133Y1516546I203J-1D01*
G01X119954D01*
G02X120156Y1516344I0J-202D01*
G01Y1515722D01*
G03X120206Y1515590I200J0D01*
G02Y1512678I-1664J-1456D01*
G03X120156Y1512546I150J-132D01*
G01Y1510604D01*
G03X120206Y1510472I200J0D01*
G02Y1507560I-1664J-1456D01*
G03X120156Y1507428I150J-132D01*
G01Y1506806D01*
G02X119953Y1506604I-203J1D01*
G01X117132D01*
G37*
G36*
G01X325006D02*
G02X324804Y1506806I0J202D01*
G01Y1507428D01*
G03X324754Y1507560I-200J0D01*
G02Y1510472I1664J1456D01*
G03X324804Y1510604I-150J132D01*
G01Y1512546D01*
G03X324754Y1512678I-200J0D01*
G02Y1515590I1664J1456D01*
G03X324804Y1515722I-150J132D01*
G01Y1516344D01*
G02X325007Y1516546I203J-1D01*
G01X327828D01*
G02X328030Y1516344I0J-202D01*
G01Y1515722D01*
G03X328080Y1515590I200J0D01*
G02Y1512678I-1664J-1456D01*
G03X328030Y1512546I150J-132D01*
G01Y1510604D01*
G03X328080Y1510472I200J0D01*
G02Y1507560I-1664J-1456D01*
G03X328030Y1507428I150J-132D01*
G01Y1506806D01*
G02X327827Y1506604I-203J1D01*
G01X325006D01*
G37*
G36*
G01X1139100D02*
G02X1138898Y1506806I0J202D01*
G01Y1507428D01*
G03X1138848Y1507560I-200J0D01*
G02Y1510472I1664J1456D01*
G03X1138898Y1510604I-150J132D01*
G01Y1512546D01*
G03X1138848Y1512678I-200J0D01*
G02Y1515590I1664J1456D01*
G03X1138898Y1515722I-150J132D01*
G01Y1516344D01*
G02X1139101Y1516546I203J-1D01*
G01X1141922D01*
G02X1142124Y1516344I0J-202D01*
G01Y1515722D01*
G03X1142174Y1515590I200J0D01*
G02Y1512678I-1664J-1456D01*
G03X1142124Y1512546I150J-132D01*
G01Y1510604D01*
G03X1142174Y1510472I200J0D01*
G02Y1507560I-1664J-1456D01*
G03X1142124Y1507428I150J-132D01*
G01Y1506806D01*
G02X1141921Y1506604I-203J1D01*
G01X1139100D01*
G37*
G36*
G01X1676108D02*
G02X1675906Y1506806I0J202D01*
G01Y1507428D01*
G03X1675856Y1507560I-200J0D01*
G02Y1510472I1664J1456D01*
G03X1675906Y1510604I-150J132D01*
G01Y1512546D01*
G03X1675856Y1512678I-200J0D01*
G02Y1515590I1664J1456D01*
G03X1675906Y1515722I-150J132D01*
G01Y1516344D01*
G02X1676109Y1516546I203J-1D01*
G01X1678930D01*
G02X1679132Y1516344I0J-202D01*
G01Y1515722D01*
G03X1679182Y1515590I200J0D01*
G02Y1512678I-1664J-1456D01*
G03X1679132Y1512546I150J-132D01*
G01Y1510604D01*
G03X1679182Y1510472I200J0D01*
G02Y1507560I-1664J-1456D01*
G03X1679132Y1507428I150J-132D01*
G01Y1506806D01*
G02X1678929Y1506604I-203J1D01*
G01X1676108D01*
G37*
G36*
G01X454929Y1568516D02*
X457749D01*
G02X457952Y1568313I0J-203D01*
G01Y1567691D01*
G03X458002Y1567559I200J0D01*
G02Y1564647I-1664J-1456D01*
G03X457952Y1564515I150J-132D01*
G01Y1562573D01*
G03X458002Y1562441I200J0D01*
G02Y1559529I-1664J-1456D01*
G03X457952Y1559397I150J-132D01*
G01Y1558775D01*
G02X457749Y1558572I-203J0D01*
G01X454929D01*
G02X454726Y1558775I0J203D01*
G01Y1559397D01*
G03X454676Y1559529I-200J0D01*
G02Y1562441I1664J1456D01*
G03X454726Y1562573I-150J132D01*
G01Y1564515D01*
G03X454676Y1564647I-200J0D01*
G02Y1567559I1664J1456D01*
G03X454726Y1567691I-150J132D01*
G01Y1568313D01*
G02X454929Y1568516I203J0D01*
G37*
G36*
G01X475274Y1558774D02*
G02X475072Y1558572I-202J0D01*
G01X472252D01*
G02X472050Y1558775I1J203D01*
G01Y1559395D01*
G03X472000Y1559527I-200J0D01*
G02Y1562443I1661J1458D01*
G03X472050Y1562575I-150J132D01*
G01Y1564513D01*
G03X472000Y1564645I-200J0D01*
G02Y1567561I1661J1458D01*
G03X472050Y1567693I-150J132D01*
G01Y1568314D01*
G02X472252Y1568516I202J0D01*
G01X475072D01*
G02X475274Y1568313I-1J-203D01*
G01Y1567693D01*
G03X475324Y1567561I200J0D01*
G02Y1564645I-1661J-1458D01*
G03X475274Y1564513I150J-132D01*
G01Y1562575D01*
G03X475324Y1562443I200J0D01*
G02Y1559527I-1661J-1458D01*
G03X475274Y1559395I150J-132D01*
G01Y1558774D01*
G37*
G36*
G01X489575Y1568516D02*
X492395D01*
G02X492598Y1568313I0J-203D01*
G01Y1567691D01*
G03X492648Y1567559I200J0D01*
G02Y1564647I-1664J-1456D01*
G03X492598Y1564515I150J-132D01*
G01Y1562573D01*
G03X492648Y1562441I200J0D01*
G02Y1559529I-1664J-1456D01*
G03X492598Y1559397I150J-132D01*
G01Y1558775D01*
G02X492395Y1558572I-203J0D01*
G01X489575D01*
G02X489372Y1558775I0J203D01*
G01Y1559397D01*
G03X489322Y1559529I-200J0D01*
G02Y1562441I1664J1456D01*
G03X489372Y1562573I-150J132D01*
G01Y1564515D01*
G03X489322Y1564647I-200J0D01*
G02Y1567559I1664J1456D01*
G03X489372Y1567691I-150J132D01*
G01Y1568313D01*
G02X489575Y1568516I203J0D01*
G37*
G36*
G01X506897D02*
X509717D01*
G02X509920Y1568313I0J-203D01*
G01Y1567691D01*
G03X509970Y1567559I200J0D01*
G02Y1564647I-1664J-1456D01*
G03X509920Y1564515I150J-132D01*
G01Y1562573D01*
G03X509970Y1562441I200J0D01*
G02Y1559529I-1664J-1456D01*
G03X509920Y1559397I150J-132D01*
G01Y1558775D01*
G02X509717Y1558572I-203J0D01*
G01X506897D01*
G02X506694Y1558775I0J203D01*
G01Y1559397D01*
G03X506644Y1559529I-200J0D01*
G02Y1562441I1664J1456D01*
G03X506694Y1562573I-150J132D01*
G01Y1564515D01*
G03X506644Y1564647I-200J0D01*
G02Y1567559I1664J1456D01*
G03X506694Y1567691I-150J132D01*
G01Y1568313D01*
G02X506897Y1568516I203J0D01*
G37*
G36*
G01X1497242Y1558774D02*
G02X1497040Y1558572I-202J0D01*
G01X1494220D01*
G02X1494018Y1558775I1J203D01*
G01Y1559395D01*
G03X1493968Y1559527I-200J0D01*
G02Y1562443I1661J1458D01*
G03X1494018Y1562575I-150J132D01*
G01Y1564513D01*
G03X1493968Y1564645I-200J0D01*
G02Y1567561I1661J1458D01*
G03X1494018Y1567693I-150J132D01*
G01Y1568314D01*
G02X1494220Y1568516I202J0D01*
G01X1497040D01*
G02X1497242Y1568313I-1J-203D01*
G01Y1567693D01*
G03X1497292Y1567561I200J0D01*
G02Y1564645I-1661J-1458D01*
G03X1497242Y1564513I150J-132D01*
G01Y1562575D01*
G03X1497292Y1562443I200J0D01*
G02Y1559527I-1661J-1458D01*
G03X1497242Y1559395I150J-132D01*
G01Y1558774D01*
G37*
G36*
G01X1511543Y1568516D02*
X1514363D01*
G02X1514566Y1568313I0J-203D01*
G01Y1567691D01*
G03X1514616Y1567559I200J0D01*
G02Y1564647I-1664J-1456D01*
G03X1514566Y1564515I150J-132D01*
G01Y1562573D01*
G03X1514616Y1562441I200J0D01*
G02Y1559529I-1664J-1456D01*
G03X1514566Y1559397I150J-132D01*
G01Y1558775D01*
G02X1514363Y1558572I-203J0D01*
G01X1511543D01*
G02X1511340Y1558775I0J203D01*
G01Y1559397D01*
G03X1511290Y1559529I-200J0D01*
G02Y1562441I1664J1456D01*
G03X1511340Y1562573I-150J132D01*
G01Y1564515D01*
G03X1511290Y1564647I-200J0D01*
G02Y1567559I1664J1456D01*
G03X1511340Y1567691I-150J132D01*
G01Y1568313D01*
G02X1511543Y1568516I203J0D01*
G37*
G36*
G01X1528865D02*
X1531685D01*
G02X1531888Y1568313I0J-203D01*
G01Y1567691D01*
G03X1531938Y1567559I200J0D01*
G02Y1564647I-1664J-1456D01*
G03X1531888Y1564515I150J-132D01*
G01Y1562573D01*
G03X1531938Y1562441I200J0D01*
G02Y1559529I-1664J-1456D01*
G03X1531888Y1559397I150J-132D01*
G01Y1558775D01*
G02X1531685Y1558572I-203J0D01*
G01X1528865D01*
G02X1528662Y1558775I0J203D01*
G01Y1559397D01*
G03X1528612Y1559529I-200J0D01*
G02Y1562441I1664J1456D01*
G03X1528662Y1562573I-150J132D01*
G01Y1564515D01*
G03X1528612Y1564647I-200J0D01*
G02Y1567559I1664J1456D01*
G03X1528662Y1567691I-150J132D01*
G01Y1568313D01*
G02X1528865Y1568516I203J0D01*
G37*
G36*
G01X463590Y1572846D02*
X466410D01*
G02X466612Y1572644I0J-202D01*
G01Y1572024D01*
G03X466662Y1571892I200J0D01*
G02Y1568976I-1661J-1458D01*
G03X466612Y1568844I150J-132D01*
G01Y1566905D01*
G03X466662Y1566773I200J0D01*
G02Y1563857I-1661J-1458D01*
G03X466612Y1563725I150J-132D01*
G01Y1563106D01*
G02X466410Y1562904I-202J0D01*
G01X463590D01*
G02X463388Y1563106I0J202D01*
G01Y1563725D01*
G03X463338Y1563857I-200J0D01*
G02Y1566773I1661J1458D01*
G03X463388Y1566905I-150J132D01*
G01Y1568844D01*
G03X463338Y1568976I-200J0D01*
G02Y1571892I1661J1458D01*
G03X463388Y1572024I-150J132D01*
G01Y1572644D01*
G02X463590Y1572846I202J0D01*
G37*
G36*
G01X498236D02*
X501056D01*
G02X501258Y1572644I0J-202D01*
G01Y1572024D01*
G03X501308Y1571892I200J0D01*
G02Y1568976I-1661J-1458D01*
G03X501258Y1568844I150J-132D01*
G01Y1566905D01*
G03X501308Y1566773I200J0D01*
G02Y1563857I-1661J-1458D01*
G03X501258Y1563725I150J-132D01*
G01Y1563106D01*
G02X501056Y1562904I-202J0D01*
G01X498236D01*
G02X498034Y1563106I0J202D01*
G01Y1563725D01*
G03X497984Y1563857I-200J0D01*
G02Y1566773I1661J1458D01*
G03X498034Y1566905I-150J132D01*
G01Y1568844D01*
G03X497984Y1568976I-200J0D01*
G02Y1571892I1661J1458D01*
G03X498034Y1572024I-150J132D01*
G01Y1572644D01*
G02X498236Y1572846I202J0D01*
G37*
G36*
G01X1485558D02*
X1488378D01*
G02X1488580Y1572644I0J-202D01*
G01Y1572024D01*
G03X1488630Y1571892I200J0D01*
G02Y1568976I-1661J-1458D01*
G03X1488580Y1568844I150J-132D01*
G01Y1566905D01*
G03X1488630Y1566773I200J0D01*
G02Y1563857I-1661J-1458D01*
G03X1488580Y1563725I150J-132D01*
G01Y1563106D01*
G02X1488378Y1562904I-202J0D01*
G01X1485558D01*
G02X1485356Y1563106I0J202D01*
G01Y1563725D01*
G03X1485306Y1563857I-200J0D01*
G02Y1566773I1661J1458D01*
G03X1485356Y1566905I-150J132D01*
G01Y1568844D01*
G03X1485306Y1568976I-200J0D01*
G02Y1571892I1661J1458D01*
G03X1485356Y1572024I-150J132D01*
G01Y1572644D01*
G02X1485558Y1572846I202J0D01*
G37*
G36*
G01X1520204D02*
X1523024D01*
G02X1523226Y1572644I0J-202D01*
G01Y1572024D01*
G03X1523276Y1571892I200J0D01*
G02Y1568976I-1661J-1458D01*
G03X1523226Y1568844I150J-132D01*
G01Y1566905D01*
G03X1523276Y1566773I200J0D01*
G02Y1563857I-1661J-1458D01*
G03X1523226Y1563725I150J-132D01*
G01Y1563106D01*
G02X1523024Y1562904I-202J0D01*
G01X1520204D01*
G02X1520002Y1563106I0J202D01*
G01Y1563725D01*
G03X1519952Y1563857I-200J0D01*
G02Y1566773I1661J1458D01*
G03X1520002Y1566905I-150J132D01*
G01Y1568844D01*
G03X1519952Y1568976I-200J0D01*
G02Y1571892I1661J1458D01*
G03X1520002Y1572024I-150J132D01*
G01Y1572644D01*
G02X1520204Y1572846I202J0D01*
G37*
G36*
G01X480912Y1562904D02*
G02X480710Y1563106I0J202D01*
G01Y1563727D01*
G03X480660Y1563859I-200J0D01*
G02Y1566771I1664J1456D01*
G03X480710Y1566903I-150J132D01*
G01Y1568846D01*
G03X480660Y1568978I-200J0D01*
G02Y1571890I1664J1456D01*
G03X480710Y1572022I-150J132D01*
G01Y1572644D01*
G02X480913Y1572846I203J-1D01*
G01X483734D01*
G02X483936Y1572644I0J-202D01*
G01Y1572022D01*
G03X483986Y1571890I200J0D01*
G02Y1568978I-1664J-1456D01*
G03X483936Y1568846I150J-132D01*
G01Y1566903D01*
G03X483986Y1566771I200J0D01*
G02Y1563859I-1664J-1456D01*
G03X483936Y1563727I150J-132D01*
G01Y1563106D01*
G02X483733Y1562904I-203J1D01*
G01X480912D01*
G37*
G36*
G01X1502880D02*
G02X1502678Y1563106I0J202D01*
G01Y1563727D01*
G03X1502628Y1563859I-200J0D01*
G02Y1566771I1664J1456D01*
G03X1502678Y1566903I-150J132D01*
G01Y1568846D01*
G03X1502628Y1568978I-200J0D01*
G02Y1571890I1664J1456D01*
G03X1502678Y1572022I-150J132D01*
G01Y1572644D01*
G02X1502881Y1572846I203J-1D01*
G01X1505702D01*
G02X1505904Y1572644I0J-202D01*
G01Y1572022D01*
G03X1505954Y1571890I200J0D01*
G02Y1568978I-1664J-1456D01*
G03X1505904Y1568846I150J-132D01*
G01Y1566903D01*
G03X1505954Y1566771I200J0D01*
G02Y1563859I-1664J-1456D01*
G03X1505904Y1563727I150J-132D01*
G01Y1563106D01*
G02X1505701Y1562904I-203J1D01*
G01X1502880D01*
G37*
G36*
G01X1537526D02*
G02X1537324Y1563106I0J202D01*
G01Y1563727D01*
G03X1537274Y1563859I-200J0D01*
G02Y1566771I1664J1456D01*
G03X1537324Y1566903I-150J132D01*
G01Y1568846D01*
G03X1537274Y1568978I-200J0D01*
G02Y1571890I1664J1456D01*
G03X1537324Y1572022I-150J132D01*
G01Y1572644D01*
G02X1537527Y1572846I203J-1D01*
G01X1540348D01*
G02X1540550Y1572644I0J-202D01*
G01Y1572022D01*
G03X1540600Y1571890I200J0D01*
G02Y1568978I-1664J-1456D01*
G03X1540550Y1568846I150J-132D01*
G01Y1566903D01*
G03X1540600Y1566771I200J0D01*
G02Y1563859I-1664J-1456D01*
G03X1540550Y1563727I150J-132D01*
G01Y1563106D01*
G02X1540347Y1562904I-203J1D01*
G01X1537526D01*
G37*
G36*
G01X454929Y1583870D02*
X457749D01*
G02X457952Y1583667I0J-203D01*
G01Y1583045D01*
G03X458002Y1582913I200J0D01*
G02Y1580001I-1664J-1456D01*
G03X457952Y1579869I150J-132D01*
G01Y1577927D01*
G03X458002Y1577795I200J0D01*
G02Y1574883I-1664J-1456D01*
G03X457952Y1574751I150J-132D01*
G01Y1574129D01*
G02X457749Y1573926I-203J0D01*
G01X454929D01*
G02X454726Y1574129I0J203D01*
G01Y1574751D01*
G03X454676Y1574883I-200J0D01*
G02Y1577795I1664J1456D01*
G03X454726Y1577927I-150J132D01*
G01Y1579869D01*
G03X454676Y1580001I-200J0D01*
G02Y1582913I1664J1456D01*
G03X454726Y1583045I-150J132D01*
G01Y1583667D01*
G02X454929Y1583870I203J0D01*
G37*
G36*
G01X475274Y1574128D02*
G02X475072Y1573926I-202J0D01*
G01X472252D01*
G02X472050Y1574129I1J203D01*
G01Y1574749D01*
G03X472000Y1574881I-200J0D01*
G02Y1577797I1661J1458D01*
G03X472050Y1577929I-150J132D01*
G01Y1579867D01*
G03X472000Y1579999I-200J0D01*
G02Y1582915I1661J1458D01*
G03X472050Y1583047I-150J132D01*
G01Y1583668D01*
G02X472252Y1583870I202J0D01*
G01X475072D01*
G02X475274Y1583667I-1J-203D01*
G01Y1583047D01*
G03X475324Y1582915I200J0D01*
G02Y1579999I-1661J-1458D01*
G03X475274Y1579867I150J-132D01*
G01Y1577929D01*
G03X475324Y1577797I200J0D01*
G02Y1574881I-1661J-1458D01*
G03X475274Y1574749I150J-132D01*
G01Y1574128D01*
G37*
G36*
G01X489575Y1583870D02*
X492395D01*
G02X492598Y1583667I0J-203D01*
G01Y1583045D01*
G03X492648Y1582913I200J0D01*
G02Y1580001I-1664J-1456D01*
G03X492598Y1579869I150J-132D01*
G01Y1577927D01*
G03X492648Y1577795I200J0D01*
G02Y1574883I-1664J-1456D01*
G03X492598Y1574751I150J-132D01*
G01Y1574129D01*
G02X492395Y1573926I-203J0D01*
G01X489575D01*
G02X489372Y1574129I0J203D01*
G01Y1574751D01*
G03X489322Y1574883I-200J0D01*
G02Y1577795I1664J1456D01*
G03X489372Y1577927I-150J132D01*
G01Y1579869D01*
G03X489322Y1580001I-200J0D01*
G02Y1582913I1664J1456D01*
G03X489372Y1583045I-150J132D01*
G01Y1583667D01*
G02X489575Y1583870I203J0D01*
G37*
G36*
G01X506897D02*
X509717D01*
G02X509920Y1583667I0J-203D01*
G01Y1583045D01*
G03X509970Y1582913I200J0D01*
G02Y1580001I-1664J-1456D01*
G03X509920Y1579869I150J-132D01*
G01Y1577927D01*
G03X509970Y1577795I200J0D01*
G02Y1574883I-1664J-1456D01*
G03X509920Y1574751I150J-132D01*
G01Y1574129D01*
G02X509717Y1573926I-203J0D01*
G01X506897D01*
G02X506694Y1574129I0J203D01*
G01Y1574751D01*
G03X506644Y1574883I-200J0D01*
G02Y1577795I1664J1456D01*
G03X506694Y1577927I-150J132D01*
G01Y1579869D01*
G03X506644Y1580001I-200J0D01*
G02Y1582913I1664J1456D01*
G03X506694Y1583045I-150J132D01*
G01Y1583667D01*
G02X506897Y1583870I203J0D01*
G37*
G36*
G01X1497242Y1574128D02*
G02X1497040Y1573926I-202J0D01*
G01X1494220D01*
G02X1494018Y1574129I1J203D01*
G01Y1574749D01*
G03X1493968Y1574881I-200J0D01*
G02Y1577797I1661J1458D01*
G03X1494018Y1577929I-150J132D01*
G01Y1579867D01*
G03X1493968Y1579999I-200J0D01*
G02Y1582915I1661J1458D01*
G03X1494018Y1583047I-150J132D01*
G01Y1583668D01*
G02X1494220Y1583870I202J0D01*
G01X1497040D01*
G02X1497242Y1583667I-1J-203D01*
G01Y1583047D01*
G03X1497292Y1582915I200J0D01*
G02Y1579999I-1661J-1458D01*
G03X1497242Y1579867I150J-132D01*
G01Y1577929D01*
G03X1497292Y1577797I200J0D01*
G02Y1574881I-1661J-1458D01*
G03X1497242Y1574749I150J-132D01*
G01Y1574128D01*
G37*
G36*
G01X1511543Y1583870D02*
X1514363D01*
G02X1514566Y1583667I0J-203D01*
G01Y1583045D01*
G03X1514616Y1582913I200J0D01*
G02Y1580001I-1664J-1456D01*
G03X1514566Y1579869I150J-132D01*
G01Y1577927D01*
G03X1514616Y1577795I200J0D01*
G02Y1574883I-1664J-1456D01*
G03X1514566Y1574751I150J-132D01*
G01Y1574129D01*
G02X1514363Y1573926I-203J0D01*
G01X1511543D01*
G02X1511340Y1574129I0J203D01*
G01Y1574751D01*
G03X1511290Y1574883I-200J0D01*
G02Y1577795I1664J1456D01*
G03X1511340Y1577927I-150J132D01*
G01Y1579869D01*
G03X1511290Y1580001I-200J0D01*
G02Y1582913I1664J1456D01*
G03X1511340Y1583045I-150J132D01*
G01Y1583667D01*
G02X1511543Y1583870I203J0D01*
G37*
G36*
G01X1528865D02*
X1531685D01*
G02X1531888Y1583667I0J-203D01*
G01Y1583045D01*
G03X1531938Y1582913I200J0D01*
G02Y1580001I-1664J-1456D01*
G03X1531888Y1579869I150J-132D01*
G01Y1577927D01*
G03X1531938Y1577795I200J0D01*
G02Y1574883I-1664J-1456D01*
G03X1531888Y1574751I150J-132D01*
G01Y1574129D01*
G02X1531685Y1573926I-203J0D01*
G01X1528865D01*
G02X1528662Y1574129I0J203D01*
G01Y1574751D01*
G03X1528612Y1574883I-200J0D01*
G02Y1577795I1664J1456D01*
G03X1528662Y1577927I-150J132D01*
G01Y1579869D01*
G03X1528612Y1580001I-200J0D01*
G02Y1582913I1664J1456D01*
G03X1528662Y1583045I-150J132D01*
G01Y1583667D01*
G02X1528865Y1583870I203J0D01*
G37*
G36*
G01X463590Y1588200D02*
X466410D01*
G02X466612Y1587998I0J-202D01*
G01Y1587378D01*
G03X466662Y1587246I200J0D01*
G02Y1584330I-1661J-1458D01*
G03X466612Y1584198I150J-132D01*
G01Y1582260D01*
G03X466662Y1582128I200J0D01*
G02Y1579212I-1661J-1458D01*
G03X466612Y1579080I150J-132D01*
G01Y1578460D01*
G02X466410Y1578258I-202J0D01*
G01X463590D01*
G02X463388Y1578460I0J202D01*
G01Y1579080D01*
G03X463338Y1579212I-200J0D01*
G02Y1582128I1661J1458D01*
G03X463388Y1582260I-150J132D01*
G01Y1584198D01*
G03X463338Y1584330I-200J0D01*
G02Y1587246I1661J1458D01*
G03X463388Y1587378I-150J132D01*
G01Y1587998D01*
G02X463590Y1588200I202J0D01*
G37*
G36*
G01X498236D02*
X501056D01*
G02X501258Y1587998I0J-202D01*
G01Y1587378D01*
G03X501308Y1587246I200J0D01*
G02Y1584330I-1661J-1458D01*
G03X501258Y1584198I150J-132D01*
G01Y1582260D01*
G03X501308Y1582128I200J0D01*
G02Y1579212I-1661J-1458D01*
G03X501258Y1579080I150J-132D01*
G01Y1578460D01*
G02X501056Y1578258I-202J0D01*
G01X498236D01*
G02X498034Y1578460I0J202D01*
G01Y1579080D01*
G03X497984Y1579212I-200J0D01*
G02Y1582128I1661J1458D01*
G03X498034Y1582260I-150J132D01*
G01Y1584198D01*
G03X497984Y1584330I-200J0D01*
G02Y1587246I1661J1458D01*
G03X498034Y1587378I-150J132D01*
G01Y1587998D01*
G02X498236Y1588200I202J0D01*
G37*
G36*
G01X1485558D02*
X1488378D01*
G02X1488580Y1587998I0J-202D01*
G01Y1587378D01*
G03X1488630Y1587246I200J0D01*
G02Y1584330I-1661J-1458D01*
G03X1488580Y1584198I150J-132D01*
G01Y1582260D01*
G03X1488630Y1582128I200J0D01*
G02Y1579212I-1661J-1458D01*
G03X1488580Y1579080I150J-132D01*
G01Y1578460D01*
G02X1488378Y1578258I-202J0D01*
G01X1485558D01*
G02X1485356Y1578460I0J202D01*
G01Y1579080D01*
G03X1485306Y1579212I-200J0D01*
G02Y1582128I1661J1458D01*
G03X1485356Y1582260I-150J132D01*
G01Y1584198D01*
G03X1485306Y1584330I-200J0D01*
G02Y1587246I1661J1458D01*
G03X1485356Y1587378I-150J132D01*
G01Y1587998D01*
G02X1485558Y1588200I202J0D01*
G37*
G36*
G01X1520204D02*
X1523024D01*
G02X1523226Y1587998I0J-202D01*
G01Y1587378D01*
G03X1523276Y1587246I200J0D01*
G02Y1584330I-1661J-1458D01*
G03X1523226Y1584198I150J-132D01*
G01Y1582260D01*
G03X1523276Y1582128I200J0D01*
G02Y1579212I-1661J-1458D01*
G03X1523226Y1579080I150J-132D01*
G01Y1578460D01*
G02X1523024Y1578258I-202J0D01*
G01X1520204D01*
G02X1520002Y1578460I0J202D01*
G01Y1579080D01*
G03X1519952Y1579212I-200J0D01*
G02Y1582128I1661J1458D01*
G03X1520002Y1582260I-150J132D01*
G01Y1584198D01*
G03X1519952Y1584330I-200J0D01*
G02Y1587246I1661J1458D01*
G03X1520002Y1587378I-150J132D01*
G01Y1587998D01*
G02X1520204Y1588200I202J0D01*
G37*
G36*
G01X480912Y1578258D02*
G02X480710Y1578460I0J202D01*
G01Y1579082D01*
G03X480660Y1579214I-200J0D01*
G02Y1582126I1664J1456D01*
G03X480710Y1582258I-150J132D01*
G01Y1584200D01*
G03X480660Y1584332I-200J0D01*
G02Y1587244I1664J1456D01*
G03X480710Y1587376I-150J132D01*
G01Y1587998D01*
G02X480913Y1588200I203J-1D01*
G01X483734D01*
G02X483936Y1587998I0J-202D01*
G01Y1587376D01*
G03X483986Y1587244I200J0D01*
G02Y1584332I-1664J-1456D01*
G03X483936Y1584200I150J-132D01*
G01Y1582258D01*
G03X483986Y1582126I200J0D01*
G02Y1579214I-1664J-1456D01*
G03X483936Y1579082I150J-132D01*
G01Y1578460D01*
G02X483733Y1578258I-203J1D01*
G01X480912D01*
G37*
G36*
G01X1502880D02*
G02X1502678Y1578460I0J202D01*
G01Y1579082D01*
G03X1502628Y1579214I-200J0D01*
G02Y1582126I1664J1456D01*
G03X1502678Y1582258I-150J132D01*
G01Y1584200D01*
G03X1502628Y1584332I-200J0D01*
G02Y1587244I1664J1456D01*
G03X1502678Y1587376I-150J132D01*
G01Y1587998D01*
G02X1502881Y1588200I203J-1D01*
G01X1505702D01*
G02X1505904Y1587998I0J-202D01*
G01Y1587376D01*
G03X1505954Y1587244I200J0D01*
G02Y1584332I-1664J-1456D01*
G03X1505904Y1584200I150J-132D01*
G01Y1582258D01*
G03X1505954Y1582126I200J0D01*
G02Y1579214I-1664J-1456D01*
G03X1505904Y1579082I150J-132D01*
G01Y1578460D01*
G02X1505701Y1578258I-203J1D01*
G01X1502880D01*
G37*
G36*
G01X1537526D02*
G02X1537324Y1578460I0J202D01*
G01Y1579082D01*
G03X1537274Y1579214I-200J0D01*
G02Y1582126I1664J1456D01*
G03X1537324Y1582258I-150J132D01*
G01Y1584200D01*
G03X1537274Y1584332I-200J0D01*
G02Y1587244I1664J1456D01*
G03X1537324Y1587376I-150J132D01*
G01Y1587998D01*
G02X1537527Y1588200I203J-1D01*
G01X1540348D01*
G02X1540550Y1587998I0J-202D01*
G01Y1587376D01*
G03X1540600Y1587244I200J0D01*
G02Y1584332I-1664J-1456D01*
G03X1540550Y1584200I150J-132D01*
G01Y1582258D01*
G03X1540600Y1582126I200J0D01*
G02Y1579214I-1664J-1456D01*
G03X1540550Y1579082I150J-132D01*
G01Y1578460D01*
G02X1540347Y1578258I-203J1D01*
G01X1537526D01*
G37*
G36*
G01X454929Y1599224D02*
X457749D01*
G02X457952Y1599021I0J-203D01*
G01Y1598399D01*
G03X458002Y1598267I200J0D01*
G02Y1595355I-1664J-1456D01*
G03X457952Y1595223I150J-132D01*
G01Y1593281D01*
G03X458002Y1593149I200J0D01*
G02Y1590237I-1664J-1456D01*
G03X457952Y1590105I150J-132D01*
G01Y1589483D01*
G02X457749Y1589280I-203J0D01*
G01X454929D01*
G02X454726Y1589483I0J203D01*
G01Y1590105D01*
G03X454676Y1590237I-200J0D01*
G02Y1593149I1664J1456D01*
G03X454726Y1593281I-150J132D01*
G01Y1595223D01*
G03X454676Y1595355I-200J0D01*
G02Y1598267I1664J1456D01*
G03X454726Y1598399I-150J132D01*
G01Y1599021D01*
G02X454929Y1599224I203J0D01*
G37*
G36*
G01X475274Y1589482D02*
G02X475072Y1589280I-202J0D01*
G01X472252D01*
G02X472050Y1589483I1J203D01*
G01Y1590103D01*
G03X472000Y1590235I-200J0D01*
G02Y1593151I1661J1458D01*
G03X472050Y1593283I-150J132D01*
G01Y1595221D01*
G03X472000Y1595353I-200J0D01*
G02Y1598269I1661J1458D01*
G03X472050Y1598401I-150J132D01*
G01Y1599022D01*
G02X472252Y1599224I202J0D01*
G01X475072D01*
G02X475274Y1599021I-1J-203D01*
G01Y1598401D01*
G03X475324Y1598269I200J0D01*
G02Y1595353I-1661J-1458D01*
G03X475274Y1595221I150J-132D01*
G01Y1593283D01*
G03X475324Y1593151I200J0D01*
G02Y1590235I-1661J-1458D01*
G03X475274Y1590103I150J-132D01*
G01Y1589482D01*
G37*
G36*
G01X489575Y1599224D02*
X492395D01*
G02X492598Y1599021I0J-203D01*
G01Y1598399D01*
G03X492648Y1598267I200J0D01*
G02Y1595355I-1664J-1456D01*
G03X492598Y1595223I150J-132D01*
G01Y1593281D01*
G03X492648Y1593149I200J0D01*
G02Y1590237I-1664J-1456D01*
G03X492598Y1590105I150J-132D01*
G01Y1589483D01*
G02X492395Y1589280I-203J0D01*
G01X489575D01*
G02X489372Y1589483I0J203D01*
G01Y1590105D01*
G03X489322Y1590237I-200J0D01*
G02Y1593149I1664J1456D01*
G03X489372Y1593281I-150J132D01*
G01Y1595223D01*
G03X489322Y1595355I-200J0D01*
G02Y1598267I1664J1456D01*
G03X489372Y1598399I-150J132D01*
G01Y1599021D01*
G02X489575Y1599224I203J0D01*
G37*
G36*
G01X506897D02*
X509717D01*
G02X509920Y1599021I0J-203D01*
G01Y1598399D01*
G03X509970Y1598267I200J0D01*
G02Y1595355I-1664J-1456D01*
G03X509920Y1595223I150J-132D01*
G01Y1593281D01*
G03X509970Y1593149I200J0D01*
G02Y1590237I-1664J-1456D01*
G03X509920Y1590105I150J-132D01*
G01Y1589483D01*
G02X509717Y1589280I-203J0D01*
G01X506897D01*
G02X506694Y1589483I0J203D01*
G01Y1590105D01*
G03X506644Y1590237I-200J0D01*
G02Y1593149I1664J1456D01*
G03X506694Y1593281I-150J132D01*
G01Y1595223D01*
G03X506644Y1595355I-200J0D01*
G02Y1598267I1664J1456D01*
G03X506694Y1598399I-150J132D01*
G01Y1599021D01*
G02X506897Y1599224I203J0D01*
G37*
G36*
G01X1497242Y1589482D02*
G02X1497040Y1589280I-202J0D01*
G01X1494220D01*
G02X1494018Y1589483I1J203D01*
G01Y1590103D01*
G03X1493968Y1590235I-200J0D01*
G02Y1593151I1661J1458D01*
G03X1494018Y1593283I-150J132D01*
G01Y1595221D01*
G03X1493968Y1595353I-200J0D01*
G02Y1598269I1661J1458D01*
G03X1494018Y1598401I-150J132D01*
G01Y1599022D01*
G02X1494220Y1599224I202J0D01*
G01X1497040D01*
G02X1497242Y1599021I-1J-203D01*
G01Y1598401D01*
G03X1497292Y1598269I200J0D01*
G02Y1595353I-1661J-1458D01*
G03X1497242Y1595221I150J-132D01*
G01Y1593283D01*
G03X1497292Y1593151I200J0D01*
G02Y1590235I-1661J-1458D01*
G03X1497242Y1590103I150J-132D01*
G01Y1589482D01*
G37*
G36*
G01X1511543Y1599224D02*
X1514363D01*
G02X1514566Y1599021I0J-203D01*
G01Y1598399D01*
G03X1514616Y1598267I200J0D01*
G02Y1595355I-1664J-1456D01*
G03X1514566Y1595223I150J-132D01*
G01Y1593281D01*
G03X1514616Y1593149I200J0D01*
G02Y1590237I-1664J-1456D01*
G03X1514566Y1590105I150J-132D01*
G01Y1589483D01*
G02X1514363Y1589280I-203J0D01*
G01X1511543D01*
G02X1511340Y1589483I0J203D01*
G01Y1590105D01*
G03X1511290Y1590237I-200J0D01*
G02Y1593149I1664J1456D01*
G03X1511340Y1593281I-150J132D01*
G01Y1595223D01*
G03X1511290Y1595355I-200J0D01*
G02Y1598267I1664J1456D01*
G03X1511340Y1598399I-150J132D01*
G01Y1599021D01*
G02X1511543Y1599224I203J0D01*
G37*
G36*
G01X1528865D02*
X1531685D01*
G02X1531888Y1599021I0J-203D01*
G01Y1598399D01*
G03X1531938Y1598267I200J0D01*
G02Y1595355I-1664J-1456D01*
G03X1531888Y1595223I150J-132D01*
G01Y1593281D01*
G03X1531938Y1593149I200J0D01*
G02Y1590237I-1664J-1456D01*
G03X1531888Y1590105I150J-132D01*
G01Y1589483D01*
G02X1531685Y1589280I-203J0D01*
G01X1528865D01*
G02X1528662Y1589483I0J203D01*
G01Y1590105D01*
G03X1528612Y1590237I-200J0D01*
G02Y1593149I1664J1456D01*
G03X1528662Y1593281I-150J132D01*
G01Y1595223D01*
G03X1528612Y1595355I-200J0D01*
G02Y1598267I1664J1456D01*
G03X1528662Y1598399I-150J132D01*
G01Y1599021D01*
G02X1528865Y1599224I203J0D01*
G37*
G36*
G01X463590Y1603554D02*
X466410D01*
G02X466612Y1603352I0J-202D01*
G01Y1602732D01*
G03X466662Y1602600I200J0D01*
G02Y1599684I-1661J-1458D01*
G03X466612Y1599552I150J-132D01*
G01Y1597614D01*
G03X466662Y1597482I200J0D01*
G02Y1594566I-1661J-1458D01*
G03X466612Y1594434I150J-132D01*
G01Y1593814D01*
G02X466410Y1593612I-202J0D01*
G01X463590D01*
G02X463388Y1593814I0J202D01*
G01Y1594434D01*
G03X463338Y1594566I-200J0D01*
G02Y1597482I1661J1458D01*
G03X463388Y1597614I-150J132D01*
G01Y1599552D01*
G03X463338Y1599684I-200J0D01*
G02Y1602600I1661J1458D01*
G03X463388Y1602732I-150J132D01*
G01Y1603352D01*
G02X463590Y1603554I202J0D01*
G37*
G36*
G01X498236D02*
X501056D01*
G02X501258Y1603352I0J-202D01*
G01Y1602732D01*
G03X501308Y1602600I200J0D01*
G02Y1599684I-1661J-1458D01*
G03X501258Y1599552I150J-132D01*
G01Y1597614D01*
G03X501308Y1597482I200J0D01*
G02Y1594566I-1661J-1458D01*
G03X501258Y1594434I150J-132D01*
G01Y1593814D01*
G02X501056Y1593612I-202J0D01*
G01X498236D01*
G02X498034Y1593814I0J202D01*
G01Y1594434D01*
G03X497984Y1594566I-200J0D01*
G02Y1597482I1661J1458D01*
G03X498034Y1597614I-150J132D01*
G01Y1599552D01*
G03X497984Y1599684I-200J0D01*
G02Y1602600I1661J1458D01*
G03X498034Y1602732I-150J132D01*
G01Y1603352D01*
G02X498236Y1603554I202J0D01*
G37*
G36*
G01X1485558D02*
X1488378D01*
G02X1488580Y1603352I0J-202D01*
G01Y1602732D01*
G03X1488630Y1602600I200J0D01*
G02Y1599684I-1661J-1458D01*
G03X1488580Y1599552I150J-132D01*
G01Y1597614D01*
G03X1488630Y1597482I200J0D01*
G02Y1594566I-1661J-1458D01*
G03X1488580Y1594434I150J-132D01*
G01Y1593814D01*
G02X1488378Y1593612I-202J0D01*
G01X1485558D01*
G02X1485356Y1593814I0J202D01*
G01Y1594434D01*
G03X1485306Y1594566I-200J0D01*
G02Y1597482I1661J1458D01*
G03X1485356Y1597614I-150J132D01*
G01Y1599552D01*
G03X1485306Y1599684I-200J0D01*
G02Y1602600I1661J1458D01*
G03X1485356Y1602732I-150J132D01*
G01Y1603352D01*
G02X1485558Y1603554I202J0D01*
G37*
G36*
G01X1520204D02*
X1523024D01*
G02X1523226Y1603352I0J-202D01*
G01Y1602732D01*
G03X1523276Y1602600I200J0D01*
G02Y1599684I-1661J-1458D01*
G03X1523226Y1599552I150J-132D01*
G01Y1597614D01*
G03X1523276Y1597482I200J0D01*
G02Y1594566I-1661J-1458D01*
G03X1523226Y1594434I150J-132D01*
G01Y1593814D01*
G02X1523024Y1593612I-202J0D01*
G01X1520204D01*
G02X1520002Y1593814I0J202D01*
G01Y1594434D01*
G03X1519952Y1594566I-200J0D01*
G02Y1597482I1661J1458D01*
G03X1520002Y1597614I-150J132D01*
G01Y1599552D01*
G03X1519952Y1599684I-200J0D01*
G02Y1602600I1661J1458D01*
G03X1520002Y1602732I-150J132D01*
G01Y1603352D01*
G02X1520204Y1603554I202J0D01*
G37*
G36*
G01X480912Y1593612D02*
G02X480710Y1593814I0J202D01*
G01Y1594436D01*
G03X480660Y1594568I-200J0D01*
G02Y1597480I1664J1456D01*
G03X480710Y1597612I-150J132D01*
G01Y1599554D01*
G03X480660Y1599686I-200J0D01*
G02Y1602598I1664J1456D01*
G03X480710Y1602730I-150J132D01*
G01Y1603352D01*
G02X480913Y1603554I203J-1D01*
G01X483734D01*
G02X483936Y1603352I0J-202D01*
G01Y1602730D01*
G03X483986Y1602598I200J0D01*
G02Y1599686I-1664J-1456D01*
G03X483936Y1599554I150J-132D01*
G01Y1597612D01*
G03X483986Y1597480I200J0D01*
G02Y1594568I-1664J-1456D01*
G03X483936Y1594436I150J-132D01*
G01Y1593814D01*
G02X483733Y1593612I-203J1D01*
G01X480912D01*
G37*
G36*
G01X1502880D02*
G02X1502678Y1593814I0J202D01*
G01Y1594436D01*
G03X1502628Y1594568I-200J0D01*
G02Y1597480I1664J1456D01*
G03X1502678Y1597612I-150J132D01*
G01Y1599554D01*
G03X1502628Y1599686I-200J0D01*
G02Y1602598I1664J1456D01*
G03X1502678Y1602730I-150J132D01*
G01Y1603352D01*
G02X1502881Y1603554I203J-1D01*
G01X1505702D01*
G02X1505904Y1603352I0J-202D01*
G01Y1602730D01*
G03X1505954Y1602598I200J0D01*
G02Y1599686I-1664J-1456D01*
G03X1505904Y1599554I150J-132D01*
G01Y1597612D01*
G03X1505954Y1597480I200J0D01*
G02Y1594568I-1664J-1456D01*
G03X1505904Y1594436I150J-132D01*
G01Y1593814D01*
G02X1505701Y1593612I-203J1D01*
G01X1502880D01*
G37*
G36*
G01X1537526D02*
G02X1537324Y1593814I0J202D01*
G01Y1594436D01*
G03X1537274Y1594568I-200J0D01*
G02Y1597480I1664J1456D01*
G03X1537324Y1597612I-150J132D01*
G01Y1599554D01*
G03X1537274Y1599686I-200J0D01*
G02Y1602598I1664J1456D01*
G03X1537324Y1602730I-150J132D01*
G01Y1603352D01*
G02X1537527Y1603554I203J-1D01*
G01X1540348D01*
G02X1540550Y1603352I0J-202D01*
G01Y1602730D01*
G03X1540600Y1602598I200J0D01*
G02Y1599686I-1664J-1456D01*
G03X1540550Y1599554I150J-132D01*
G01Y1597612D01*
G03X1540600Y1597480I200J0D01*
G02Y1594568I-1664J-1456D01*
G03X1540550Y1594436I150J-132D01*
G01Y1593814D01*
G02X1540347Y1593612I-203J1D01*
G01X1537526D01*
G37*
G36*
G01X472252Y1614578D02*
X475072D01*
G02X475274Y1614376I0J-202D01*
G01Y1613756D01*
G03X475324Y1613624I200J0D01*
G02Y1610708I-1661J-1458D01*
G03X475274Y1610576I150J-132D01*
G01Y1608638D01*
G03X475324Y1608506I200J0D01*
G02Y1605590I-1661J-1458D01*
G03X475274Y1605458I150J-132D01*
G01Y1604838D01*
G02X475072Y1604636I-202J0D01*
G01X472252D01*
G02X472050Y1604838I0J202D01*
G01Y1605458D01*
G03X472000Y1605590I-200J0D01*
G02Y1608506I1661J1458D01*
G03X472050Y1608638I-150J132D01*
G01Y1610576D01*
G03X472000Y1610708I-200J0D01*
G02Y1613624I1661J1458D01*
G03X472050Y1613756I-150J132D01*
G01Y1614376D01*
G02X472252Y1614578I202J0D01*
G37*
G36*
G01X1494220D02*
X1497040D01*
G02X1497242Y1614376I0J-202D01*
G01Y1613756D01*
G03X1497292Y1613624I200J0D01*
G02Y1610708I-1661J-1458D01*
G03X1497242Y1610576I150J-132D01*
G01Y1608638D01*
G03X1497292Y1608506I200J0D01*
G02Y1605590I-1661J-1458D01*
G03X1497242Y1605458I150J-132D01*
G01Y1604838D01*
G02X1497040Y1604636I-202J0D01*
G01X1494220D01*
G02X1494018Y1604838I0J202D01*
G01Y1605458D01*
G03X1493968Y1605590I-200J0D01*
G02Y1608506I1661J1458D01*
G03X1494018Y1608638I-150J132D01*
G01Y1610576D01*
G03X1493968Y1610708I-200J0D01*
G02Y1613624I1661J1458D01*
G03X1494018Y1613756I-150J132D01*
G01Y1614376D01*
G02X1494220Y1614578I202J0D01*
G37*
G36*
G01X454928Y1604636D02*
G02X454726Y1604838I0J202D01*
G01Y1605460D01*
G03X454676Y1605592I-200J0D01*
G02Y1608504I1664J1456D01*
G03X454726Y1608636I-150J132D01*
G01Y1610578D01*
G03X454676Y1610710I-200J0D01*
G02Y1613622I1664J1456D01*
G03X454726Y1613754I-150J132D01*
G01Y1614376D01*
G02X454929Y1614578I203J-1D01*
G01X457750D01*
G02X457952Y1614376I0J-202D01*
G01Y1613754D01*
G03X458002Y1613622I200J0D01*
G02Y1610710I-1664J-1456D01*
G03X457952Y1610578I150J-132D01*
G01Y1608636D01*
G03X458002Y1608504I200J0D01*
G02Y1605592I-1664J-1456D01*
G03X457952Y1605460I150J-132D01*
G01Y1604838D01*
G02X457749Y1604636I-203J1D01*
G01X454928D01*
G37*
G36*
G01X489574D02*
G02X489372Y1604838I0J202D01*
G01Y1605460D01*
G03X489322Y1605592I-200J0D01*
G02Y1608504I1664J1456D01*
G03X489372Y1608636I-150J132D01*
G01Y1610578D01*
G03X489322Y1610710I-200J0D01*
G02Y1613622I1664J1456D01*
G03X489372Y1613754I-150J132D01*
G01Y1614376D01*
G02X489575Y1614578I203J-1D01*
G01X492396D01*
G02X492598Y1614376I0J-202D01*
G01Y1613754D01*
G03X492648Y1613622I200J0D01*
G02Y1610710I-1664J-1456D01*
G03X492598Y1610578I150J-132D01*
G01Y1608636D01*
G03X492648Y1608504I200J0D01*
G02Y1605592I-1664J-1456D01*
G03X492598Y1605460I150J-132D01*
G01Y1604838D01*
G02X492395Y1604636I-203J1D01*
G01X489574D01*
G37*
G36*
G01X506896D02*
G02X506694Y1604838I0J202D01*
G01Y1605460D01*
G03X506644Y1605592I-200J0D01*
G02Y1608504I1664J1456D01*
G03X506694Y1608636I-150J132D01*
G01Y1610578D01*
G03X506644Y1610710I-200J0D01*
G02Y1613622I1664J1456D01*
G03X506694Y1613754I-150J132D01*
G01Y1614376D01*
G02X506897Y1614578I203J-1D01*
G01X509718D01*
G02X509920Y1614376I0J-202D01*
G01Y1613754D01*
G03X509970Y1613622I200J0D01*
G02Y1610710I-1664J-1456D01*
G03X509920Y1610578I150J-132D01*
G01Y1608636D01*
G03X509970Y1608504I200J0D01*
G02Y1605592I-1664J-1456D01*
G03X509920Y1605460I150J-132D01*
G01Y1604838D01*
G02X509717Y1604636I-203J1D01*
G01X506896D01*
G37*
G36*
G01X1511542D02*
G02X1511340Y1604838I0J202D01*
G01Y1605460D01*
G03X1511290Y1605592I-200J0D01*
G02Y1608504I1664J1456D01*
G03X1511340Y1608636I-150J132D01*
G01Y1610578D01*
G03X1511290Y1610710I-200J0D01*
G02Y1613622I1664J1456D01*
G03X1511340Y1613754I-150J132D01*
G01Y1614376D01*
G02X1511543Y1614578I203J-1D01*
G01X1514364D01*
G02X1514566Y1614376I0J-202D01*
G01Y1613754D01*
G03X1514616Y1613622I200J0D01*
G02Y1610710I-1664J-1456D01*
G03X1514566Y1610578I150J-132D01*
G01Y1608636D01*
G03X1514616Y1608504I200J0D01*
G02Y1605592I-1664J-1456D01*
G03X1514566Y1605460I150J-132D01*
G01Y1604838D01*
G02X1514363Y1604636I-203J1D01*
G01X1511542D01*
G37*
G36*
G01X1528864D02*
G02X1528662Y1604838I0J202D01*
G01Y1605460D01*
G03X1528612Y1605592I-200J0D01*
G02Y1608504I1664J1456D01*
G03X1528662Y1608636I-150J132D01*
G01Y1610578D01*
G03X1528612Y1610710I-200J0D01*
G02Y1613622I1664J1456D01*
G03X1528662Y1613754I-150J132D01*
G01Y1614376D01*
G02X1528865Y1614578I203J-1D01*
G01X1531686D01*
G02X1531888Y1614376I0J-202D01*
G01Y1613754D01*
G03X1531938Y1613622I200J0D01*
G02Y1610710I-1664J-1456D01*
G03X1531888Y1610578I150J-132D01*
G01Y1608636D01*
G03X1531938Y1608504I200J0D01*
G02Y1605592I-1664J-1456D01*
G03X1531888Y1605460I150J-132D01*
G01Y1604838D01*
G02X1531685Y1604636I-203J1D01*
G01X1528864D01*
G37*
G36*
G01X463590Y1618908D02*
X466410D01*
G02X466612Y1618706I0J-202D01*
G01Y1618086D01*
G03X466662Y1617954I200J0D01*
G02Y1615038I-1661J-1458D01*
G03X466612Y1614906I150J-132D01*
G01Y1612968D01*
G03X466662Y1612836I200J0D01*
G02Y1609920I-1661J-1458D01*
G03X466612Y1609788I150J-132D01*
G01Y1609168D01*
G02X466410Y1608966I-202J0D01*
G01X463590D01*
G02X463388Y1609168I0J202D01*
G01Y1609788D01*
G03X463338Y1609920I-200J0D01*
G02Y1612836I1661J1458D01*
G03X463388Y1612968I-150J132D01*
G01Y1614906D01*
G03X463338Y1615038I-200J0D01*
G02Y1617954I1661J1458D01*
G03X463388Y1618086I-150J132D01*
G01Y1618706D01*
G02X463590Y1618908I202J0D01*
G37*
G36*
G01X498236D02*
X501056D01*
G02X501258Y1618706I0J-202D01*
G01Y1618086D01*
G03X501308Y1617954I200J0D01*
G02Y1615038I-1661J-1458D01*
G03X501258Y1614906I150J-132D01*
G01Y1612968D01*
G03X501308Y1612836I200J0D01*
G02Y1609920I-1661J-1458D01*
G03X501258Y1609788I150J-132D01*
G01Y1609168D01*
G02X501056Y1608966I-202J0D01*
G01X498236D01*
G02X498034Y1609168I0J202D01*
G01Y1609788D01*
G03X497984Y1609920I-200J0D01*
G02Y1612836I1661J1458D01*
G03X498034Y1612968I-150J132D01*
G01Y1614906D01*
G03X497984Y1615038I-200J0D01*
G02Y1617954I1661J1458D01*
G03X498034Y1618086I-150J132D01*
G01Y1618706D01*
G02X498236Y1618908I202J0D01*
G37*
G36*
G01X1485558D02*
X1488378D01*
G02X1488580Y1618706I0J-202D01*
G01Y1618086D01*
G03X1488630Y1617954I200J0D01*
G02Y1615038I-1661J-1458D01*
G03X1488580Y1614906I150J-132D01*
G01Y1612968D01*
G03X1488630Y1612836I200J0D01*
G02Y1609920I-1661J-1458D01*
G03X1488580Y1609788I150J-132D01*
G01Y1609168D01*
G02X1488378Y1608966I-202J0D01*
G01X1485558D01*
G02X1485356Y1609168I0J202D01*
G01Y1609788D01*
G03X1485306Y1609920I-200J0D01*
G02Y1612836I1661J1458D01*
G03X1485356Y1612968I-150J132D01*
G01Y1614906D01*
G03X1485306Y1615038I-200J0D01*
G02Y1617954I1661J1458D01*
G03X1485356Y1618086I-150J132D01*
G01Y1618706D01*
G02X1485558Y1618908I202J0D01*
G37*
G36*
G01X1520204D02*
X1523024D01*
G02X1523226Y1618706I0J-202D01*
G01Y1618086D01*
G03X1523276Y1617954I200J0D01*
G02Y1615038I-1661J-1458D01*
G03X1523226Y1614906I150J-132D01*
G01Y1612968D01*
G03X1523276Y1612836I200J0D01*
G02Y1609920I-1661J-1458D01*
G03X1523226Y1609788I150J-132D01*
G01Y1609168D01*
G02X1523024Y1608966I-202J0D01*
G01X1520204D01*
G02X1520002Y1609168I0J202D01*
G01Y1609788D01*
G03X1519952Y1609920I-200J0D01*
G02Y1612836I1661J1458D01*
G03X1520002Y1612968I-150J132D01*
G01Y1614906D01*
G03X1519952Y1615038I-200J0D01*
G02Y1617954I1661J1458D01*
G03X1520002Y1618086I-150J132D01*
G01Y1618706D01*
G02X1520204Y1618908I202J0D01*
G37*
G36*
G01X480912Y1608966D02*
G02X480710Y1609168I0J202D01*
G01Y1609790D01*
G03X480660Y1609922I-200J0D01*
G02Y1612834I1664J1456D01*
G03X480710Y1612966I-150J132D01*
G01Y1614908D01*
G03X480660Y1615040I-200J0D01*
G02Y1617952I1664J1456D01*
G03X480710Y1618084I-150J132D01*
G01Y1618706D01*
G02X480913Y1618908I203J-1D01*
G01X483734D01*
G02X483936Y1618706I0J-202D01*
G01Y1618084D01*
G03X483986Y1617952I200J0D01*
G02Y1615040I-1664J-1456D01*
G03X483936Y1614908I150J-132D01*
G01Y1612966D01*
G03X483986Y1612834I200J0D01*
G02Y1609922I-1664J-1456D01*
G03X483936Y1609790I150J-132D01*
G01Y1609168D01*
G02X483733Y1608966I-203J1D01*
G01X480912D01*
G37*
G36*
G01X1502880D02*
G02X1502678Y1609168I0J202D01*
G01Y1609790D01*
G03X1502628Y1609922I-200J0D01*
G02Y1612834I1664J1456D01*
G03X1502678Y1612966I-150J132D01*
G01Y1614908D01*
G03X1502628Y1615040I-200J0D01*
G02Y1617952I1664J1456D01*
G03X1502678Y1618084I-150J132D01*
G01Y1618706D01*
G02X1502881Y1618908I203J-1D01*
G01X1505702D01*
G02X1505904Y1618706I0J-202D01*
G01Y1618084D01*
G03X1505954Y1617952I200J0D01*
G02Y1615040I-1664J-1456D01*
G03X1505904Y1614908I150J-132D01*
G01Y1612966D01*
G03X1505954Y1612834I200J0D01*
G02Y1609922I-1664J-1456D01*
G03X1505904Y1609790I150J-132D01*
G01Y1609168D01*
G02X1505701Y1608966I-203J1D01*
G01X1502880D01*
G37*
G36*
G01X1537526D02*
G02X1537324Y1609168I0J202D01*
G01Y1609790D01*
G03X1537274Y1609922I-200J0D01*
G02Y1612834I1664J1456D01*
G03X1537324Y1612966I-150J132D01*
G01Y1614908D01*
G03X1537274Y1615040I-200J0D01*
G02Y1617952I1664J1456D01*
G03X1537324Y1618084I-150J132D01*
G01Y1618706D01*
G02X1537527Y1618908I203J-1D01*
G01X1540348D01*
G02X1540550Y1618706I0J-202D01*
G01Y1618084D01*
G03X1540600Y1617952I200J0D01*
G02Y1615040I-1664J-1456D01*
G03X1540550Y1614908I150J-132D01*
G01Y1612966D01*
G03X1540600Y1612834I200J0D01*
G02Y1609922I-1664J-1456D01*
G03X1540550Y1609790I150J-132D01*
G01Y1609168D01*
G02X1540347Y1608966I-203J1D01*
G01X1537526D01*
G37*
G36*
G01X125795Y1466154D02*
X128615D01*
G02X128818Y1465951I0J-203D01*
G01Y1465329D01*
G03X128868Y1465197I200J0D01*
G02Y1462285I-1664J-1456D01*
G03X128818Y1462153I150J-132D01*
G01Y1460210D01*
G03X128868Y1460078I200J0D01*
G02Y1457166I-1664J-1456D01*
G03X128818Y1457034I150J-132D01*
G01Y1456413D01*
G02X128615Y1456210I-203J0D01*
G01X125795D01*
G02X125592Y1456413I0J203D01*
G01Y1457034D01*
G03X125542Y1457166I-200J0D01*
G02Y1460078I1664J1456D01*
G03X125592Y1460210I-150J132D01*
G01Y1462153D01*
G03X125542Y1462285I-200J0D01*
G02Y1465197I1664J1456D01*
G03X125592Y1465329I-150J132D01*
G01Y1465951D01*
G02X125795Y1466154I203J0D01*
G37*
G36*
G01X143118D02*
X145938D01*
G02X146140Y1465951I-1J-203D01*
G01Y1465331D01*
G03X146190Y1465199I200J0D01*
G02Y1462283I-1661J-1458D01*
G03X146140Y1462151I150J-132D01*
G01Y1460212D01*
G03X146190Y1460080I200J0D01*
G02Y1457164I-1661J-1458D01*
G03X146140Y1457032I150J-132D01*
G01Y1456413D01*
G02X145938Y1456210I-202J-1D01*
G01X143118D01*
G02X142916Y1456413I1J203D01*
G01Y1457032D01*
G03X142866Y1457164I-200J0D01*
G02Y1460080I1661J1458D01*
G03X142916Y1460212I-150J132D01*
G01Y1462151D01*
G03X142866Y1462283I-200J0D01*
G02Y1465199I1661J1458D01*
G03X142916Y1465331I-150J132D01*
G01Y1465951D01*
G02X143118Y1466154I202J1D01*
G37*
G36*
G01X160440D02*
X163260D01*
G02X163462Y1465951I-1J-203D01*
G01Y1465331D01*
G03X163512Y1465199I200J0D01*
G02Y1462283I-1661J-1458D01*
G03X163462Y1462151I150J-132D01*
G01Y1460212D01*
G03X163512Y1460080I200J0D01*
G02Y1457164I-1661J-1458D01*
G03X163462Y1457032I150J-132D01*
G01Y1456413D01*
G02X163260Y1456210I-202J-1D01*
G01X160440D01*
G02X160238Y1456413I1J203D01*
G01Y1457032D01*
G03X160188Y1457164I-200J0D01*
G02Y1460080I1661J1458D01*
G03X160238Y1460212I-150J132D01*
G01Y1462151D01*
G03X160188Y1462283I-200J0D01*
G02Y1465199I1661J1458D01*
G03X160238Y1465331I-150J132D01*
G01Y1465951D01*
G02X160440Y1466154I202J1D01*
G37*
G36*
G01X177763D02*
X180583D01*
G02X180786Y1465951I0J-203D01*
G01Y1465329D01*
G03X180836Y1465197I200J0D01*
G02Y1462285I-1664J-1456D01*
G03X180786Y1462153I150J-132D01*
G01Y1460210D01*
G03X180836Y1460078I200J0D01*
G02Y1457166I-1664J-1456D01*
G03X180786Y1457034I150J-132D01*
G01Y1456413D01*
G02X180583Y1456210I-203J0D01*
G01X177763D01*
G02X177560Y1456413I0J203D01*
G01Y1457034D01*
G03X177510Y1457166I-200J0D01*
G02Y1460078I1664J1456D01*
G03X177560Y1460210I-150J132D01*
G01Y1462153D01*
G03X177510Y1462285I-200J0D01*
G02Y1465197I1664J1456D01*
G03X177560Y1465329I-150J132D01*
G01Y1465951D01*
G02X177763Y1466154I203J0D01*
G37*
G36*
G01X281700D02*
X284520D01*
G02X284722Y1465951I-1J-203D01*
G01Y1465331D01*
G03X284772Y1465199I200J0D01*
G02Y1462283I-1661J-1458D01*
G03X284722Y1462151I150J-132D01*
G01Y1460212D01*
G03X284772Y1460080I200J0D01*
G02Y1457164I-1661J-1458D01*
G03X284722Y1457032I150J-132D01*
G01Y1456413D01*
G02X284520Y1456210I-202J-1D01*
G01X281700D01*
G02X281498Y1456413I1J203D01*
G01Y1457032D01*
G03X281448Y1457164I-200J0D01*
G02Y1460080I1661J1458D01*
G03X281498Y1460212I-150J132D01*
G01Y1462151D01*
G03X281448Y1462283I-200J0D01*
G02Y1465199I1661J1458D01*
G03X281498Y1465331I-150J132D01*
G01Y1465951D01*
G02X281700Y1466154I202J1D01*
G37*
G36*
G01X299023D02*
X301843D01*
G02X302046Y1465951I0J-203D01*
G01Y1465329D01*
G03X302096Y1465197I200J0D01*
G02Y1462285I-1664J-1456D01*
G03X302046Y1462153I150J-132D01*
G01Y1460210D01*
G03X302096Y1460078I200J0D01*
G02Y1457166I-1664J-1456D01*
G03X302046Y1457034I150J-132D01*
G01Y1456413D01*
G02X301843Y1456210I-203J0D01*
G01X299023D01*
G02X298820Y1456413I0J203D01*
G01Y1457034D01*
G03X298770Y1457166I-200J0D01*
G02Y1460078I1664J1456D01*
G03X298820Y1460210I-150J132D01*
G01Y1462153D01*
G03X298770Y1462285I-200J0D01*
G02Y1465197I1664J1456D01*
G03X298820Y1465329I-150J132D01*
G01Y1465951D01*
G02X299023Y1466154I203J0D01*
G37*
G36*
G01X454929D02*
X457749D01*
G02X457952Y1465951I0J-203D01*
G01Y1465329D01*
G03X458002Y1465197I200J0D01*
G02Y1462285I-1664J-1456D01*
G03X457952Y1462153I150J-132D01*
G01Y1460210D01*
G03X458002Y1460078I200J0D01*
G02Y1457166I-1664J-1456D01*
G03X457952Y1457034I150J-132D01*
G01Y1456413D01*
G02X457749Y1456210I-203J0D01*
G01X454929D01*
G02X454726Y1456413I0J203D01*
G01Y1457034D01*
G03X454676Y1457166I-200J0D01*
G02Y1460078I1664J1456D01*
G03X454726Y1460210I-150J132D01*
G01Y1462153D01*
G03X454676Y1462285I-200J0D01*
G02Y1465197I1664J1456D01*
G03X454726Y1465329I-150J132D01*
G01Y1465951D01*
G02X454929Y1466154I203J0D01*
G37*
G36*
G01X472252D02*
X475072D01*
G02X475274Y1465951I-1J-203D01*
G01Y1465331D01*
G03X475324Y1465199I200J0D01*
G02Y1462283I-1661J-1458D01*
G03X475274Y1462151I150J-132D01*
G01Y1460212D01*
G03X475324Y1460080I200J0D01*
G02Y1457164I-1661J-1458D01*
G03X475274Y1457032I150J-132D01*
G01Y1456413D01*
G02X475072Y1456210I-202J-1D01*
G01X472252D01*
G02X472050Y1456413I1J203D01*
G01Y1457032D01*
G03X472000Y1457164I-200J0D01*
G02Y1460080I1661J1458D01*
G03X472050Y1460212I-150J132D01*
G01Y1462151D01*
G03X472000Y1462283I-200J0D01*
G02Y1465199I1661J1458D01*
G03X472050Y1465331I-150J132D01*
G01Y1465951D01*
G02X472252Y1466154I202J1D01*
G37*
G36*
G01X489575D02*
X492395D01*
G02X492598Y1465951I0J-203D01*
G01Y1465329D01*
G03X492648Y1465197I200J0D01*
G02Y1462285I-1664J-1456D01*
G03X492598Y1462153I150J-132D01*
G01Y1460210D01*
G03X492648Y1460078I200J0D01*
G02Y1457166I-1664J-1456D01*
G03X492598Y1457034I150J-132D01*
G01Y1456413D01*
G02X492395Y1456210I-203J0D01*
G01X489575D01*
G02X489372Y1456413I0J203D01*
G01Y1457034D01*
G03X489322Y1457166I-200J0D01*
G02Y1460078I1664J1456D01*
G03X489372Y1460210I-150J132D01*
G01Y1462153D01*
G03X489322Y1462285I-200J0D01*
G02Y1465197I1664J1456D01*
G03X489372Y1465329I-150J132D01*
G01Y1465951D01*
G02X489575Y1466154I203J0D01*
G37*
G36*
G01X506897D02*
X509717D01*
G02X509920Y1465951I0J-203D01*
G01Y1465329D01*
G03X509970Y1465197I200J0D01*
G02Y1462285I-1664J-1456D01*
G03X509920Y1462153I150J-132D01*
G01Y1460210D01*
G03X509970Y1460078I200J0D01*
G02Y1457166I-1664J-1456D01*
G03X509920Y1457034I150J-132D01*
G01Y1456413D01*
G02X509717Y1456210I-203J0D01*
G01X506897D01*
G02X506694Y1456413I0J203D01*
G01Y1457034D01*
G03X506644Y1457166I-200J0D01*
G02Y1460078I1664J1456D01*
G03X506694Y1460210I-150J132D01*
G01Y1462153D01*
G03X506644Y1462285I-200J0D01*
G02Y1465197I1664J1456D01*
G03X506694Y1465329I-150J132D01*
G01Y1465951D01*
G02X506897Y1466154I203J0D01*
G37*
G36*
G01X645480D02*
X648300D01*
G02X648502Y1465951I-1J-203D01*
G01Y1465331D01*
G03X648552Y1465199I200J0D01*
G02Y1462283I-1661J-1458D01*
G03X648502Y1462151I150J-132D01*
G01Y1460212D01*
G03X648552Y1460080I200J0D01*
G02Y1457164I-1661J-1458D01*
G03X648502Y1457032I150J-132D01*
G01Y1456413D01*
G02X648300Y1456210I-202J-1D01*
G01X645480D01*
G02X645278Y1456413I1J203D01*
G01Y1457032D01*
G03X645228Y1457164I-200J0D01*
G02Y1460080I1661J1458D01*
G03X645278Y1460212I-150J132D01*
G01Y1462151D01*
G03X645228Y1462283I-200J0D01*
G02Y1465199I1661J1458D01*
G03X645278Y1465331I-150J132D01*
G01Y1465951D01*
G02X645480Y1466154I202J1D01*
G37*
G36*
G01X662803D02*
X665623D01*
G02X665826Y1465951I0J-203D01*
G01Y1465329D01*
G03X665876Y1465197I200J0D01*
G02Y1462285I-1664J-1456D01*
G03X665826Y1462153I150J-132D01*
G01Y1460210D01*
G03X665876Y1460078I200J0D01*
G02Y1457166I-1664J-1456D01*
G03X665826Y1457034I150J-132D01*
G01Y1456413D01*
G02X665623Y1456210I-203J0D01*
G01X662803D01*
G02X662600Y1456413I0J203D01*
G01Y1457034D01*
G03X662550Y1457166I-200J0D01*
G02Y1460078I1664J1456D01*
G03X662600Y1460210I-150J132D01*
G01Y1462153D01*
G03X662550Y1462285I-200J0D01*
G02Y1465197I1664J1456D01*
G03X662600Y1465329I-150J132D01*
G01Y1465951D01*
G02X662803Y1466154I203J0D01*
G37*
G36*
G01X680125D02*
X682945D01*
G02X683148Y1465951I0J-203D01*
G01Y1465329D01*
G03X683198Y1465197I200J0D01*
G02Y1462285I-1664J-1456D01*
G03X683148Y1462153I150J-132D01*
G01Y1460210D01*
G03X683198Y1460078I200J0D01*
G02Y1457166I-1664J-1456D01*
G03X683148Y1457034I150J-132D01*
G01Y1456413D01*
G02X682945Y1456210I-203J0D01*
G01X680125D01*
G02X679922Y1456413I0J203D01*
G01Y1457034D01*
G03X679872Y1457166I-200J0D01*
G02Y1460078I1664J1456D01*
G03X679922Y1460210I-150J132D01*
G01Y1462153D01*
G03X679872Y1462285I-200J0D01*
G02Y1465197I1664J1456D01*
G03X679922Y1465329I-150J132D01*
G01Y1465951D01*
G02X680125Y1466154I203J0D01*
G37*
G36*
G01X1165086D02*
X1167906D01*
G02X1168108Y1465951I-1J-203D01*
G01Y1465331D01*
G03X1168158Y1465199I200J0D01*
G02Y1462283I-1661J-1458D01*
G03X1168108Y1462151I150J-132D01*
G01Y1460212D01*
G03X1168158Y1460080I200J0D01*
G02Y1457164I-1661J-1458D01*
G03X1168108Y1457032I150J-132D01*
G01Y1456413D01*
G02X1167906Y1456210I-202J-1D01*
G01X1165086D01*
G02X1164884Y1456413I1J203D01*
G01Y1457032D01*
G03X1164834Y1457164I-200J0D01*
G02Y1460080I1661J1458D01*
G03X1164884Y1460212I-150J132D01*
G01Y1462151D01*
G03X1164834Y1462283I-200J0D01*
G02Y1465199I1661J1458D01*
G03X1164884Y1465331I-150J132D01*
G01Y1465951D01*
G02X1165086Y1466154I202J1D01*
G37*
G36*
G01X1182408D02*
X1185228D01*
G02X1185430Y1465951I-1J-203D01*
G01Y1465331D01*
G03X1185480Y1465199I200J0D01*
G02Y1462283I-1661J-1458D01*
G03X1185430Y1462151I150J-132D01*
G01Y1460212D01*
G03X1185480Y1460080I200J0D01*
G02Y1457164I-1661J-1458D01*
G03X1185430Y1457032I150J-132D01*
G01Y1456413D01*
G02X1185228Y1456210I-202J-1D01*
G01X1182408D01*
G02X1182206Y1456413I1J203D01*
G01Y1457032D01*
G03X1182156Y1457164I-200J0D01*
G02Y1460080I1661J1458D01*
G03X1182206Y1460212I-150J132D01*
G01Y1462151D01*
G03X1182156Y1462283I-200J0D01*
G02Y1465199I1661J1458D01*
G03X1182206Y1465331I-150J132D01*
G01Y1465951D01*
G02X1182408Y1466154I202J1D01*
G37*
G36*
G01X1303669D02*
X1306489D01*
G02X1306692Y1465951I0J-203D01*
G01Y1465329D01*
G03X1306742Y1465197I200J0D01*
G02Y1462285I-1664J-1456D01*
G03X1306692Y1462153I150J-132D01*
G01Y1460210D01*
G03X1306742Y1460078I200J0D01*
G02Y1457166I-1664J-1456D01*
G03X1306692Y1457034I150J-132D01*
G01Y1456413D01*
G02X1306489Y1456210I-203J0D01*
G01X1303669D01*
G02X1303466Y1456413I0J203D01*
G01Y1457034D01*
G03X1303416Y1457166I-200J0D01*
G02Y1460078I1664J1456D01*
G03X1303466Y1460210I-150J132D01*
G01Y1462153D01*
G03X1303416Y1462285I-200J0D01*
G02Y1465197I1664J1456D01*
G03X1303466Y1465329I-150J132D01*
G01Y1465951D01*
G02X1303669Y1466154I203J0D01*
G37*
G36*
G01X1320992D02*
X1323812D01*
G02X1324014Y1465951I-1J-203D01*
G01Y1465331D01*
G03X1324064Y1465199I200J0D01*
G02Y1462283I-1661J-1458D01*
G03X1324014Y1462151I150J-132D01*
G01Y1460212D01*
G03X1324064Y1460080I200J0D01*
G02Y1457164I-1661J-1458D01*
G03X1324014Y1457032I150J-132D01*
G01Y1456413D01*
G02X1323812Y1456210I-202J-1D01*
G01X1320992D01*
G02X1320790Y1456413I1J203D01*
G01Y1457032D01*
G03X1320740Y1457164I-200J0D01*
G02Y1460080I1661J1458D01*
G03X1320790Y1460212I-150J132D01*
G01Y1462151D01*
G03X1320740Y1462283I-200J0D01*
G02Y1465199I1661J1458D01*
G03X1320790Y1465331I-150J132D01*
G01Y1465951D01*
G02X1320992Y1466154I202J1D01*
G37*
G36*
G01X1338315D02*
X1341135D01*
G02X1341338Y1465951I0J-203D01*
G01Y1465329D01*
G03X1341388Y1465197I200J0D01*
G02Y1462285I-1664J-1456D01*
G03X1341338Y1462153I150J-132D01*
G01Y1460210D01*
G03X1341388Y1460078I200J0D01*
G02Y1457166I-1664J-1456D01*
G03X1341338Y1457034I150J-132D01*
G01Y1456413D01*
G02X1341135Y1456210I-203J0D01*
G01X1338315D01*
G02X1338112Y1456413I0J203D01*
G01Y1457034D01*
G03X1338062Y1457166I-200J0D01*
G02Y1460078I1664J1456D01*
G03X1338112Y1460210I-150J132D01*
G01Y1462153D01*
G03X1338062Y1462285I-200J0D01*
G02Y1465197I1664J1456D01*
G03X1338112Y1465329I-150J132D01*
G01Y1465951D01*
G02X1338315Y1466154I203J0D01*
G37*
G36*
G01X1355637D02*
X1358457D01*
G02X1358660Y1465951I0J-203D01*
G01Y1465329D01*
G03X1358710Y1465197I200J0D01*
G02Y1462285I-1664J-1456D01*
G03X1358660Y1462153I150J-132D01*
G01Y1460210D01*
G03X1358710Y1460078I200J0D01*
G02Y1457166I-1664J-1456D01*
G03X1358660Y1457034I150J-132D01*
G01Y1456413D01*
G02X1358457Y1456210I-203J0D01*
G01X1355637D01*
G02X1355434Y1456413I0J203D01*
G01Y1457034D01*
G03X1355384Y1457166I-200J0D01*
G02Y1460078I1664J1456D01*
G03X1355434Y1460210I-150J132D01*
G01Y1462153D01*
G03X1355384Y1462285I-200J0D01*
G02Y1465197I1664J1456D01*
G03X1355434Y1465329I-150J132D01*
G01Y1465951D01*
G02X1355637Y1466154I203J0D01*
G37*
G36*
G01X1476897D02*
X1479717D01*
G02X1479920Y1465951I0J-203D01*
G01Y1465329D01*
G03X1479970Y1465197I200J0D01*
G02Y1462285I-1664J-1456D01*
G03X1479920Y1462153I150J-132D01*
G01Y1460210D01*
G03X1479970Y1460078I200J0D01*
G02Y1457166I-1664J-1456D01*
G03X1479920Y1457034I150J-132D01*
G01Y1456413D01*
G02X1479717Y1456210I-203J0D01*
G01X1476897D01*
G02X1476694Y1456413I0J203D01*
G01Y1457034D01*
G03X1476644Y1457166I-200J0D01*
G02Y1460078I1664J1456D01*
G03X1476694Y1460210I-150J132D01*
G01Y1462153D01*
G03X1476644Y1462285I-200J0D01*
G02Y1465197I1664J1456D01*
G03X1476694Y1465329I-150J132D01*
G01Y1465951D01*
G02X1476897Y1466154I203J0D01*
G37*
G36*
G01X1494220D02*
X1497040D01*
G02X1497242Y1465951I-1J-203D01*
G01Y1465331D01*
G03X1497292Y1465199I200J0D01*
G02Y1462283I-1661J-1458D01*
G03X1497242Y1462151I150J-132D01*
G01Y1460212D01*
G03X1497292Y1460080I200J0D01*
G02Y1457164I-1661J-1458D01*
G03X1497242Y1457032I150J-132D01*
G01Y1456413D01*
G02X1497040Y1456210I-202J-1D01*
G01X1494220D01*
G02X1494018Y1456413I1J203D01*
G01Y1457032D01*
G03X1493968Y1457164I-200J0D01*
G02Y1460080I1661J1458D01*
G03X1494018Y1460212I-150J132D01*
G01Y1462151D01*
G03X1493968Y1462283I-200J0D01*
G02Y1465199I1661J1458D01*
G03X1494018Y1465331I-150J132D01*
G01Y1465951D01*
G02X1494220Y1466154I202J1D01*
G37*
G36*
G01X1511543D02*
X1514363D01*
G02X1514566Y1465951I0J-203D01*
G01Y1465329D01*
G03X1514616Y1465197I200J0D01*
G02Y1462285I-1664J-1456D01*
G03X1514566Y1462153I150J-132D01*
G01Y1460210D01*
G03X1514616Y1460078I200J0D01*
G02Y1457166I-1664J-1456D01*
G03X1514566Y1457034I150J-132D01*
G01Y1456413D01*
G02X1514363Y1456210I-203J0D01*
G01X1511543D01*
G02X1511340Y1456413I0J203D01*
G01Y1457034D01*
G03X1511290Y1457166I-200J0D01*
G02Y1460078I1664J1456D01*
G03X1511340Y1460210I-150J132D01*
G01Y1462153D01*
G03X1511290Y1462285I-200J0D01*
G02Y1465197I1664J1456D01*
G03X1511340Y1465329I-150J132D01*
G01Y1465951D01*
G02X1511543Y1466154I203J0D01*
G37*
G36*
G01X1528865D02*
X1531685D01*
G02X1531888Y1465951I0J-203D01*
G01Y1465329D01*
G03X1531938Y1465197I200J0D01*
G02Y1462285I-1664J-1456D01*
G03X1531888Y1462153I150J-132D01*
G01Y1460210D01*
G03X1531938Y1460078I200J0D01*
G02Y1457166I-1664J-1456D01*
G03X1531888Y1457034I150J-132D01*
G01Y1456413D01*
G02X1531685Y1456210I-203J0D01*
G01X1528865D01*
G02X1528662Y1456413I0J203D01*
G01Y1457034D01*
G03X1528612Y1457166I-200J0D01*
G02Y1460078I1664J1456D01*
G03X1528662Y1460210I-150J132D01*
G01Y1462153D01*
G03X1528612Y1462285I-200J0D01*
G02Y1465197I1664J1456D01*
G03X1528662Y1465329I-150J132D01*
G01Y1465951D01*
G02X1528865Y1466154I203J0D01*
G37*
G36*
G01X1684771D02*
X1687591D01*
G02X1687794Y1465951I0J-203D01*
G01Y1465329D01*
G03X1687844Y1465197I200J0D01*
G02Y1462285I-1664J-1456D01*
G03X1687794Y1462153I150J-132D01*
G01Y1460210D01*
G03X1687844Y1460078I200J0D01*
G02Y1457166I-1664J-1456D01*
G03X1687794Y1457034I150J-132D01*
G01Y1456413D01*
G02X1687591Y1456210I-203J0D01*
G01X1684771D01*
G02X1684568Y1456413I0J203D01*
G01Y1457034D01*
G03X1684518Y1457166I-200J0D01*
G02Y1460078I1664J1456D01*
G03X1684568Y1460210I-150J132D01*
G01Y1462153D01*
G03X1684518Y1462285I-200J0D01*
G02Y1465197I1664J1456D01*
G03X1684568Y1465329I-150J132D01*
G01Y1465951D01*
G02X1684771Y1466154I203J0D01*
G37*
G36*
G01X1702093D02*
X1704913D01*
G02X1705116Y1465951I0J-203D01*
G01Y1465329D01*
G03X1705166Y1465197I200J0D01*
G02Y1462285I-1664J-1456D01*
G03X1705116Y1462153I150J-132D01*
G01Y1460210D01*
G03X1705166Y1460078I200J0D01*
G02Y1457166I-1664J-1456D01*
G03X1705116Y1457034I150J-132D01*
G01Y1456413D01*
G02X1704913Y1456210I-203J0D01*
G01X1702093D01*
G02X1701890Y1456413I0J203D01*
G01Y1457034D01*
G03X1701840Y1457166I-200J0D01*
G02Y1460078I1664J1456D01*
G03X1701890Y1460210I-150J132D01*
G01Y1462153D01*
G03X1701840Y1462285I-200J0D01*
G02Y1465197I1664J1456D01*
G03X1701890Y1465329I-150J132D01*
G01Y1465951D01*
G02X1702093Y1466154I203J0D01*
G37*
G36*
G01X134456Y1470484D02*
X137276D01*
G02X137478Y1470281I-1J-203D01*
G01Y1469661D01*
G03X137528Y1469529I200J0D01*
G02Y1466613I-1661J-1458D01*
G03X137478Y1466481I150J-132D01*
G01Y1464543D01*
G03X137528Y1464411I200J0D01*
G02Y1461495I-1661J-1458D01*
G03X137478Y1461363I150J-132D01*
G01Y1460743D01*
G02X137276Y1460540I-202J-1D01*
G01X134456D01*
G02X134254Y1460743I1J203D01*
G01Y1461363D01*
G03X134204Y1461495I-200J0D01*
G02Y1464411I1661J1458D01*
G03X134254Y1464543I-150J132D01*
G01Y1466481D01*
G03X134204Y1466613I-200J0D01*
G02Y1469529I1661J1458D01*
G03X134254Y1469661I-150J132D01*
G01Y1470281D01*
G02X134456Y1470484I202J1D01*
G37*
G36*
G01X151779D02*
X154599D01*
G02X154802Y1470281I0J-203D01*
G01Y1469659D01*
G03X154852Y1469527I200J0D01*
G02Y1466615I-1664J-1456D01*
G03X154802Y1466483I150J-132D01*
G01Y1464541D01*
G03X154852Y1464409I200J0D01*
G02Y1461497I-1664J-1456D01*
G03X154802Y1461365I150J-132D01*
G01Y1460743D01*
G02X154599Y1460540I-203J0D01*
G01X151779D01*
G02X151576Y1460743I0J203D01*
G01Y1461365D01*
G03X151526Y1461497I-200J0D01*
G02Y1464409I1664J1456D01*
G03X151576Y1464541I-150J132D01*
G01Y1466483D01*
G03X151526Y1466615I-200J0D01*
G02Y1469527I1664J1456D01*
G03X151576Y1469659I-150J132D01*
G01Y1470281D01*
G02X151779Y1470484I203J0D01*
G37*
G36*
G01X169102D02*
X171922D01*
G02X172124Y1470281I-1J-203D01*
G01Y1469661D01*
G03X172174Y1469529I200J0D01*
G02Y1466613I-1661J-1458D01*
G03X172124Y1466481I150J-132D01*
G01Y1464543D01*
G03X172174Y1464411I200J0D01*
G02Y1461495I-1661J-1458D01*
G03X172124Y1461363I150J-132D01*
G01Y1460743D01*
G02X171922Y1460540I-202J-1D01*
G01X169102D01*
G02X168900Y1460743I1J203D01*
G01Y1461363D01*
G03X168850Y1461495I-200J0D01*
G02Y1464411I1661J1458D01*
G03X168900Y1464543I-150J132D01*
G01Y1466481D01*
G03X168850Y1466613I-200J0D01*
G02Y1469529I1661J1458D01*
G03X168900Y1469661I-150J132D01*
G01Y1470281D01*
G02X169102Y1470484I202J1D01*
G37*
G36*
G01X186425D02*
X189245D01*
G02X189448Y1470281I0J-203D01*
G01Y1469659D01*
G03X189498Y1469527I200J0D01*
G02Y1466615I-1664J-1456D01*
G03X189448Y1466483I150J-132D01*
G01Y1464541D01*
G03X189498Y1464409I200J0D01*
G02Y1461497I-1664J-1456D01*
G03X189448Y1461365I150J-132D01*
G01Y1460743D01*
G02X189245Y1460540I-203J0D01*
G01X186425D01*
G02X186222Y1460743I0J203D01*
G01Y1461365D01*
G03X186172Y1461497I-200J0D01*
G02Y1464409I1664J1456D01*
G03X186222Y1464541I-150J132D01*
G01Y1466483D01*
G03X186172Y1466615I-200J0D01*
G02Y1469527I1664J1456D01*
G03X186222Y1469659I-150J132D01*
G01Y1470281D01*
G02X186425Y1470484I203J0D01*
G37*
G36*
G01X290361D02*
X293181D01*
G02X293384Y1470281I0J-203D01*
G01Y1469659D01*
G03X293434Y1469527I200J0D01*
G02Y1466615I-1664J-1456D01*
G03X293384Y1466483I150J-132D01*
G01Y1464541D01*
G03X293434Y1464409I200J0D01*
G02Y1461497I-1664J-1456D01*
G03X293384Y1461365I150J-132D01*
G01Y1460743D01*
G02X293181Y1460540I-203J0D01*
G01X290361D01*
G02X290158Y1460743I0J203D01*
G01Y1461365D01*
G03X290108Y1461497I-200J0D01*
G02Y1464409I1664J1456D01*
G03X290158Y1464541I-150J132D01*
G01Y1466483D01*
G03X290108Y1466615I-200J0D01*
G02Y1469527I1664J1456D01*
G03X290158Y1469659I-150J132D01*
G01Y1470281D01*
G02X290361Y1470484I203J0D01*
G37*
G36*
G01X463590D02*
X466410D01*
G02X466612Y1470281I-1J-203D01*
G01Y1469661D01*
G03X466662Y1469529I200J0D01*
G02Y1466613I-1661J-1458D01*
G03X466612Y1466481I150J-132D01*
G01Y1464543D01*
G03X466662Y1464411I200J0D01*
G02Y1461495I-1661J-1458D01*
G03X466612Y1461363I150J-132D01*
G01Y1460743D01*
G02X466410Y1460540I-202J-1D01*
G01X463590D01*
G02X463388Y1460743I1J203D01*
G01Y1461363D01*
G03X463338Y1461495I-200J0D01*
G02Y1464411I1661J1458D01*
G03X463388Y1464543I-150J132D01*
G01Y1466481D01*
G03X463338Y1466613I-200J0D01*
G02Y1469529I1661J1458D01*
G03X463388Y1469661I-150J132D01*
G01Y1470281D01*
G02X463590Y1470484I202J1D01*
G37*
G36*
G01X480913D02*
X483733D01*
G02X483936Y1470281I0J-203D01*
G01Y1469659D01*
G03X483986Y1469527I200J0D01*
G02Y1466615I-1664J-1456D01*
G03X483936Y1466483I150J-132D01*
G01Y1464541D01*
G03X483986Y1464409I200J0D01*
G02Y1461497I-1664J-1456D01*
G03X483936Y1461365I150J-132D01*
G01Y1460743D01*
G02X483733Y1460540I-203J0D01*
G01X480913D01*
G02X480710Y1460743I0J203D01*
G01Y1461365D01*
G03X480660Y1461497I-200J0D01*
G02Y1464409I1664J1456D01*
G03X480710Y1464541I-150J132D01*
G01Y1466483D01*
G03X480660Y1466615I-200J0D01*
G02Y1469527I1664J1456D01*
G03X480710Y1469659I-150J132D01*
G01Y1470281D01*
G02X480913Y1470484I203J0D01*
G37*
G36*
G01X498236D02*
X501056D01*
G02X501258Y1470281I-1J-203D01*
G01Y1469661D01*
G03X501308Y1469529I200J0D01*
G02Y1466613I-1661J-1458D01*
G03X501258Y1466481I150J-132D01*
G01Y1464543D01*
G03X501308Y1464411I200J0D01*
G02Y1461495I-1661J-1458D01*
G03X501258Y1461363I150J-132D01*
G01Y1460743D01*
G02X501056Y1460540I-202J-1D01*
G01X498236D01*
G02X498034Y1460743I1J203D01*
G01Y1461363D01*
G03X497984Y1461495I-200J0D01*
G02Y1464411I1661J1458D01*
G03X498034Y1464543I-150J132D01*
G01Y1466481D01*
G03X497984Y1466613I-200J0D01*
G02Y1469529I1661J1458D01*
G03X498034Y1469661I-150J132D01*
G01Y1470281D01*
G02X498236Y1470484I202J1D01*
G37*
G36*
G01X515559D02*
X518379D01*
G02X518582Y1470281I0J-203D01*
G01Y1469659D01*
G03X518632Y1469527I200J0D01*
G02Y1466615I-1664J-1456D01*
G03X518582Y1466483I150J-132D01*
G01Y1464541D01*
G03X518632Y1464409I200J0D01*
G02Y1461497I-1664J-1456D01*
G03X518582Y1461365I150J-132D01*
G01Y1460743D01*
G02X518379Y1460540I-203J0D01*
G01X515559D01*
G02X515356Y1460743I0J203D01*
G01Y1461365D01*
G03X515306Y1461497I-200J0D01*
G02Y1464409I1664J1456D01*
G03X515356Y1464541I-150J132D01*
G01Y1466483D01*
G03X515306Y1466615I-200J0D01*
G02Y1469527I1664J1456D01*
G03X515356Y1469659I-150J132D01*
G01Y1470281D01*
G02X515559Y1470484I203J0D01*
G37*
G36*
G01X654141D02*
X656961D01*
G02X657164Y1470281I0J-203D01*
G01Y1469659D01*
G03X657214Y1469527I200J0D01*
G02Y1466615I-1664J-1456D01*
G03X657164Y1466483I150J-132D01*
G01Y1464541D01*
G03X657214Y1464409I200J0D01*
G02Y1461497I-1664J-1456D01*
G03X657164Y1461365I150J-132D01*
G01Y1460743D01*
G02X656961Y1460540I-203J0D01*
G01X654141D01*
G02X653938Y1460743I0J203D01*
G01Y1461365D01*
G03X653888Y1461497I-200J0D01*
G02Y1464409I1664J1456D01*
G03X653938Y1464541I-150J132D01*
G01Y1466483D01*
G03X653888Y1466615I-200J0D01*
G02Y1469527I1664J1456D01*
G03X653938Y1469659I-150J132D01*
G01Y1470281D01*
G02X654141Y1470484I203J0D01*
G37*
G36*
G01X671464D02*
X674284D01*
G02X674486Y1470281I-1J-203D01*
G01Y1469661D01*
G03X674536Y1469529I200J0D01*
G02Y1466613I-1661J-1458D01*
G03X674486Y1466481I150J-132D01*
G01Y1464543D01*
G03X674536Y1464411I200J0D01*
G02Y1461495I-1661J-1458D01*
G03X674486Y1461363I150J-132D01*
G01Y1460743D01*
G02X674284Y1460540I-202J-1D01*
G01X671464D01*
G02X671262Y1460743I1J203D01*
G01Y1461363D01*
G03X671212Y1461495I-200J0D01*
G02Y1464411I1661J1458D01*
G03X671262Y1464543I-150J132D01*
G01Y1466481D01*
G03X671212Y1466613I-200J0D01*
G02Y1469529I1661J1458D01*
G03X671262Y1469661I-150J132D01*
G01Y1470281D01*
G02X671464Y1470484I202J1D01*
G37*
G36*
G01X688787D02*
X691607D01*
G02X691810Y1470281I0J-203D01*
G01Y1469659D01*
G03X691860Y1469527I200J0D01*
G02Y1466615I-1664J-1456D01*
G03X691810Y1466483I150J-132D01*
G01Y1464541D01*
G03X691860Y1464409I200J0D01*
G02Y1461497I-1664J-1456D01*
G03X691810Y1461365I150J-132D01*
G01Y1460743D01*
G02X691607Y1460540I-203J0D01*
G01X688787D01*
G02X688584Y1460743I0J203D01*
G01Y1461365D01*
G03X688534Y1461497I-200J0D01*
G02Y1464409I1664J1456D01*
G03X688584Y1464541I-150J132D01*
G01Y1466483D01*
G03X688534Y1466615I-200J0D01*
G02Y1469527I1664J1456D01*
G03X688584Y1469659I-150J132D01*
G01Y1470281D01*
G02X688787Y1470484I203J0D01*
G37*
G36*
G01X1173747D02*
X1176567D01*
G02X1176770Y1470281I0J-203D01*
G01Y1469659D01*
G03X1176820Y1469527I200J0D01*
G02Y1466615I-1664J-1456D01*
G03X1176770Y1466483I150J-132D01*
G01Y1464541D01*
G03X1176820Y1464409I200J0D01*
G02Y1461497I-1664J-1456D01*
G03X1176770Y1461365I150J-132D01*
G01Y1460743D01*
G02X1176567Y1460540I-203J0D01*
G01X1173747D01*
G02X1173544Y1460743I0J203D01*
G01Y1461365D01*
G03X1173494Y1461497I-200J0D01*
G02Y1464409I1664J1456D01*
G03X1173544Y1464541I-150J132D01*
G01Y1466483D01*
G03X1173494Y1466615I-200J0D01*
G02Y1469527I1664J1456D01*
G03X1173544Y1469659I-150J132D01*
G01Y1470281D01*
G02X1173747Y1470484I203J0D01*
G37*
G36*
G01X1191070D02*
X1193890D01*
G02X1194092Y1470281I-1J-203D01*
G01Y1469661D01*
G03X1194142Y1469529I200J0D01*
G02Y1466613I-1661J-1458D01*
G03X1194092Y1466481I150J-132D01*
G01Y1464543D01*
G03X1194142Y1464411I200J0D01*
G02Y1461495I-1661J-1458D01*
G03X1194092Y1461363I150J-132D01*
G01Y1460743D01*
G02X1193890Y1460540I-202J-1D01*
G01X1191070D01*
G02X1190868Y1460743I1J203D01*
G01Y1461363D01*
G03X1190818Y1461495I-200J0D01*
G02Y1464411I1661J1458D01*
G03X1190868Y1464543I-150J132D01*
G01Y1466481D01*
G03X1190818Y1466613I-200J0D01*
G02Y1469529I1661J1458D01*
G03X1190868Y1469661I-150J132D01*
G01Y1470281D01*
G02X1191070Y1470484I202J1D01*
G37*
G36*
G01X1312330D02*
X1315150D01*
G02X1315352Y1470281I-1J-203D01*
G01Y1469661D01*
G03X1315402Y1469529I200J0D01*
G02Y1466613I-1661J-1458D01*
G03X1315352Y1466481I150J-132D01*
G01Y1464543D01*
G03X1315402Y1464411I200J0D01*
G02Y1461495I-1661J-1458D01*
G03X1315352Y1461363I150J-132D01*
G01Y1460743D01*
G02X1315150Y1460540I-202J-1D01*
G01X1312330D01*
G02X1312128Y1460743I1J203D01*
G01Y1461363D01*
G03X1312078Y1461495I-200J0D01*
G02Y1464411I1661J1458D01*
G03X1312128Y1464543I-150J132D01*
G01Y1466481D01*
G03X1312078Y1466613I-200J0D01*
G02Y1469529I1661J1458D01*
G03X1312128Y1469661I-150J132D01*
G01Y1470281D01*
G02X1312330Y1470484I202J1D01*
G37*
G36*
G01X1329653D02*
X1332473D01*
G02X1332676Y1470281I0J-203D01*
G01Y1469659D01*
G03X1332726Y1469527I200J0D01*
G02Y1466615I-1664J-1456D01*
G03X1332676Y1466483I150J-132D01*
G01Y1464541D01*
G03X1332726Y1464409I200J0D01*
G02Y1461497I-1664J-1456D01*
G03X1332676Y1461365I150J-132D01*
G01Y1460743D01*
G02X1332473Y1460540I-203J0D01*
G01X1329653D01*
G02X1329450Y1460743I0J203D01*
G01Y1461365D01*
G03X1329400Y1461497I-200J0D01*
G02Y1464409I1664J1456D01*
G03X1329450Y1464541I-150J132D01*
G01Y1466483D01*
G03X1329400Y1466615I-200J0D01*
G02Y1469527I1664J1456D01*
G03X1329450Y1469659I-150J132D01*
G01Y1470281D01*
G02X1329653Y1470484I203J0D01*
G37*
G36*
G01X1346976D02*
X1349796D01*
G02X1349998Y1470281I-1J-203D01*
G01Y1469661D01*
G03X1350048Y1469529I200J0D01*
G02Y1466613I-1661J-1458D01*
G03X1349998Y1466481I150J-132D01*
G01Y1464543D01*
G03X1350048Y1464411I200J0D01*
G02Y1461495I-1661J-1458D01*
G03X1349998Y1461363I150J-132D01*
G01Y1460743D01*
G02X1349796Y1460540I-202J-1D01*
G01X1346976D01*
G02X1346774Y1460743I1J203D01*
G01Y1461363D01*
G03X1346724Y1461495I-200J0D01*
G02Y1464411I1661J1458D01*
G03X1346774Y1464543I-150J132D01*
G01Y1466481D01*
G03X1346724Y1466613I-200J0D01*
G02Y1469529I1661J1458D01*
G03X1346774Y1469661I-150J132D01*
G01Y1470281D01*
G02X1346976Y1470484I202J1D01*
G37*
G36*
G01X1364299D02*
X1367119D01*
G02X1367322Y1470281I0J-203D01*
G01Y1469659D01*
G03X1367372Y1469527I200J0D01*
G02Y1466615I-1664J-1456D01*
G03X1367322Y1466483I150J-132D01*
G01Y1464541D01*
G03X1367372Y1464409I200J0D01*
G02Y1461497I-1664J-1456D01*
G03X1367322Y1461365I150J-132D01*
G01Y1460743D01*
G02X1367119Y1460540I-203J0D01*
G01X1364299D01*
G02X1364096Y1460743I0J203D01*
G01Y1461365D01*
G03X1364046Y1461497I-200J0D01*
G02Y1464409I1664J1456D01*
G03X1364096Y1464541I-150J132D01*
G01Y1466483D01*
G03X1364046Y1466615I-200J0D01*
G02Y1469527I1664J1456D01*
G03X1364096Y1469659I-150J132D01*
G01Y1470281D01*
G02X1364299Y1470484I203J0D01*
G37*
G36*
G01X1485558D02*
X1488378D01*
G02X1488580Y1470281I-1J-203D01*
G01Y1469661D01*
G03X1488630Y1469529I200J0D01*
G02Y1466613I-1661J-1458D01*
G03X1488580Y1466481I150J-132D01*
G01Y1464543D01*
G03X1488630Y1464411I200J0D01*
G02Y1461495I-1661J-1458D01*
G03X1488580Y1461363I150J-132D01*
G01Y1460743D01*
G02X1488378Y1460540I-202J-1D01*
G01X1485558D01*
G02X1485356Y1460743I1J203D01*
G01Y1461363D01*
G03X1485306Y1461495I-200J0D01*
G02Y1464411I1661J1458D01*
G03X1485356Y1464543I-150J132D01*
G01Y1466481D01*
G03X1485306Y1466613I-200J0D01*
G02Y1469529I1661J1458D01*
G03X1485356Y1469661I-150J132D01*
G01Y1470281D01*
G02X1485558Y1470484I202J1D01*
G37*
G36*
G01X1502881D02*
X1505701D01*
G02X1505904Y1470281I0J-203D01*
G01Y1469659D01*
G03X1505954Y1469527I200J0D01*
G02Y1466615I-1664J-1456D01*
G03X1505904Y1466483I150J-132D01*
G01Y1464541D01*
G03X1505954Y1464409I200J0D01*
G02Y1461497I-1664J-1456D01*
G03X1505904Y1461365I150J-132D01*
G01Y1460743D01*
G02X1505701Y1460540I-203J0D01*
G01X1502881D01*
G02X1502678Y1460743I0J203D01*
G01Y1461365D01*
G03X1502628Y1461497I-200J0D01*
G02Y1464409I1664J1456D01*
G03X1502678Y1464541I-150J132D01*
G01Y1466483D01*
G03X1502628Y1466615I-200J0D01*
G02Y1469527I1664J1456D01*
G03X1502678Y1469659I-150J132D01*
G01Y1470281D01*
G02X1502881Y1470484I203J0D01*
G37*
G36*
G01X1520204D02*
X1523024D01*
G02X1523226Y1470281I-1J-203D01*
G01Y1469661D01*
G03X1523276Y1469529I200J0D01*
G02Y1466613I-1661J-1458D01*
G03X1523226Y1466481I150J-132D01*
G01Y1464543D01*
G03X1523276Y1464411I200J0D01*
G02Y1461495I-1661J-1458D01*
G03X1523226Y1461363I150J-132D01*
G01Y1460743D01*
G02X1523024Y1460540I-202J-1D01*
G01X1520204D01*
G02X1520002Y1460743I1J203D01*
G01Y1461363D01*
G03X1519952Y1461495I-200J0D01*
G02Y1464411I1661J1458D01*
G03X1520002Y1464543I-150J132D01*
G01Y1466481D01*
G03X1519952Y1466613I-200J0D01*
G02Y1469529I1661J1458D01*
G03X1520002Y1469661I-150J132D01*
G01Y1470281D01*
G02X1520204Y1470484I202J1D01*
G37*
G36*
G01X1537527D02*
X1540347D01*
G02X1540550Y1470281I0J-203D01*
G01Y1469659D01*
G03X1540600Y1469527I200J0D01*
G02Y1466615I-1664J-1456D01*
G03X1540550Y1466483I150J-132D01*
G01Y1464541D01*
G03X1540600Y1464409I200J0D01*
G02Y1461497I-1664J-1456D01*
G03X1540550Y1461365I150J-132D01*
G01Y1460743D01*
G02X1540347Y1460540I-203J0D01*
G01X1537527D01*
G02X1537324Y1460743I0J203D01*
G01Y1461365D01*
G03X1537274Y1461497I-200J0D01*
G02Y1464409I1664J1456D01*
G03X1537324Y1464541I-150J132D01*
G01Y1466483D01*
G03X1537274Y1466615I-200J0D01*
G02Y1469527I1664J1456D01*
G03X1537324Y1469659I-150J132D01*
G01Y1470281D01*
G02X1537527Y1470484I203J0D01*
G37*
G36*
G01X1693432D02*
X1696252D01*
G02X1696454Y1470281I-1J-203D01*
G01Y1469661D01*
G03X1696504Y1469529I200J0D01*
G02Y1466613I-1661J-1458D01*
G03X1696454Y1466481I150J-132D01*
G01Y1464543D01*
G03X1696504Y1464411I200J0D01*
G02Y1461495I-1661J-1458D01*
G03X1696454Y1461363I150J-132D01*
G01Y1460743D01*
G02X1696252Y1460540I-202J-1D01*
G01X1693432D01*
G02X1693230Y1460743I1J203D01*
G01Y1461363D01*
G03X1693180Y1461495I-200J0D01*
G02Y1464411I1661J1458D01*
G03X1693230Y1464543I-150J132D01*
G01Y1466481D01*
G03X1693180Y1466613I-200J0D01*
G02Y1469529I1661J1458D01*
G03X1693230Y1469661I-150J132D01*
G01Y1470281D01*
G02X1693432Y1470484I202J1D01*
G37*
G36*
G01X1710755D02*
X1713575D01*
G02X1713778Y1470281I0J-203D01*
G01Y1469659D01*
G03X1713828Y1469527I200J0D01*
G02Y1466615I-1664J-1456D01*
G03X1713778Y1466483I150J-132D01*
G01Y1464541D01*
G03X1713828Y1464409I200J0D01*
G02Y1461497I-1664J-1456D01*
G03X1713778Y1461365I150J-132D01*
G01Y1460743D01*
G02X1713575Y1460540I-203J0D01*
G01X1710755D01*
G02X1710552Y1460743I0J203D01*
G01Y1461365D01*
G03X1710502Y1461497I-200J0D01*
G02Y1464409I1664J1456D01*
G03X1710552Y1464541I-150J132D01*
G01Y1466483D01*
G03X1710502Y1466615I-200J0D01*
G02Y1469527I1664J1456D01*
G03X1710552Y1469659I-150J132D01*
G01Y1470281D01*
G02X1710755Y1470484I203J0D01*
G37*
G36*
G01X125795Y1481508D02*
X128615D01*
G02X128818Y1481305I0J-203D01*
G01Y1480683D01*
G03X128868Y1480551I200J0D01*
G02Y1477639I-1664J-1456D01*
G03X128818Y1477507I150J-132D01*
G01Y1475565D01*
G03X128868Y1475433I200J0D01*
G02Y1472521I-1664J-1456D01*
G03X128818Y1472389I150J-132D01*
G01Y1471767D01*
G02X128615Y1471564I-203J0D01*
G01X125795D01*
G02X125592Y1471767I0J203D01*
G01Y1472389D01*
G03X125542Y1472521I-200J0D01*
G02Y1475433I1664J1456D01*
G03X125592Y1475565I-150J132D01*
G01Y1477507D01*
G03X125542Y1477639I-200J0D01*
G02Y1480551I1664J1456D01*
G03X125592Y1480683I-150J132D01*
G01Y1481305D01*
G02X125795Y1481508I203J0D01*
G37*
G36*
G01X143118D02*
X145938D01*
G02X146140Y1481305I-1J-203D01*
G01Y1480685D01*
G03X146190Y1480553I200J0D01*
G02Y1477637I-1661J-1458D01*
G03X146140Y1477505I150J-132D01*
G01Y1475567D01*
G03X146190Y1475435I200J0D01*
G02Y1472519I-1661J-1458D01*
G03X146140Y1472387I150J-132D01*
G01Y1471767D01*
G02X145938Y1471564I-202J-1D01*
G01X143118D01*
G02X142916Y1471767I1J203D01*
G01Y1472387D01*
G03X142866Y1472519I-200J0D01*
G02Y1475435I1661J1458D01*
G03X142916Y1475567I-150J132D01*
G01Y1477505D01*
G03X142866Y1477637I-200J0D01*
G02Y1480553I1661J1458D01*
G03X142916Y1480685I-150J132D01*
G01Y1481305D01*
G02X143118Y1481508I202J1D01*
G37*
G36*
G01X160440D02*
X163260D01*
G02X163462Y1481305I-1J-203D01*
G01Y1480685D01*
G03X163512Y1480553I200J0D01*
G02Y1477637I-1661J-1458D01*
G03X163462Y1477505I150J-132D01*
G01Y1475567D01*
G03X163512Y1475435I200J0D01*
G02Y1472519I-1661J-1458D01*
G03X163462Y1472387I150J-132D01*
G01Y1471767D01*
G02X163260Y1471564I-202J-1D01*
G01X160440D01*
G02X160238Y1471767I1J203D01*
G01Y1472387D01*
G03X160188Y1472519I-200J0D01*
G02Y1475435I1661J1458D01*
G03X160238Y1475567I-150J132D01*
G01Y1477505D01*
G03X160188Y1477637I-200J0D01*
G02Y1480553I1661J1458D01*
G03X160238Y1480685I-150J132D01*
G01Y1481305D01*
G02X160440Y1481508I202J1D01*
G37*
G36*
G01X177763D02*
X180583D01*
G02X180786Y1481305I0J-203D01*
G01Y1480683D01*
G03X180836Y1480551I200J0D01*
G02Y1477639I-1664J-1456D01*
G03X180786Y1477507I150J-132D01*
G01Y1475565D01*
G03X180836Y1475433I200J0D01*
G02Y1472521I-1664J-1456D01*
G03X180786Y1472389I150J-132D01*
G01Y1471767D01*
G02X180583Y1471564I-203J0D01*
G01X177763D01*
G02X177560Y1471767I0J203D01*
G01Y1472389D01*
G03X177510Y1472521I-200J0D01*
G02Y1475433I1664J1456D01*
G03X177560Y1475565I-150J132D01*
G01Y1477507D01*
G03X177510Y1477639I-200J0D01*
G02Y1480551I1664J1456D01*
G03X177560Y1480683I-150J132D01*
G01Y1481305D01*
G02X177763Y1481508I203J0D01*
G37*
G36*
G01X281700D02*
X284520D01*
G02X284722Y1481305I-1J-203D01*
G01Y1480685D01*
G03X284772Y1480553I200J0D01*
G02Y1477637I-1661J-1458D01*
G03X284722Y1477505I150J-132D01*
G01Y1475567D01*
G03X284772Y1475435I200J0D01*
G02Y1472519I-1661J-1458D01*
G03X284722Y1472387I150J-132D01*
G01Y1471767D01*
G02X284520Y1471564I-202J-1D01*
G01X281700D01*
G02X281498Y1471767I1J203D01*
G01Y1472387D01*
G03X281448Y1472519I-200J0D01*
G02Y1475435I1661J1458D01*
G03X281498Y1475567I-150J132D01*
G01Y1477505D01*
G03X281448Y1477637I-200J0D01*
G02Y1480553I1661J1458D01*
G03X281498Y1480685I-150J132D01*
G01Y1481305D01*
G02X281700Y1481508I202J1D01*
G37*
G36*
G01X299023D02*
X301843D01*
G02X302046Y1481305I0J-203D01*
G01Y1480683D01*
G03X302096Y1480551I200J0D01*
G02Y1477639I-1664J-1456D01*
G03X302046Y1477507I150J-132D01*
G01Y1475565D01*
G03X302096Y1475433I200J0D01*
G02Y1472521I-1664J-1456D01*
G03X302046Y1472389I150J-132D01*
G01Y1471767D01*
G02X301843Y1471564I-203J0D01*
G01X299023D01*
G02X298820Y1471767I0J203D01*
G01Y1472389D01*
G03X298770Y1472521I-200J0D01*
G02Y1475433I1664J1456D01*
G03X298820Y1475565I-150J132D01*
G01Y1477507D01*
G03X298770Y1477639I-200J0D01*
G02Y1480551I1664J1456D01*
G03X298820Y1480683I-150J132D01*
G01Y1481305D01*
G02X299023Y1481508I203J0D01*
G37*
G36*
G01X454929D02*
X457749D01*
G02X457952Y1481305I0J-203D01*
G01Y1480683D01*
G03X458002Y1480551I200J0D01*
G02Y1477639I-1664J-1456D01*
G03X457952Y1477507I150J-132D01*
G01Y1475565D01*
G03X458002Y1475433I200J0D01*
G02Y1472521I-1664J-1456D01*
G03X457952Y1472389I150J-132D01*
G01Y1471767D01*
G02X457749Y1471564I-203J0D01*
G01X454929D01*
G02X454726Y1471767I0J203D01*
G01Y1472389D01*
G03X454676Y1472521I-200J0D01*
G02Y1475433I1664J1456D01*
G03X454726Y1475565I-150J132D01*
G01Y1477507D01*
G03X454676Y1477639I-200J0D01*
G02Y1480551I1664J1456D01*
G03X454726Y1480683I-150J132D01*
G01Y1481305D01*
G02X454929Y1481508I203J0D01*
G37*
G36*
G01X472252D02*
X475072D01*
G02X475274Y1481305I-1J-203D01*
G01Y1480685D01*
G03X475324Y1480553I200J0D01*
G02Y1477637I-1661J-1458D01*
G03X475274Y1477505I150J-132D01*
G01Y1475567D01*
G03X475324Y1475435I200J0D01*
G02Y1472519I-1661J-1458D01*
G03X475274Y1472387I150J-132D01*
G01Y1471767D01*
G02X475072Y1471564I-202J-1D01*
G01X472252D01*
G02X472050Y1471767I1J203D01*
G01Y1472387D01*
G03X472000Y1472519I-200J0D01*
G02Y1475435I1661J1458D01*
G03X472050Y1475567I-150J132D01*
G01Y1477505D01*
G03X472000Y1477637I-200J0D01*
G02Y1480553I1661J1458D01*
G03X472050Y1480685I-150J132D01*
G01Y1481305D01*
G02X472252Y1481508I202J1D01*
G37*
G36*
G01X489575D02*
X492395D01*
G02X492598Y1481305I0J-203D01*
G01Y1480683D01*
G03X492648Y1480551I200J0D01*
G02Y1477639I-1664J-1456D01*
G03X492598Y1477507I150J-132D01*
G01Y1475565D01*
G03X492648Y1475433I200J0D01*
G02Y1472521I-1664J-1456D01*
G03X492598Y1472389I150J-132D01*
G01Y1471767D01*
G02X492395Y1471564I-203J0D01*
G01X489575D01*
G02X489372Y1471767I0J203D01*
G01Y1472389D01*
G03X489322Y1472521I-200J0D01*
G02Y1475433I1664J1456D01*
G03X489372Y1475565I-150J132D01*
G01Y1477507D01*
G03X489322Y1477639I-200J0D01*
G02Y1480551I1664J1456D01*
G03X489372Y1480683I-150J132D01*
G01Y1481305D01*
G02X489575Y1481508I203J0D01*
G37*
G36*
G01X506897D02*
X509717D01*
G02X509920Y1481305I0J-203D01*
G01Y1480683D01*
G03X509970Y1480551I200J0D01*
G02Y1477639I-1664J-1456D01*
G03X509920Y1477507I150J-132D01*
G01Y1475565D01*
G03X509970Y1475433I200J0D01*
G02Y1472521I-1664J-1456D01*
G03X509920Y1472389I150J-132D01*
G01Y1471767D01*
G02X509717Y1471564I-203J0D01*
G01X506897D01*
G02X506694Y1471767I0J203D01*
G01Y1472389D01*
G03X506644Y1472521I-200J0D01*
G02Y1475433I1664J1456D01*
G03X506694Y1475565I-150J132D01*
G01Y1477507D01*
G03X506644Y1477639I-200J0D01*
G02Y1480551I1664J1456D01*
G03X506694Y1480683I-150J132D01*
G01Y1481305D01*
G02X506897Y1481508I203J0D01*
G37*
G36*
G01X645480D02*
X648300D01*
G02X648502Y1481305I-1J-203D01*
G01Y1480685D01*
G03X648552Y1480553I200J0D01*
G02Y1477637I-1661J-1458D01*
G03X648502Y1477505I150J-132D01*
G01Y1475567D01*
G03X648552Y1475435I200J0D01*
G02Y1472519I-1661J-1458D01*
G03X648502Y1472387I150J-132D01*
G01Y1471767D01*
G02X648300Y1471564I-202J-1D01*
G01X645480D01*
G02X645278Y1471767I1J203D01*
G01Y1472387D01*
G03X645228Y1472519I-200J0D01*
G02Y1475435I1661J1458D01*
G03X645278Y1475567I-150J132D01*
G01Y1477505D01*
G03X645228Y1477637I-200J0D01*
G02Y1480553I1661J1458D01*
G03X645278Y1480685I-150J132D01*
G01Y1481305D01*
G02X645480Y1481508I202J1D01*
G37*
G36*
G01X662803D02*
X665623D01*
G02X665826Y1481305I0J-203D01*
G01Y1480683D01*
G03X665876Y1480551I200J0D01*
G02Y1477639I-1664J-1456D01*
G03X665826Y1477507I150J-132D01*
G01Y1475565D01*
G03X665876Y1475433I200J0D01*
G02Y1472521I-1664J-1456D01*
G03X665826Y1472389I150J-132D01*
G01Y1471767D01*
G02X665623Y1471564I-203J0D01*
G01X662803D01*
G02X662600Y1471767I0J203D01*
G01Y1472389D01*
G03X662550Y1472521I-200J0D01*
G02Y1475433I1664J1456D01*
G03X662600Y1475565I-150J132D01*
G01Y1477507D01*
G03X662550Y1477639I-200J0D01*
G02Y1480551I1664J1456D01*
G03X662600Y1480683I-150J132D01*
G01Y1481305D01*
G02X662803Y1481508I203J0D01*
G37*
G36*
G01X680125D02*
X682945D01*
G02X683148Y1481305I0J-203D01*
G01Y1480683D01*
G03X683198Y1480551I200J0D01*
G02Y1477639I-1664J-1456D01*
G03X683148Y1477507I150J-132D01*
G01Y1475565D01*
G03X683198Y1475433I200J0D01*
G02Y1472521I-1664J-1456D01*
G03X683148Y1472389I150J-132D01*
G01Y1471767D01*
G02X682945Y1471564I-203J0D01*
G01X680125D01*
G02X679922Y1471767I0J203D01*
G01Y1472389D01*
G03X679872Y1472521I-200J0D01*
G02Y1475433I1664J1456D01*
G03X679922Y1475565I-150J132D01*
G01Y1477507D01*
G03X679872Y1477639I-200J0D01*
G02Y1480551I1664J1456D01*
G03X679922Y1480683I-150J132D01*
G01Y1481305D01*
G02X680125Y1481508I203J0D01*
G37*
G36*
G01X1165086D02*
X1167906D01*
G02X1168108Y1481305I-1J-203D01*
G01Y1480685D01*
G03X1168158Y1480553I200J0D01*
G02Y1477637I-1661J-1458D01*
G03X1168108Y1477505I150J-132D01*
G01Y1475567D01*
G03X1168158Y1475435I200J0D01*
G02Y1472519I-1661J-1458D01*
G03X1168108Y1472387I150J-132D01*
G01Y1471767D01*
G02X1167906Y1471564I-202J-1D01*
G01X1165086D01*
G02X1164884Y1471767I1J203D01*
G01Y1472387D01*
G03X1164834Y1472519I-200J0D01*
G02Y1475435I1661J1458D01*
G03X1164884Y1475567I-150J132D01*
G01Y1477505D01*
G03X1164834Y1477637I-200J0D01*
G02Y1480553I1661J1458D01*
G03X1164884Y1480685I-150J132D01*
G01Y1481305D01*
G02X1165086Y1481508I202J1D01*
G37*
G36*
G01X1182408D02*
X1185228D01*
G02X1185430Y1481305I-1J-203D01*
G01Y1480685D01*
G03X1185480Y1480553I200J0D01*
G02Y1477637I-1661J-1458D01*
G03X1185430Y1477505I150J-132D01*
G01Y1475567D01*
G03X1185480Y1475435I200J0D01*
G02Y1472519I-1661J-1458D01*
G03X1185430Y1472387I150J-132D01*
G01Y1471767D01*
G02X1185228Y1471564I-202J-1D01*
G01X1182408D01*
G02X1182206Y1471767I1J203D01*
G01Y1472387D01*
G03X1182156Y1472519I-200J0D01*
G02Y1475435I1661J1458D01*
G03X1182206Y1475567I-150J132D01*
G01Y1477505D01*
G03X1182156Y1477637I-200J0D01*
G02Y1480553I1661J1458D01*
G03X1182206Y1480685I-150J132D01*
G01Y1481305D01*
G02X1182408Y1481508I202J1D01*
G37*
G36*
G01X1303669D02*
X1306489D01*
G02X1306692Y1481305I0J-203D01*
G01Y1480683D01*
G03X1306742Y1480551I200J0D01*
G02Y1477639I-1664J-1456D01*
G03X1306692Y1477507I150J-132D01*
G01Y1475565D01*
G03X1306742Y1475433I200J0D01*
G02Y1472521I-1664J-1456D01*
G03X1306692Y1472389I150J-132D01*
G01Y1471767D01*
G02X1306489Y1471564I-203J0D01*
G01X1303669D01*
G02X1303466Y1471767I0J203D01*
G01Y1472389D01*
G03X1303416Y1472521I-200J0D01*
G02Y1475433I1664J1456D01*
G03X1303466Y1475565I-150J132D01*
G01Y1477507D01*
G03X1303416Y1477639I-200J0D01*
G02Y1480551I1664J1456D01*
G03X1303466Y1480683I-150J132D01*
G01Y1481305D01*
G02X1303669Y1481508I203J0D01*
G37*
G36*
G01X1320992D02*
X1323812D01*
G02X1324014Y1481305I-1J-203D01*
G01Y1480685D01*
G03X1324064Y1480553I200J0D01*
G02Y1477637I-1661J-1458D01*
G03X1324014Y1477505I150J-132D01*
G01Y1475567D01*
G03X1324064Y1475435I200J0D01*
G02Y1472519I-1661J-1458D01*
G03X1324014Y1472387I150J-132D01*
G01Y1471767D01*
G02X1323812Y1471564I-202J-1D01*
G01X1320992D01*
G02X1320790Y1471767I1J203D01*
G01Y1472387D01*
G03X1320740Y1472519I-200J0D01*
G02Y1475435I1661J1458D01*
G03X1320790Y1475567I-150J132D01*
G01Y1477505D01*
G03X1320740Y1477637I-200J0D01*
G02Y1480553I1661J1458D01*
G03X1320790Y1480685I-150J132D01*
G01Y1481305D01*
G02X1320992Y1481508I202J1D01*
G37*
G36*
G01X1338315D02*
X1341135D01*
G02X1341338Y1481305I0J-203D01*
G01Y1480683D01*
G03X1341388Y1480551I200J0D01*
G02Y1477639I-1664J-1456D01*
G03X1341338Y1477507I150J-132D01*
G01Y1475565D01*
G03X1341388Y1475433I200J0D01*
G02Y1472521I-1664J-1456D01*
G03X1341338Y1472389I150J-132D01*
G01Y1471767D01*
G02X1341135Y1471564I-203J0D01*
G01X1338315D01*
G02X1338112Y1471767I0J203D01*
G01Y1472389D01*
G03X1338062Y1472521I-200J0D01*
G02Y1475433I1664J1456D01*
G03X1338112Y1475565I-150J132D01*
G01Y1477507D01*
G03X1338062Y1477639I-200J0D01*
G02Y1480551I1664J1456D01*
G03X1338112Y1480683I-150J132D01*
G01Y1481305D01*
G02X1338315Y1481508I203J0D01*
G37*
G36*
G01X1355637D02*
X1358457D01*
G02X1358660Y1481305I0J-203D01*
G01Y1480683D01*
G03X1358710Y1480551I200J0D01*
G02Y1477639I-1664J-1456D01*
G03X1358660Y1477507I150J-132D01*
G01Y1475565D01*
G03X1358710Y1475433I200J0D01*
G02Y1472521I-1664J-1456D01*
G03X1358660Y1472389I150J-132D01*
G01Y1471767D01*
G02X1358457Y1471564I-203J0D01*
G01X1355637D01*
G02X1355434Y1471767I0J203D01*
G01Y1472389D01*
G03X1355384Y1472521I-200J0D01*
G02Y1475433I1664J1456D01*
G03X1355434Y1475565I-150J132D01*
G01Y1477507D01*
G03X1355384Y1477639I-200J0D01*
G02Y1480551I1664J1456D01*
G03X1355434Y1480683I-150J132D01*
G01Y1481305D01*
G02X1355637Y1481508I203J0D01*
G37*
G36*
G01X1476897D02*
X1479717D01*
G02X1479920Y1481305I0J-203D01*
G01Y1480683D01*
G03X1479970Y1480551I200J0D01*
G02Y1477639I-1664J-1456D01*
G03X1479920Y1477507I150J-132D01*
G01Y1475565D01*
G03X1479970Y1475433I200J0D01*
G02Y1472521I-1664J-1456D01*
G03X1479920Y1472389I150J-132D01*
G01Y1471767D01*
G02X1479717Y1471564I-203J0D01*
G01X1476897D01*
G02X1476694Y1471767I0J203D01*
G01Y1472389D01*
G03X1476644Y1472521I-200J0D01*
G02Y1475433I1664J1456D01*
G03X1476694Y1475565I-150J132D01*
G01Y1477507D01*
G03X1476644Y1477639I-200J0D01*
G02Y1480551I1664J1456D01*
G03X1476694Y1480683I-150J132D01*
G01Y1481305D01*
G02X1476897Y1481508I203J0D01*
G37*
G36*
G01X1494220D02*
X1497040D01*
G02X1497242Y1481305I-1J-203D01*
G01Y1480685D01*
G03X1497292Y1480553I200J0D01*
G02Y1477637I-1661J-1458D01*
G03X1497242Y1477505I150J-132D01*
G01Y1475567D01*
G03X1497292Y1475435I200J0D01*
G02Y1472519I-1661J-1458D01*
G03X1497242Y1472387I150J-132D01*
G01Y1471767D01*
G02X1497040Y1471564I-202J-1D01*
G01X1494220D01*
G02X1494018Y1471767I1J203D01*
G01Y1472387D01*
G03X1493968Y1472519I-200J0D01*
G02Y1475435I1661J1458D01*
G03X1494018Y1475567I-150J132D01*
G01Y1477505D01*
G03X1493968Y1477637I-200J0D01*
G02Y1480553I1661J1458D01*
G03X1494018Y1480685I-150J132D01*
G01Y1481305D01*
G02X1494220Y1481508I202J1D01*
G37*
G36*
G01X1511543D02*
X1514363D01*
G02X1514566Y1481305I0J-203D01*
G01Y1480683D01*
G03X1514616Y1480551I200J0D01*
G02Y1477639I-1664J-1456D01*
G03X1514566Y1477507I150J-132D01*
G01Y1475565D01*
G03X1514616Y1475433I200J0D01*
G02Y1472521I-1664J-1456D01*
G03X1514566Y1472389I150J-132D01*
G01Y1471767D01*
G02X1514363Y1471564I-203J0D01*
G01X1511543D01*
G02X1511340Y1471767I0J203D01*
G01Y1472389D01*
G03X1511290Y1472521I-200J0D01*
G02Y1475433I1664J1456D01*
G03X1511340Y1475565I-150J132D01*
G01Y1477507D01*
G03X1511290Y1477639I-200J0D01*
G02Y1480551I1664J1456D01*
G03X1511340Y1480683I-150J132D01*
G01Y1481305D01*
G02X1511543Y1481508I203J0D01*
G37*
G36*
G01X1528865D02*
X1531685D01*
G02X1531888Y1481305I0J-203D01*
G01Y1480683D01*
G03X1531938Y1480551I200J0D01*
G02Y1477639I-1664J-1456D01*
G03X1531888Y1477507I150J-132D01*
G01Y1475565D01*
G03X1531938Y1475433I200J0D01*
G02Y1472521I-1664J-1456D01*
G03X1531888Y1472389I150J-132D01*
G01Y1471767D01*
G02X1531685Y1471564I-203J0D01*
G01X1528865D01*
G02X1528662Y1471767I0J203D01*
G01Y1472389D01*
G03X1528612Y1472521I-200J0D01*
G02Y1475433I1664J1456D01*
G03X1528662Y1475565I-150J132D01*
G01Y1477507D01*
G03X1528612Y1477639I-200J0D01*
G02Y1480551I1664J1456D01*
G03X1528662Y1480683I-150J132D01*
G01Y1481305D01*
G02X1528865Y1481508I203J0D01*
G37*
G36*
G01X1684771D02*
X1687591D01*
G02X1687794Y1481305I0J-203D01*
G01Y1480683D01*
G03X1687844Y1480551I200J0D01*
G02Y1477639I-1664J-1456D01*
G03X1687794Y1477507I150J-132D01*
G01Y1475565D01*
G03X1687844Y1475433I200J0D01*
G02Y1472521I-1664J-1456D01*
G03X1687794Y1472389I150J-132D01*
G01Y1471767D01*
G02X1687591Y1471564I-203J0D01*
G01X1684771D01*
G02X1684568Y1471767I0J203D01*
G01Y1472389D01*
G03X1684518Y1472521I-200J0D01*
G02Y1475433I1664J1456D01*
G03X1684568Y1475565I-150J132D01*
G01Y1477507D01*
G03X1684518Y1477639I-200J0D01*
G02Y1480551I1664J1456D01*
G03X1684568Y1480683I-150J132D01*
G01Y1481305D01*
G02X1684771Y1481508I203J0D01*
G37*
G36*
G01X1702093D02*
X1704913D01*
G02X1705116Y1481305I0J-203D01*
G01Y1480683D01*
G03X1705166Y1480551I200J0D01*
G02Y1477639I-1664J-1456D01*
G03X1705116Y1477507I150J-132D01*
G01Y1475565D01*
G03X1705166Y1475433I200J0D01*
G02Y1472521I-1664J-1456D01*
G03X1705116Y1472389I150J-132D01*
G01Y1471767D01*
G02X1704913Y1471564I-203J0D01*
G01X1702093D01*
G02X1701890Y1471767I0J203D01*
G01Y1472389D01*
G03X1701840Y1472521I-200J0D01*
G02Y1475433I1664J1456D01*
G03X1701890Y1475565I-150J132D01*
G01Y1477507D01*
G03X1701840Y1477639I-200J0D01*
G02Y1480551I1664J1456D01*
G03X1701890Y1480683I-150J132D01*
G01Y1481305D01*
G02X1702093Y1481508I203J0D01*
G37*
G36*
G01X134456Y1485838D02*
X137276D01*
G02X137478Y1485635I-1J-203D01*
G01Y1485016D01*
G03X137528Y1484884I200J0D01*
G02Y1481968I-1661J-1458D01*
G03X137478Y1481836I150J-132D01*
G01Y1479898D01*
G03X137528Y1479766I200J0D01*
G02Y1476850I-1661J-1458D01*
G03X137478Y1476718I150J-132D01*
G01Y1476097D01*
G02X137276Y1475894I-202J-1D01*
G01X134456D01*
G02X134254Y1476097I1J203D01*
G01Y1476718D01*
G03X134204Y1476850I-200J0D01*
G02Y1479766I1661J1458D01*
G03X134254Y1479898I-150J132D01*
G01Y1481836D01*
G03X134204Y1481968I-200J0D01*
G02Y1484884I1661J1458D01*
G03X134254Y1485016I-150J132D01*
G01Y1485635D01*
G02X134456Y1485838I202J1D01*
G37*
G36*
G01X151779D02*
X154599D01*
G02X154802Y1485635I0J-203D01*
G01Y1485014D01*
G03X154852Y1484882I200J0D01*
G02Y1481970I-1664J-1456D01*
G03X154802Y1481838I150J-132D01*
G01Y1479896D01*
G03X154852Y1479764I200J0D01*
G02Y1476852I-1664J-1456D01*
G03X154802Y1476720I150J-132D01*
G01Y1476097D01*
G02X154599Y1475894I-203J0D01*
G01X151779D01*
G02X151576Y1476097I0J203D01*
G01Y1476720D01*
G03X151526Y1476852I-200J0D01*
G02Y1479764I1664J1456D01*
G03X151576Y1479896I-150J132D01*
G01Y1481838D01*
G03X151526Y1481970I-200J0D01*
G02Y1484882I1664J1456D01*
G03X151576Y1485014I-150J132D01*
G01Y1485635D01*
G02X151779Y1485838I203J0D01*
G37*
G36*
G01X169102D02*
X171922D01*
G02X172124Y1485635I-1J-203D01*
G01Y1485016D01*
G03X172174Y1484884I200J0D01*
G02Y1481968I-1661J-1458D01*
G03X172124Y1481836I150J-132D01*
G01Y1479898D01*
G03X172174Y1479766I200J0D01*
G02Y1476850I-1661J-1458D01*
G03X172124Y1476718I150J-132D01*
G01Y1476097D01*
G02X171922Y1475894I-202J-1D01*
G01X169102D01*
G02X168900Y1476097I1J203D01*
G01Y1476718D01*
G03X168850Y1476850I-200J0D01*
G02Y1479766I1661J1458D01*
G03X168900Y1479898I-150J132D01*
G01Y1481836D01*
G03X168850Y1481968I-200J0D01*
G02Y1484884I1661J1458D01*
G03X168900Y1485016I-150J132D01*
G01Y1485635D01*
G02X169102Y1485838I202J1D01*
G37*
G36*
G01X290361D02*
X293181D01*
G02X293384Y1485635I0J-203D01*
G01Y1485014D01*
G03X293434Y1484882I200J0D01*
G02Y1481970I-1664J-1456D01*
G03X293384Y1481838I150J-132D01*
G01Y1479896D01*
G03X293434Y1479764I200J0D01*
G02Y1476852I-1664J-1456D01*
G03X293384Y1476720I150J-132D01*
G01Y1476097D01*
G02X293181Y1475894I-203J0D01*
G01X290361D01*
G02X290158Y1476097I0J203D01*
G01Y1476720D01*
G03X290108Y1476852I-200J0D01*
G02Y1479764I1664J1456D01*
G03X290158Y1479896I-150J132D01*
G01Y1481838D01*
G03X290108Y1481970I-200J0D01*
G02Y1484882I1664J1456D01*
G03X290158Y1485014I-150J132D01*
G01Y1485635D01*
G02X290361Y1485838I203J0D01*
G37*
G36*
G01X463590D02*
X466410D01*
G02X466612Y1485635I-1J-203D01*
G01Y1485016D01*
G03X466662Y1484884I200J0D01*
G02Y1481968I-1661J-1458D01*
G03X466612Y1481836I150J-132D01*
G01Y1479898D01*
G03X466662Y1479766I200J0D01*
G02Y1476850I-1661J-1458D01*
G03X466612Y1476718I150J-132D01*
G01Y1476097D01*
G02X466410Y1475894I-202J-1D01*
G01X463590D01*
G02X463388Y1476097I1J203D01*
G01Y1476718D01*
G03X463338Y1476850I-200J0D01*
G02Y1479766I1661J1458D01*
G03X463388Y1479898I-150J132D01*
G01Y1481836D01*
G03X463338Y1481968I-200J0D01*
G02Y1484884I1661J1458D01*
G03X463388Y1485016I-150J132D01*
G01Y1485635D01*
G02X463590Y1485838I202J1D01*
G37*
G36*
G01X480913D02*
X483733D01*
G02X483936Y1485635I0J-203D01*
G01Y1485014D01*
G03X483986Y1484882I200J0D01*
G02Y1481970I-1664J-1456D01*
G03X483936Y1481838I150J-132D01*
G01Y1479896D01*
G03X483986Y1479764I200J0D01*
G02Y1476852I-1664J-1456D01*
G03X483936Y1476720I150J-132D01*
G01Y1476097D01*
G02X483733Y1475894I-203J0D01*
G01X480913D01*
G02X480710Y1476097I0J203D01*
G01Y1476720D01*
G03X480660Y1476852I-200J0D01*
G02Y1479764I1664J1456D01*
G03X480710Y1479896I-150J132D01*
G01Y1481838D01*
G03X480660Y1481970I-200J0D01*
G02Y1484882I1664J1456D01*
G03X480710Y1485014I-150J132D01*
G01Y1485635D01*
G02X480913Y1485838I203J0D01*
G37*
G36*
G01X498236D02*
X501056D01*
G02X501258Y1485635I-1J-203D01*
G01Y1485016D01*
G03X501308Y1484884I200J0D01*
G02Y1481968I-1661J-1458D01*
G03X501258Y1481836I150J-132D01*
G01Y1479898D01*
G03X501308Y1479766I200J0D01*
G02Y1476850I-1661J-1458D01*
G03X501258Y1476718I150J-132D01*
G01Y1476097D01*
G02X501056Y1475894I-202J-1D01*
G01X498236D01*
G02X498034Y1476097I1J203D01*
G01Y1476718D01*
G03X497984Y1476850I-200J0D01*
G02Y1479766I1661J1458D01*
G03X498034Y1479898I-150J132D01*
G01Y1481836D01*
G03X497984Y1481968I-200J0D01*
G02Y1484884I1661J1458D01*
G03X498034Y1485016I-150J132D01*
G01Y1485635D01*
G02X498236Y1485838I202J1D01*
G37*
G36*
G01X515559D02*
X518379D01*
G02X518582Y1485635I0J-203D01*
G01Y1485014D01*
G03X518632Y1484882I200J0D01*
G02Y1481970I-1664J-1456D01*
G03X518582Y1481838I150J-132D01*
G01Y1479896D01*
G03X518632Y1479764I200J0D01*
G02Y1476852I-1664J-1456D01*
G03X518582Y1476720I150J-132D01*
G01Y1476097D01*
G02X518379Y1475894I-203J0D01*
G01X515559D01*
G02X515356Y1476097I0J203D01*
G01Y1476720D01*
G03X515306Y1476852I-200J0D01*
G02Y1479764I1664J1456D01*
G03X515356Y1479896I-150J132D01*
G01Y1481838D01*
G03X515306Y1481970I-200J0D01*
G02Y1484882I1664J1456D01*
G03X515356Y1485014I-150J132D01*
G01Y1485635D01*
G02X515559Y1485838I203J0D01*
G37*
G36*
G01X654141D02*
X656961D01*
G02X657164Y1485635I0J-203D01*
G01Y1485014D01*
G03X657214Y1484882I200J0D01*
G02Y1481970I-1664J-1456D01*
G03X657164Y1481838I150J-132D01*
G01Y1479896D01*
G03X657214Y1479764I200J0D01*
G02Y1476852I-1664J-1456D01*
G03X657164Y1476720I150J-132D01*
G01Y1476097D01*
G02X656961Y1475894I-203J0D01*
G01X654141D01*
G02X653938Y1476097I0J203D01*
G01Y1476720D01*
G03X653888Y1476852I-200J0D01*
G02Y1479764I1664J1456D01*
G03X653938Y1479896I-150J132D01*
G01Y1481838D01*
G03X653888Y1481970I-200J0D01*
G02Y1484882I1664J1456D01*
G03X653938Y1485014I-150J132D01*
G01Y1485635D01*
G02X654141Y1485838I203J0D01*
G37*
G36*
G01X671464D02*
X674284D01*
G02X674486Y1485635I-1J-203D01*
G01Y1485016D01*
G03X674536Y1484884I200J0D01*
G02Y1481968I-1661J-1458D01*
G03X674486Y1481836I150J-132D01*
G01Y1479898D01*
G03X674536Y1479766I200J0D01*
G02Y1476850I-1661J-1458D01*
G03X674486Y1476718I150J-132D01*
G01Y1476097D01*
G02X674284Y1475894I-202J-1D01*
G01X671464D01*
G02X671262Y1476097I1J203D01*
G01Y1476718D01*
G03X671212Y1476850I-200J0D01*
G02Y1479766I1661J1458D01*
G03X671262Y1479898I-150J132D01*
G01Y1481836D01*
G03X671212Y1481968I-200J0D01*
G02Y1484884I1661J1458D01*
G03X671262Y1485016I-150J132D01*
G01Y1485635D01*
G02X671464Y1485838I202J1D01*
G37*
G36*
G01X688787D02*
X691607D01*
G02X691810Y1485635I0J-203D01*
G01Y1485014D01*
G03X691860Y1484882I200J0D01*
G02Y1481970I-1664J-1456D01*
G03X691810Y1481838I150J-132D01*
G01Y1479896D01*
G03X691860Y1479764I200J0D01*
G02Y1476852I-1664J-1456D01*
G03X691810Y1476720I150J-132D01*
G01Y1476097D01*
G02X691607Y1475894I-203J0D01*
G01X688787D01*
G02X688584Y1476097I0J203D01*
G01Y1476720D01*
G03X688534Y1476852I-200J0D01*
G02Y1479764I1664J1456D01*
G03X688584Y1479896I-150J132D01*
G01Y1481838D01*
G03X688534Y1481970I-200J0D01*
G02Y1484882I1664J1456D01*
G03X688584Y1485014I-150J132D01*
G01Y1485635D01*
G02X688787Y1485838I203J0D01*
G37*
G36*
G01X1173747D02*
X1176567D01*
G02X1176770Y1485635I0J-203D01*
G01Y1485014D01*
G03X1176820Y1484882I200J0D01*
G02Y1481970I-1664J-1456D01*
G03X1176770Y1481838I150J-132D01*
G01Y1479896D01*
G03X1176820Y1479764I200J0D01*
G02Y1476852I-1664J-1456D01*
G03X1176770Y1476720I150J-132D01*
G01Y1476097D01*
G02X1176567Y1475894I-203J0D01*
G01X1173747D01*
G02X1173544Y1476097I0J203D01*
G01Y1476720D01*
G03X1173494Y1476852I-200J0D01*
G02Y1479764I1664J1456D01*
G03X1173544Y1479896I-150J132D01*
G01Y1481838D01*
G03X1173494Y1481970I-200J0D01*
G02Y1484882I1664J1456D01*
G03X1173544Y1485014I-150J132D01*
G01Y1485635D01*
G02X1173747Y1485838I203J0D01*
G37*
G36*
G01X1191070D02*
X1193890D01*
G02X1194092Y1485635I-1J-203D01*
G01Y1485016D01*
G03X1194142Y1484884I200J0D01*
G02Y1481968I-1661J-1458D01*
G03X1194092Y1481836I150J-132D01*
G01Y1479898D01*
G03X1194142Y1479766I200J0D01*
G02Y1476850I-1661J-1458D01*
G03X1194092Y1476718I150J-132D01*
G01Y1476097D01*
G02X1193890Y1475894I-202J-1D01*
G01X1191070D01*
G02X1190868Y1476097I1J203D01*
G01Y1476718D01*
G03X1190818Y1476850I-200J0D01*
G02Y1479766I1661J1458D01*
G03X1190868Y1479898I-150J132D01*
G01Y1481836D01*
G03X1190818Y1481968I-200J0D01*
G02Y1484884I1661J1458D01*
G03X1190868Y1485016I-150J132D01*
G01Y1485635D01*
G02X1191070Y1485838I202J1D01*
G37*
G36*
G01X1312330D02*
X1315150D01*
G02X1315352Y1485635I-1J-203D01*
G01Y1485016D01*
G03X1315402Y1484884I200J0D01*
G02Y1481968I-1661J-1458D01*
G03X1315352Y1481836I150J-132D01*
G01Y1479898D01*
G03X1315402Y1479766I200J0D01*
G02Y1476850I-1661J-1458D01*
G03X1315352Y1476718I150J-132D01*
G01Y1476097D01*
G02X1315150Y1475894I-202J-1D01*
G01X1312330D01*
G02X1312128Y1476097I1J203D01*
G01Y1476718D01*
G03X1312078Y1476850I-200J0D01*
G02Y1479766I1661J1458D01*
G03X1312128Y1479898I-150J132D01*
G01Y1481836D01*
G03X1312078Y1481968I-200J0D01*
G02Y1484884I1661J1458D01*
G03X1312128Y1485016I-150J132D01*
G01Y1485635D01*
G02X1312330Y1485838I202J1D01*
G37*
G36*
G01X1329653D02*
X1332473D01*
G02X1332676Y1485635I0J-203D01*
G01Y1485014D01*
G03X1332726Y1484882I200J0D01*
G02Y1481970I-1664J-1456D01*
G03X1332676Y1481838I150J-132D01*
G01Y1479896D01*
G03X1332726Y1479764I200J0D01*
G02Y1476852I-1664J-1456D01*
G03X1332676Y1476720I150J-132D01*
G01Y1476097D01*
G02X1332473Y1475894I-203J0D01*
G01X1329653D01*
G02X1329450Y1476097I0J203D01*
G01Y1476720D01*
G03X1329400Y1476852I-200J0D01*
G02Y1479764I1664J1456D01*
G03X1329450Y1479896I-150J132D01*
G01Y1481838D01*
G03X1329400Y1481970I-200J0D01*
G02Y1484882I1664J1456D01*
G03X1329450Y1485014I-150J132D01*
G01Y1485635D01*
G02X1329653Y1485838I203J0D01*
G37*
G36*
G01X1346976D02*
X1349796D01*
G02X1349998Y1485635I-1J-203D01*
G01Y1485016D01*
G03X1350048Y1484884I200J0D01*
G02Y1481968I-1661J-1458D01*
G03X1349998Y1481836I150J-132D01*
G01Y1479898D01*
G03X1350048Y1479766I200J0D01*
G02Y1476850I-1661J-1458D01*
G03X1349998Y1476718I150J-132D01*
G01Y1476097D01*
G02X1349796Y1475894I-202J-1D01*
G01X1346976D01*
G02X1346774Y1476097I1J203D01*
G01Y1476718D01*
G03X1346724Y1476850I-200J0D01*
G02Y1479766I1661J1458D01*
G03X1346774Y1479898I-150J132D01*
G01Y1481836D01*
G03X1346724Y1481968I-200J0D01*
G02Y1484884I1661J1458D01*
G03X1346774Y1485016I-150J132D01*
G01Y1485635D01*
G02X1346976Y1485838I202J1D01*
G37*
G36*
G01X1364299D02*
X1367119D01*
G02X1367322Y1485635I0J-203D01*
G01Y1485014D01*
G03X1367372Y1484882I200J0D01*
G02Y1481970I-1664J-1456D01*
G03X1367322Y1481838I150J-132D01*
G01Y1479896D01*
G03X1367372Y1479764I200J0D01*
G02Y1476852I-1664J-1456D01*
G03X1367322Y1476720I150J-132D01*
G01Y1476097D01*
G02X1367119Y1475894I-203J0D01*
G01X1364299D01*
G02X1364096Y1476097I0J203D01*
G01Y1476720D01*
G03X1364046Y1476852I-200J0D01*
G02Y1479764I1664J1456D01*
G03X1364096Y1479896I-150J132D01*
G01Y1481838D01*
G03X1364046Y1481970I-200J0D01*
G02Y1484882I1664J1456D01*
G03X1364096Y1485014I-150J132D01*
G01Y1485635D01*
G02X1364299Y1485838I203J0D01*
G37*
G36*
G01X1485558D02*
X1488378D01*
G02X1488580Y1485635I-1J-203D01*
G01Y1485016D01*
G03X1488630Y1484884I200J0D01*
G02Y1481968I-1661J-1458D01*
G03X1488580Y1481836I150J-132D01*
G01Y1479898D01*
G03X1488630Y1479766I200J0D01*
G02Y1476850I-1661J-1458D01*
G03X1488580Y1476718I150J-132D01*
G01Y1476097D01*
G02X1488378Y1475894I-202J-1D01*
G01X1485558D01*
G02X1485356Y1476097I1J203D01*
G01Y1476718D01*
G03X1485306Y1476850I-200J0D01*
G02Y1479766I1661J1458D01*
G03X1485356Y1479898I-150J132D01*
G01Y1481836D01*
G03X1485306Y1481968I-200J0D01*
G02Y1484884I1661J1458D01*
G03X1485356Y1485016I-150J132D01*
G01Y1485635D01*
G02X1485558Y1485838I202J1D01*
G37*
G36*
G01X1502881D02*
X1505701D01*
G02X1505904Y1485635I0J-203D01*
G01Y1485014D01*
G03X1505954Y1484882I200J0D01*
G02Y1481970I-1664J-1456D01*
G03X1505904Y1481838I150J-132D01*
G01Y1479896D01*
G03X1505954Y1479764I200J0D01*
G02Y1476852I-1664J-1456D01*
G03X1505904Y1476720I150J-132D01*
G01Y1476097D01*
G02X1505701Y1475894I-203J0D01*
G01X1502881D01*
G02X1502678Y1476097I0J203D01*
G01Y1476720D01*
G03X1502628Y1476852I-200J0D01*
G02Y1479764I1664J1456D01*
G03X1502678Y1479896I-150J132D01*
G01Y1481838D01*
G03X1502628Y1481970I-200J0D01*
G02Y1484882I1664J1456D01*
G03X1502678Y1485014I-150J132D01*
G01Y1485635D01*
G02X1502881Y1485838I203J0D01*
G37*
G36*
G01X1520204D02*
X1523024D01*
G02X1523226Y1485635I-1J-203D01*
G01Y1485016D01*
G03X1523276Y1484884I200J0D01*
G02Y1481968I-1661J-1458D01*
G03X1523226Y1481836I150J-132D01*
G01Y1479898D01*
G03X1523276Y1479766I200J0D01*
G02Y1476850I-1661J-1458D01*
G03X1523226Y1476718I150J-132D01*
G01Y1476097D01*
G02X1523024Y1475894I-202J-1D01*
G01X1520204D01*
G02X1520002Y1476097I1J203D01*
G01Y1476718D01*
G03X1519952Y1476850I-200J0D01*
G02Y1479766I1661J1458D01*
G03X1520002Y1479898I-150J132D01*
G01Y1481836D01*
G03X1519952Y1481968I-200J0D01*
G02Y1484884I1661J1458D01*
G03X1520002Y1485016I-150J132D01*
G01Y1485635D01*
G02X1520204Y1485838I202J1D01*
G37*
G36*
G01X1537527D02*
X1540347D01*
G02X1540550Y1485635I0J-203D01*
G01Y1485014D01*
G03X1540600Y1484882I200J0D01*
G02Y1481970I-1664J-1456D01*
G03X1540550Y1481838I150J-132D01*
G01Y1479896D01*
G03X1540600Y1479764I200J0D01*
G02Y1476852I-1664J-1456D01*
G03X1540550Y1476720I150J-132D01*
G01Y1476097D01*
G02X1540347Y1475894I-203J0D01*
G01X1537527D01*
G02X1537324Y1476097I0J203D01*
G01Y1476720D01*
G03X1537274Y1476852I-200J0D01*
G02Y1479764I1664J1456D01*
G03X1537324Y1479896I-150J132D01*
G01Y1481838D01*
G03X1537274Y1481970I-200J0D01*
G02Y1484882I1664J1456D01*
G03X1537324Y1485014I-150J132D01*
G01Y1485635D01*
G02X1537527Y1485838I203J0D01*
G37*
G36*
G01X1693432D02*
X1696252D01*
G02X1696454Y1485635I-1J-203D01*
G01Y1485016D01*
G03X1696504Y1484884I200J0D01*
G02Y1481968I-1661J-1458D01*
G03X1696454Y1481836I150J-132D01*
G01Y1479898D01*
G03X1696504Y1479766I200J0D01*
G02Y1476850I-1661J-1458D01*
G03X1696454Y1476718I150J-132D01*
G01Y1476097D01*
G02X1696252Y1475894I-202J-1D01*
G01X1693432D01*
G02X1693230Y1476097I1J203D01*
G01Y1476718D01*
G03X1693180Y1476850I-200J0D01*
G02Y1479766I1661J1458D01*
G03X1693230Y1479898I-150J132D01*
G01Y1481836D01*
G03X1693180Y1481968I-200J0D01*
G02Y1484884I1661J1458D01*
G03X1693230Y1485016I-150J132D01*
G01Y1485635D01*
G02X1693432Y1485838I202J1D01*
G37*
G36*
G01X1710755D02*
X1713575D01*
G02X1713778Y1485635I0J-203D01*
G01Y1485014D01*
G03X1713828Y1484882I200J0D01*
G02Y1481970I-1664J-1456D01*
G03X1713778Y1481838I150J-132D01*
G01Y1479896D01*
G03X1713828Y1479764I200J0D01*
G02Y1476852I-1664J-1456D01*
G03X1713778Y1476720I150J-132D01*
G01Y1476097D01*
G02X1713575Y1475894I-203J0D01*
G01X1710755D01*
G02X1710552Y1476097I0J203D01*
G01Y1476720D01*
G03X1710502Y1476852I-200J0D01*
G02Y1479764I1664J1456D01*
G03X1710552Y1479896I-150J132D01*
G01Y1481838D01*
G03X1710502Y1481970I-200J0D01*
G02Y1484882I1664J1456D01*
G03X1710552Y1485014I-150J132D01*
G01Y1485635D01*
G02X1710755Y1485838I203J0D01*
G37*
G36*
G01X186425D02*
X189245D01*
G02X189448Y1485636I1J-202D01*
G01Y1485014D01*
G03X189498Y1484882I200J0D01*
G02Y1481970I-1664J-1456D01*
G03X189448Y1481838I150J-132D01*
G01Y1479896D01*
G03X189498Y1479764I200J0D01*
G02Y1476852I-1664J-1456D01*
G03X189448Y1476720I150J-132D01*
G01Y1476098D01*
G02X189245Y1475896I-203J1D01*
G01X186425D01*
G02X186222Y1476098I-1J202D01*
G01Y1476720D01*
G03X186172Y1476852I-200J0D01*
G02Y1479764I1664J1456D01*
G03X186222Y1479896I-150J132D01*
G01Y1481838D01*
G03X186172Y1481970I-200J0D01*
G02Y1484882I1664J1456D01*
G03X186222Y1485014I-150J132D01*
G01Y1485636D01*
G02X186425Y1485838I203J-1D01*
G37*
G36*
G01X125795Y1496862D02*
X128615D01*
G02X128818Y1496659I0J-203D01*
G01Y1496037D01*
G03X128868Y1495905I200J0D01*
G02Y1492993I-1664J-1456D01*
G03X128818Y1492861I150J-132D01*
G01Y1490919D01*
G03X128868Y1490787I200J0D01*
G02Y1487875I-1664J-1456D01*
G03X128818Y1487743I150J-132D01*
G01Y1487121D01*
G02X128615Y1486918I-203J0D01*
G01X125795D01*
G02X125592Y1487121I0J203D01*
G01Y1487743D01*
G03X125542Y1487875I-200J0D01*
G02Y1490787I1664J1456D01*
G03X125592Y1490919I-150J132D01*
G01Y1492861D01*
G03X125542Y1492993I-200J0D01*
G02Y1495905I1664J1456D01*
G03X125592Y1496037I-150J132D01*
G01Y1496659D01*
G02X125795Y1496862I203J0D01*
G37*
G36*
G01X143118D02*
X145938D01*
G02X146140Y1496659I-1J-203D01*
G01Y1496039D01*
G03X146190Y1495907I200J0D01*
G02Y1492991I-1661J-1458D01*
G03X146140Y1492859I150J-132D01*
G01Y1490921D01*
G03X146190Y1490789I200J0D01*
G02Y1487873I-1661J-1458D01*
G03X146140Y1487741I150J-132D01*
G01Y1487121D01*
G02X145938Y1486918I-202J-1D01*
G01X143118D01*
G02X142916Y1487121I1J203D01*
G01Y1487741D01*
G03X142866Y1487873I-200J0D01*
G02Y1490789I1661J1458D01*
G03X142916Y1490921I-150J132D01*
G01Y1492859D01*
G03X142866Y1492991I-200J0D01*
G02Y1495907I1661J1458D01*
G03X142916Y1496039I-150J132D01*
G01Y1496659D01*
G02X143118Y1496862I202J1D01*
G37*
G36*
G01X160440D02*
X163260D01*
G02X163462Y1496659I-1J-203D01*
G01Y1496039D01*
G03X163512Y1495907I200J0D01*
G02Y1492991I-1661J-1458D01*
G03X163462Y1492859I150J-132D01*
G01Y1490921D01*
G03X163512Y1490789I200J0D01*
G02Y1487873I-1661J-1458D01*
G03X163462Y1487741I150J-132D01*
G01Y1487121D01*
G02X163260Y1486918I-202J-1D01*
G01X160440D01*
G02X160238Y1487121I1J203D01*
G01Y1487741D01*
G03X160188Y1487873I-200J0D01*
G02Y1490789I1661J1458D01*
G03X160238Y1490921I-150J132D01*
G01Y1492859D01*
G03X160188Y1492991I-200J0D01*
G02Y1495907I1661J1458D01*
G03X160238Y1496039I-150J132D01*
G01Y1496659D01*
G02X160440Y1496862I202J1D01*
G37*
G36*
G01X281700D02*
X284520D01*
G02X284722Y1496659I-1J-203D01*
G01Y1496039D01*
G03X284772Y1495907I200J0D01*
G02Y1492991I-1661J-1458D01*
G03X284722Y1492859I150J-132D01*
G01Y1490921D01*
G03X284772Y1490789I200J0D01*
G02Y1487873I-1661J-1458D01*
G03X284722Y1487741I150J-132D01*
G01Y1487121D01*
G02X284520Y1486918I-202J-1D01*
G01X281700D01*
G02X281498Y1487121I1J203D01*
G01Y1487741D01*
G03X281448Y1487873I-200J0D01*
G02Y1490789I1661J1458D01*
G03X281498Y1490921I-150J132D01*
G01Y1492859D01*
G03X281448Y1492991I-200J0D01*
G02Y1495907I1661J1458D01*
G03X281498Y1496039I-150J132D01*
G01Y1496659D01*
G02X281700Y1496862I202J1D01*
G37*
G36*
G01X299023D02*
X301843D01*
G02X302046Y1496659I0J-203D01*
G01Y1496037D01*
G03X302096Y1495905I200J0D01*
G02Y1492993I-1664J-1456D01*
G03X302046Y1492861I150J-132D01*
G01Y1490919D01*
G03X302096Y1490787I200J0D01*
G02Y1487875I-1664J-1456D01*
G03X302046Y1487743I150J-132D01*
G01Y1487121D01*
G02X301843Y1486918I-203J0D01*
G01X299023D01*
G02X298820Y1487121I0J203D01*
G01Y1487743D01*
G03X298770Y1487875I-200J0D01*
G02Y1490787I1664J1456D01*
G03X298820Y1490919I-150J132D01*
G01Y1492861D01*
G03X298770Y1492993I-200J0D01*
G02Y1495905I1664J1456D01*
G03X298820Y1496037I-150J132D01*
G01Y1496659D01*
G02X299023Y1496862I203J0D01*
G37*
G36*
G01X454929D02*
X457749D01*
G02X457952Y1496659I0J-203D01*
G01Y1496037D01*
G03X458002Y1495905I200J0D01*
G02Y1492993I-1664J-1456D01*
G03X457952Y1492861I150J-132D01*
G01Y1490919D01*
G03X458002Y1490787I200J0D01*
G02Y1487875I-1664J-1456D01*
G03X457952Y1487743I150J-132D01*
G01Y1487121D01*
G02X457749Y1486918I-203J0D01*
G01X454929D01*
G02X454726Y1487121I0J203D01*
G01Y1487743D01*
G03X454676Y1487875I-200J0D01*
G02Y1490787I1664J1456D01*
G03X454726Y1490919I-150J132D01*
G01Y1492861D01*
G03X454676Y1492993I-200J0D01*
G02Y1495905I1664J1456D01*
G03X454726Y1496037I-150J132D01*
G01Y1496659D01*
G02X454929Y1496862I203J0D01*
G37*
G36*
G01X472252D02*
X475072D01*
G02X475274Y1496659I-1J-203D01*
G01Y1496039D01*
G03X475324Y1495907I200J0D01*
G02Y1492991I-1661J-1458D01*
G03X475274Y1492859I150J-132D01*
G01Y1490921D01*
G03X475324Y1490789I200J0D01*
G02Y1487873I-1661J-1458D01*
G03X475274Y1487741I150J-132D01*
G01Y1487121D01*
G02X475072Y1486918I-202J-1D01*
G01X472252D01*
G02X472050Y1487121I1J203D01*
G01Y1487741D01*
G03X472000Y1487873I-200J0D01*
G02Y1490789I1661J1458D01*
G03X472050Y1490921I-150J132D01*
G01Y1492859D01*
G03X472000Y1492991I-200J0D01*
G02Y1495907I1661J1458D01*
G03X472050Y1496039I-150J132D01*
G01Y1496659D01*
G02X472252Y1496862I202J1D01*
G37*
G36*
G01X489575D02*
X492395D01*
G02X492598Y1496659I0J-203D01*
G01Y1496037D01*
G03X492648Y1495905I200J0D01*
G02Y1492993I-1664J-1456D01*
G03X492598Y1492861I150J-132D01*
G01Y1490919D01*
G03X492648Y1490787I200J0D01*
G02Y1487875I-1664J-1456D01*
G03X492598Y1487743I150J-132D01*
G01Y1487121D01*
G02X492395Y1486918I-203J0D01*
G01X489575D01*
G02X489372Y1487121I0J203D01*
G01Y1487743D01*
G03X489322Y1487875I-200J0D01*
G02Y1490787I1664J1456D01*
G03X489372Y1490919I-150J132D01*
G01Y1492861D01*
G03X489322Y1492993I-200J0D01*
G02Y1495905I1664J1456D01*
G03X489372Y1496037I-150J132D01*
G01Y1496659D01*
G02X489575Y1496862I203J0D01*
G37*
G36*
G01X506897D02*
X509717D01*
G02X509920Y1496659I0J-203D01*
G01Y1496037D01*
G03X509970Y1495905I200J0D01*
G02Y1492993I-1664J-1456D01*
G03X509920Y1492861I150J-132D01*
G01Y1490919D01*
G03X509970Y1490787I200J0D01*
G02Y1487875I-1664J-1456D01*
G03X509920Y1487743I150J-132D01*
G01Y1487121D01*
G02X509717Y1486918I-203J0D01*
G01X506897D01*
G02X506694Y1487121I0J203D01*
G01Y1487743D01*
G03X506644Y1487875I-200J0D01*
G02Y1490787I1664J1456D01*
G03X506694Y1490919I-150J132D01*
G01Y1492861D01*
G03X506644Y1492993I-200J0D01*
G02Y1495905I1664J1456D01*
G03X506694Y1496037I-150J132D01*
G01Y1496659D01*
G02X506897Y1496862I203J0D01*
G37*
G36*
G01X645480D02*
X648300D01*
G02X648502Y1496659I-1J-203D01*
G01Y1496039D01*
G03X648552Y1495907I200J0D01*
G02Y1492991I-1661J-1458D01*
G03X648502Y1492859I150J-132D01*
G01Y1490921D01*
G03X648552Y1490789I200J0D01*
G02Y1487873I-1661J-1458D01*
G03X648502Y1487741I150J-132D01*
G01Y1487121D01*
G02X648300Y1486918I-202J-1D01*
G01X645480D01*
G02X645278Y1487121I1J203D01*
G01Y1487741D01*
G03X645228Y1487873I-200J0D01*
G02Y1490789I1661J1458D01*
G03X645278Y1490921I-150J132D01*
G01Y1492859D01*
G03X645228Y1492991I-200J0D01*
G02Y1495907I1661J1458D01*
G03X645278Y1496039I-150J132D01*
G01Y1496659D01*
G02X645480Y1496862I202J1D01*
G37*
G36*
G01X662803D02*
X665623D01*
G02X665826Y1496659I0J-203D01*
G01Y1496037D01*
G03X665876Y1495905I200J0D01*
G02Y1492993I-1664J-1456D01*
G03X665826Y1492861I150J-132D01*
G01Y1490919D01*
G03X665876Y1490787I200J0D01*
G02Y1487875I-1664J-1456D01*
G03X665826Y1487743I150J-132D01*
G01Y1487121D01*
G02X665623Y1486918I-203J0D01*
G01X662803D01*
G02X662600Y1487121I0J203D01*
G01Y1487743D01*
G03X662550Y1487875I-200J0D01*
G02Y1490787I1664J1456D01*
G03X662600Y1490919I-150J132D01*
G01Y1492861D01*
G03X662550Y1492993I-200J0D01*
G02Y1495905I1664J1456D01*
G03X662600Y1496037I-150J132D01*
G01Y1496659D01*
G02X662803Y1496862I203J0D01*
G37*
G36*
G01X680125D02*
X682945D01*
G02X683148Y1496659I0J-203D01*
G01Y1496037D01*
G03X683198Y1495905I200J0D01*
G02Y1492993I-1664J-1456D01*
G03X683148Y1492861I150J-132D01*
G01Y1490919D01*
G03X683198Y1490787I200J0D01*
G02Y1487875I-1664J-1456D01*
G03X683148Y1487743I150J-132D01*
G01Y1487121D01*
G02X682945Y1486918I-203J0D01*
G01X680125D01*
G02X679922Y1487121I0J203D01*
G01Y1487743D01*
G03X679872Y1487875I-200J0D01*
G02Y1490787I1664J1456D01*
G03X679922Y1490919I-150J132D01*
G01Y1492861D01*
G03X679872Y1492993I-200J0D01*
G02Y1495905I1664J1456D01*
G03X679922Y1496037I-150J132D01*
G01Y1496659D01*
G02X680125Y1496862I203J0D01*
G37*
G36*
G01X1165086D02*
X1167906D01*
G02X1168108Y1496659I-1J-203D01*
G01Y1496039D01*
G03X1168158Y1495907I200J0D01*
G02Y1492991I-1661J-1458D01*
G03X1168108Y1492859I150J-132D01*
G01Y1490921D01*
G03X1168158Y1490789I200J0D01*
G02Y1487873I-1661J-1458D01*
G03X1168108Y1487741I150J-132D01*
G01Y1487121D01*
G02X1167906Y1486918I-202J-1D01*
G01X1165086D01*
G02X1164884Y1487121I1J203D01*
G01Y1487741D01*
G03X1164834Y1487873I-200J0D01*
G02Y1490789I1661J1458D01*
G03X1164884Y1490921I-150J132D01*
G01Y1492859D01*
G03X1164834Y1492991I-200J0D01*
G02Y1495907I1661J1458D01*
G03X1164884Y1496039I-150J132D01*
G01Y1496659D01*
G02X1165086Y1496862I202J1D01*
G37*
G36*
G01X1182408D02*
X1185228D01*
G02X1185430Y1496659I-1J-203D01*
G01Y1496039D01*
G03X1185480Y1495907I200J0D01*
G02Y1492991I-1661J-1458D01*
G03X1185430Y1492859I150J-132D01*
G01Y1490921D01*
G03X1185480Y1490789I200J0D01*
G02Y1487873I-1661J-1458D01*
G03X1185430Y1487741I150J-132D01*
G01Y1487121D01*
G02X1185228Y1486918I-202J-1D01*
G01X1182408D01*
G02X1182206Y1487121I1J203D01*
G01Y1487741D01*
G03X1182156Y1487873I-200J0D01*
G02Y1490789I1661J1458D01*
G03X1182206Y1490921I-150J132D01*
G01Y1492859D01*
G03X1182156Y1492991I-200J0D01*
G02Y1495907I1661J1458D01*
G03X1182206Y1496039I-150J132D01*
G01Y1496659D01*
G02X1182408Y1496862I202J1D01*
G37*
G36*
G01X1303669D02*
X1306489D01*
G02X1306692Y1496659I0J-203D01*
G01Y1496037D01*
G03X1306742Y1495905I200J0D01*
G02Y1492993I-1664J-1456D01*
G03X1306692Y1492861I150J-132D01*
G01Y1490919D01*
G03X1306742Y1490787I200J0D01*
G02Y1487875I-1664J-1456D01*
G03X1306692Y1487743I150J-132D01*
G01Y1487121D01*
G02X1306489Y1486918I-203J0D01*
G01X1303669D01*
G02X1303466Y1487121I0J203D01*
G01Y1487743D01*
G03X1303416Y1487875I-200J0D01*
G02Y1490787I1664J1456D01*
G03X1303466Y1490919I-150J132D01*
G01Y1492861D01*
G03X1303416Y1492993I-200J0D01*
G02Y1495905I1664J1456D01*
G03X1303466Y1496037I-150J132D01*
G01Y1496659D01*
G02X1303669Y1496862I203J0D01*
G37*
G36*
G01X1320992D02*
X1323812D01*
G02X1324014Y1496659I-1J-203D01*
G01Y1496039D01*
G03X1324064Y1495907I200J0D01*
G02Y1492991I-1661J-1458D01*
G03X1324014Y1492859I150J-132D01*
G01Y1490921D01*
G03X1324064Y1490789I200J0D01*
G02Y1487873I-1661J-1458D01*
G03X1324014Y1487741I150J-132D01*
G01Y1487121D01*
G02X1323812Y1486918I-202J-1D01*
G01X1320992D01*
G02X1320790Y1487121I1J203D01*
G01Y1487741D01*
G03X1320740Y1487873I-200J0D01*
G02Y1490789I1661J1458D01*
G03X1320790Y1490921I-150J132D01*
G01Y1492859D01*
G03X1320740Y1492991I-200J0D01*
G02Y1495907I1661J1458D01*
G03X1320790Y1496039I-150J132D01*
G01Y1496659D01*
G02X1320992Y1496862I202J1D01*
G37*
G36*
G01X1338315D02*
X1341135D01*
G02X1341338Y1496659I0J-203D01*
G01Y1496037D01*
G03X1341388Y1495905I200J0D01*
G02Y1492993I-1664J-1456D01*
G03X1341338Y1492861I150J-132D01*
G01Y1490919D01*
G03X1341388Y1490787I200J0D01*
G02Y1487875I-1664J-1456D01*
G03X1341338Y1487743I150J-132D01*
G01Y1487121D01*
G02X1341135Y1486918I-203J0D01*
G01X1338315D01*
G02X1338112Y1487121I0J203D01*
G01Y1487743D01*
G03X1338062Y1487875I-200J0D01*
G02Y1490787I1664J1456D01*
G03X1338112Y1490919I-150J132D01*
G01Y1492861D01*
G03X1338062Y1492993I-200J0D01*
G02Y1495905I1664J1456D01*
G03X1338112Y1496037I-150J132D01*
G01Y1496659D01*
G02X1338315Y1496862I203J0D01*
G37*
G36*
G01X1355637D02*
X1358457D01*
G02X1358660Y1496659I0J-203D01*
G01Y1496037D01*
G03X1358710Y1495905I200J0D01*
G02Y1492993I-1664J-1456D01*
G03X1358660Y1492861I150J-132D01*
G01Y1490919D01*
G03X1358710Y1490787I200J0D01*
G02Y1487875I-1664J-1456D01*
G03X1358660Y1487743I150J-132D01*
G01Y1487121D01*
G02X1358457Y1486918I-203J0D01*
G01X1355637D01*
G02X1355434Y1487121I0J203D01*
G01Y1487743D01*
G03X1355384Y1487875I-200J0D01*
G02Y1490787I1664J1456D01*
G03X1355434Y1490919I-150J132D01*
G01Y1492861D01*
G03X1355384Y1492993I-200J0D01*
G02Y1495905I1664J1456D01*
G03X1355434Y1496037I-150J132D01*
G01Y1496659D01*
G02X1355637Y1496862I203J0D01*
G37*
G36*
G01X1476897D02*
X1479717D01*
G02X1479920Y1496659I0J-203D01*
G01Y1496037D01*
G03X1479970Y1495905I200J0D01*
G02Y1492993I-1664J-1456D01*
G03X1479920Y1492861I150J-132D01*
G01Y1490919D01*
G03X1479970Y1490787I200J0D01*
G02Y1487875I-1664J-1456D01*
G03X1479920Y1487743I150J-132D01*
G01Y1487121D01*
G02X1479717Y1486918I-203J0D01*
G01X1476897D01*
G02X1476694Y1487121I0J203D01*
G01Y1487743D01*
G03X1476644Y1487875I-200J0D01*
G02Y1490787I1664J1456D01*
G03X1476694Y1490919I-150J132D01*
G01Y1492861D01*
G03X1476644Y1492993I-200J0D01*
G02Y1495905I1664J1456D01*
G03X1476694Y1496037I-150J132D01*
G01Y1496659D01*
G02X1476897Y1496862I203J0D01*
G37*
G36*
G01X1494220D02*
X1497040D01*
G02X1497242Y1496659I-1J-203D01*
G01Y1496039D01*
G03X1497292Y1495907I200J0D01*
G02Y1492991I-1661J-1458D01*
G03X1497242Y1492859I150J-132D01*
G01Y1490921D01*
G03X1497292Y1490789I200J0D01*
G02Y1487873I-1661J-1458D01*
G03X1497242Y1487741I150J-132D01*
G01Y1487121D01*
G02X1497040Y1486918I-202J-1D01*
G01X1494220D01*
G02X1494018Y1487121I1J203D01*
G01Y1487741D01*
G03X1493968Y1487873I-200J0D01*
G02Y1490789I1661J1458D01*
G03X1494018Y1490921I-150J132D01*
G01Y1492859D01*
G03X1493968Y1492991I-200J0D01*
G02Y1495907I1661J1458D01*
G03X1494018Y1496039I-150J132D01*
G01Y1496659D01*
G02X1494220Y1496862I202J1D01*
G37*
G36*
G01X1511543D02*
X1514363D01*
G02X1514566Y1496659I0J-203D01*
G01Y1496037D01*
G03X1514616Y1495905I200J0D01*
G02Y1492993I-1664J-1456D01*
G03X1514566Y1492861I150J-132D01*
G01Y1490919D01*
G03X1514616Y1490787I200J0D01*
G02Y1487875I-1664J-1456D01*
G03X1514566Y1487743I150J-132D01*
G01Y1487121D01*
G02X1514363Y1486918I-203J0D01*
G01X1511543D01*
G02X1511340Y1487121I0J203D01*
G01Y1487743D01*
G03X1511290Y1487875I-200J0D01*
G02Y1490787I1664J1456D01*
G03X1511340Y1490919I-150J132D01*
G01Y1492861D01*
G03X1511290Y1492993I-200J0D01*
G02Y1495905I1664J1456D01*
G03X1511340Y1496037I-150J132D01*
G01Y1496659D01*
G02X1511543Y1496862I203J0D01*
G37*
G36*
G01X1528865D02*
X1531685D01*
G02X1531888Y1496659I0J-203D01*
G01Y1496037D01*
G03X1531938Y1495905I200J0D01*
G02Y1492993I-1664J-1456D01*
G03X1531888Y1492861I150J-132D01*
G01Y1490919D01*
G03X1531938Y1490787I200J0D01*
G02Y1487875I-1664J-1456D01*
G03X1531888Y1487743I150J-132D01*
G01Y1487121D01*
G02X1531685Y1486918I-203J0D01*
G01X1528865D01*
G02X1528662Y1487121I0J203D01*
G01Y1487743D01*
G03X1528612Y1487875I-200J0D01*
G02Y1490787I1664J1456D01*
G03X1528662Y1490919I-150J132D01*
G01Y1492861D01*
G03X1528612Y1492993I-200J0D01*
G02Y1495905I1664J1456D01*
G03X1528662Y1496037I-150J132D01*
G01Y1496659D01*
G02X1528865Y1496862I203J0D01*
G37*
G36*
G01X1684771D02*
X1687591D01*
G02X1687794Y1496659I0J-203D01*
G01Y1496037D01*
G03X1687844Y1495905I200J0D01*
G02Y1492993I-1664J-1456D01*
G03X1687794Y1492861I150J-132D01*
G01Y1490919D01*
G03X1687844Y1490787I200J0D01*
G02Y1487875I-1664J-1456D01*
G03X1687794Y1487743I150J-132D01*
G01Y1487121D01*
G02X1687591Y1486918I-203J0D01*
G01X1684771D01*
G02X1684568Y1487121I0J203D01*
G01Y1487743D01*
G03X1684518Y1487875I-200J0D01*
G02Y1490787I1664J1456D01*
G03X1684568Y1490919I-150J132D01*
G01Y1492861D01*
G03X1684518Y1492993I-200J0D01*
G02Y1495905I1664J1456D01*
G03X1684568Y1496037I-150J132D01*
G01Y1496659D01*
G02X1684771Y1496862I203J0D01*
G37*
G36*
G01X1702093D02*
X1704913D01*
G02X1705116Y1496659I0J-203D01*
G01Y1496037D01*
G03X1705166Y1495905I200J0D01*
G02Y1492993I-1664J-1456D01*
G03X1705116Y1492861I150J-132D01*
G01Y1490919D01*
G03X1705166Y1490787I200J0D01*
G02Y1487875I-1664J-1456D01*
G03X1705116Y1487743I150J-132D01*
G01Y1487121D01*
G02X1704913Y1486918I-203J0D01*
G01X1702093D01*
G02X1701890Y1487121I0J203D01*
G01Y1487743D01*
G03X1701840Y1487875I-200J0D01*
G02Y1490787I1664J1456D01*
G03X1701890Y1490919I-150J132D01*
G01Y1492861D01*
G03X1701840Y1492993I-200J0D01*
G02Y1495905I1664J1456D01*
G03X1701890Y1496037I-150J132D01*
G01Y1496659D01*
G02X1702093Y1496862I203J0D01*
G37*
G36*
G01X134456Y1501192D02*
X137276D01*
G02X137478Y1500989I-1J-203D01*
G01Y1500370D01*
G03X137528Y1500238I200J0D01*
G02Y1497322I-1661J-1458D01*
G03X137478Y1497190I150J-132D01*
G01Y1495252D01*
G03X137528Y1495120I200J0D01*
G02Y1492204I-1661J-1458D01*
G03X137478Y1492072I150J-132D01*
G01Y1491451D01*
G02X137276Y1491248I-202J-1D01*
G01X134456D01*
G02X134254Y1491451I1J203D01*
G01Y1492072D01*
G03X134204Y1492204I-200J0D01*
G02Y1495120I1661J1458D01*
G03X134254Y1495252I-150J132D01*
G01Y1497190D01*
G03X134204Y1497322I-200J0D01*
G02Y1500238I1661J1458D01*
G03X134254Y1500370I-150J132D01*
G01Y1500989D01*
G02X134456Y1501192I202J1D01*
G37*
G36*
G01X151779D02*
X154599D01*
G02X154802Y1500989I0J-203D01*
G01Y1500368D01*
G03X154852Y1500236I200J0D01*
G02Y1497324I-1664J-1456D01*
G03X154802Y1497192I150J-132D01*
G01Y1495250D01*
G03X154852Y1495118I200J0D01*
G02Y1492206I-1664J-1456D01*
G03X154802Y1492074I150J-132D01*
G01Y1491451D01*
G02X154599Y1491248I-203J0D01*
G01X151779D01*
G02X151576Y1491451I0J203D01*
G01Y1492074D01*
G03X151526Y1492206I-200J0D01*
G02Y1495118I1664J1456D01*
G03X151576Y1495250I-150J132D01*
G01Y1497192D01*
G03X151526Y1497324I-200J0D01*
G02Y1500236I1664J1456D01*
G03X151576Y1500368I-150J132D01*
G01Y1500989D01*
G02X151779Y1501192I203J0D01*
G37*
G36*
G01X169102D02*
X171922D01*
G02X172124Y1500989I-1J-203D01*
G01Y1500370D01*
G03X172174Y1500238I200J0D01*
G02Y1497322I-1661J-1458D01*
G03X172124Y1497190I150J-132D01*
G01Y1495252D01*
G03X172174Y1495120I200J0D01*
G02Y1492204I-1661J-1458D01*
G03X172124Y1492072I150J-132D01*
G01Y1491451D01*
G02X171922Y1491248I-202J-1D01*
G01X169102D01*
G02X168900Y1491451I1J203D01*
G01Y1492072D01*
G03X168850Y1492204I-200J0D01*
G02Y1495120I1661J1458D01*
G03X168900Y1495252I-150J132D01*
G01Y1497190D01*
G03X168850Y1497322I-200J0D01*
G02Y1500238I1661J1458D01*
G03X168900Y1500370I-150J132D01*
G01Y1500989D01*
G02X169102Y1501192I202J1D01*
G37*
G36*
G01X290361D02*
X293181D01*
G02X293384Y1500989I0J-203D01*
G01Y1500368D01*
G03X293434Y1500236I200J0D01*
G02Y1497324I-1664J-1456D01*
G03X293384Y1497192I150J-132D01*
G01Y1495250D01*
G03X293434Y1495118I200J0D01*
G02Y1492206I-1664J-1456D01*
G03X293384Y1492074I150J-132D01*
G01Y1491451D01*
G02X293181Y1491248I-203J0D01*
G01X290361D01*
G02X290158Y1491451I0J203D01*
G01Y1492074D01*
G03X290108Y1492206I-200J0D01*
G02Y1495118I1664J1456D01*
G03X290158Y1495250I-150J132D01*
G01Y1497192D01*
G03X290108Y1497324I-200J0D01*
G02Y1500236I1664J1456D01*
G03X290158Y1500368I-150J132D01*
G01Y1500989D01*
G02X290361Y1501192I203J0D01*
G37*
G36*
G01X463590D02*
X466410D01*
G02X466612Y1500989I-1J-203D01*
G01Y1500370D01*
G03X466662Y1500238I200J0D01*
G02Y1497322I-1661J-1458D01*
G03X466612Y1497190I150J-132D01*
G01Y1495252D01*
G03X466662Y1495120I200J0D01*
G02Y1492204I-1661J-1458D01*
G03X466612Y1492072I150J-132D01*
G01Y1491451D01*
G02X466410Y1491248I-202J-1D01*
G01X463590D01*
G02X463388Y1491451I1J203D01*
G01Y1492072D01*
G03X463338Y1492204I-200J0D01*
G02Y1495120I1661J1458D01*
G03X463388Y1495252I-150J132D01*
G01Y1497190D01*
G03X463338Y1497322I-200J0D01*
G02Y1500238I1661J1458D01*
G03X463388Y1500370I-150J132D01*
G01Y1500989D01*
G02X463590Y1501192I202J1D01*
G37*
G36*
G01X480913D02*
X483733D01*
G02X483936Y1500989I0J-203D01*
G01Y1500368D01*
G03X483986Y1500236I200J0D01*
G02Y1497324I-1664J-1456D01*
G03X483936Y1497192I150J-132D01*
G01Y1495250D01*
G03X483986Y1495118I200J0D01*
G02Y1492206I-1664J-1456D01*
G03X483936Y1492074I150J-132D01*
G01Y1491451D01*
G02X483733Y1491248I-203J0D01*
G01X480913D01*
G02X480710Y1491451I0J203D01*
G01Y1492074D01*
G03X480660Y1492206I-200J0D01*
G02Y1495118I1664J1456D01*
G03X480710Y1495250I-150J132D01*
G01Y1497192D01*
G03X480660Y1497324I-200J0D01*
G02Y1500236I1664J1456D01*
G03X480710Y1500368I-150J132D01*
G01Y1500989D01*
G02X480913Y1501192I203J0D01*
G37*
G36*
G01X498236D02*
X501056D01*
G02X501258Y1500989I-1J-203D01*
G01Y1500370D01*
G03X501308Y1500238I200J0D01*
G02Y1497322I-1661J-1458D01*
G03X501258Y1497190I150J-132D01*
G01Y1495252D01*
G03X501308Y1495120I200J0D01*
G02Y1492204I-1661J-1458D01*
G03X501258Y1492072I150J-132D01*
G01Y1491451D01*
G02X501056Y1491248I-202J-1D01*
G01X498236D01*
G02X498034Y1491451I1J203D01*
G01Y1492072D01*
G03X497984Y1492204I-200J0D01*
G02Y1495120I1661J1458D01*
G03X498034Y1495252I-150J132D01*
G01Y1497190D01*
G03X497984Y1497322I-200J0D01*
G02Y1500238I1661J1458D01*
G03X498034Y1500370I-150J132D01*
G01Y1500989D01*
G02X498236Y1501192I202J1D01*
G37*
G36*
G01X515559D02*
X518379D01*
G02X518582Y1500989I0J-203D01*
G01Y1500368D01*
G03X518632Y1500236I200J0D01*
G02Y1497324I-1664J-1456D01*
G03X518582Y1497192I150J-132D01*
G01Y1495250D01*
G03X518632Y1495118I200J0D01*
G02Y1492206I-1664J-1456D01*
G03X518582Y1492074I150J-132D01*
G01Y1491451D01*
G02X518379Y1491248I-203J0D01*
G01X515559D01*
G02X515356Y1491451I0J203D01*
G01Y1492074D01*
G03X515306Y1492206I-200J0D01*
G02Y1495118I1664J1456D01*
G03X515356Y1495250I-150J132D01*
G01Y1497192D01*
G03X515306Y1497324I-200J0D01*
G02Y1500236I1664J1456D01*
G03X515356Y1500368I-150J132D01*
G01Y1500989D01*
G02X515559Y1501192I203J0D01*
G37*
G36*
G01X654141D02*
X656961D01*
G02X657164Y1500989I0J-203D01*
G01Y1500368D01*
G03X657214Y1500236I200J0D01*
G02Y1497324I-1664J-1456D01*
G03X657164Y1497192I150J-132D01*
G01Y1495250D01*
G03X657214Y1495118I200J0D01*
G02Y1492206I-1664J-1456D01*
G03X657164Y1492074I150J-132D01*
G01Y1491451D01*
G02X656961Y1491248I-203J0D01*
G01X654141D01*
G02X653938Y1491451I0J203D01*
G01Y1492074D01*
G03X653888Y1492206I-200J0D01*
G02Y1495118I1664J1456D01*
G03X653938Y1495250I-150J132D01*
G01Y1497192D01*
G03X653888Y1497324I-200J0D01*
G02Y1500236I1664J1456D01*
G03X653938Y1500368I-150J132D01*
G01Y1500989D01*
G02X654141Y1501192I203J0D01*
G37*
G36*
G01X671464D02*
X674284D01*
G02X674486Y1500989I-1J-203D01*
G01Y1500370D01*
G03X674536Y1500238I200J0D01*
G02Y1497322I-1661J-1458D01*
G03X674486Y1497190I150J-132D01*
G01Y1495252D01*
G03X674536Y1495120I200J0D01*
G02Y1492204I-1661J-1458D01*
G03X674486Y1492072I150J-132D01*
G01Y1491451D01*
G02X674284Y1491248I-202J-1D01*
G01X671464D01*
G02X671262Y1491451I1J203D01*
G01Y1492072D01*
G03X671212Y1492204I-200J0D01*
G02Y1495120I1661J1458D01*
G03X671262Y1495252I-150J132D01*
G01Y1497190D01*
G03X671212Y1497322I-200J0D01*
G02Y1500238I1661J1458D01*
G03X671262Y1500370I-150J132D01*
G01Y1500989D01*
G02X671464Y1501192I202J1D01*
G37*
G36*
G01X688787D02*
X691607D01*
G02X691810Y1500989I0J-203D01*
G01Y1500368D01*
G03X691860Y1500236I200J0D01*
G02Y1497324I-1664J-1456D01*
G03X691810Y1497192I150J-132D01*
G01Y1495250D01*
G03X691860Y1495118I200J0D01*
G02Y1492206I-1664J-1456D01*
G03X691810Y1492074I150J-132D01*
G01Y1491451D01*
G02X691607Y1491248I-203J0D01*
G01X688787D01*
G02X688584Y1491451I0J203D01*
G01Y1492074D01*
G03X688534Y1492206I-200J0D01*
G02Y1495118I1664J1456D01*
G03X688584Y1495250I-150J132D01*
G01Y1497192D01*
G03X688534Y1497324I-200J0D01*
G02Y1500236I1664J1456D01*
G03X688584Y1500368I-150J132D01*
G01Y1500989D01*
G02X688787Y1501192I203J0D01*
G37*
G36*
G01X1173747D02*
X1176567D01*
G02X1176770Y1500989I0J-203D01*
G01Y1500368D01*
G03X1176820Y1500236I200J0D01*
G02Y1497324I-1664J-1456D01*
G03X1176770Y1497192I150J-132D01*
G01Y1495250D01*
G03X1176820Y1495118I200J0D01*
G02Y1492206I-1664J-1456D01*
G03X1176770Y1492074I150J-132D01*
G01Y1491451D01*
G02X1176567Y1491248I-203J0D01*
G01X1173747D01*
G02X1173544Y1491451I0J203D01*
G01Y1492074D01*
G03X1173494Y1492206I-200J0D01*
G02Y1495118I1664J1456D01*
G03X1173544Y1495250I-150J132D01*
G01Y1497192D01*
G03X1173494Y1497324I-200J0D01*
G02Y1500236I1664J1456D01*
G03X1173544Y1500368I-150J132D01*
G01Y1500989D01*
G02X1173747Y1501192I203J0D01*
G37*
G36*
G01X1191070D02*
X1193890D01*
G02X1194092Y1500989I-1J-203D01*
G01Y1500370D01*
G03X1194142Y1500238I200J0D01*
G02Y1497322I-1661J-1458D01*
G03X1194092Y1497190I150J-132D01*
G01Y1495252D01*
G03X1194142Y1495120I200J0D01*
G02Y1492204I-1661J-1458D01*
G03X1194092Y1492072I150J-132D01*
G01Y1491451D01*
G02X1193890Y1491248I-202J-1D01*
G01X1191070D01*
G02X1190868Y1491451I1J203D01*
G01Y1492072D01*
G03X1190818Y1492204I-200J0D01*
G02Y1495120I1661J1458D01*
G03X1190868Y1495252I-150J132D01*
G01Y1497190D01*
G03X1190818Y1497322I-200J0D01*
G02Y1500238I1661J1458D01*
G03X1190868Y1500370I-150J132D01*
G01Y1500989D01*
G02X1191070Y1501192I202J1D01*
G37*
G36*
G01X1312330D02*
X1315150D01*
G02X1315352Y1500989I-1J-203D01*
G01Y1500370D01*
G03X1315402Y1500238I200J0D01*
G02Y1497322I-1661J-1458D01*
G03X1315352Y1497190I150J-132D01*
G01Y1495252D01*
G03X1315402Y1495120I200J0D01*
G02Y1492204I-1661J-1458D01*
G03X1315352Y1492072I150J-132D01*
G01Y1491451D01*
G02X1315150Y1491248I-202J-1D01*
G01X1312330D01*
G02X1312128Y1491451I1J203D01*
G01Y1492072D01*
G03X1312078Y1492204I-200J0D01*
G02Y1495120I1661J1458D01*
G03X1312128Y1495252I-150J132D01*
G01Y1497190D01*
G03X1312078Y1497322I-200J0D01*
G02Y1500238I1661J1458D01*
G03X1312128Y1500370I-150J132D01*
G01Y1500989D01*
G02X1312330Y1501192I202J1D01*
G37*
G36*
G01X1329653D02*
X1332473D01*
G02X1332676Y1500989I0J-203D01*
G01Y1500368D01*
G03X1332726Y1500236I200J0D01*
G02Y1497324I-1664J-1456D01*
G03X1332676Y1497192I150J-132D01*
G01Y1495250D01*
G03X1332726Y1495118I200J0D01*
G02Y1492206I-1664J-1456D01*
G03X1332676Y1492074I150J-132D01*
G01Y1491451D01*
G02X1332473Y1491248I-203J0D01*
G01X1329653D01*
G02X1329450Y1491451I0J203D01*
G01Y1492074D01*
G03X1329400Y1492206I-200J0D01*
G02Y1495118I1664J1456D01*
G03X1329450Y1495250I-150J132D01*
G01Y1497192D01*
G03X1329400Y1497324I-200J0D01*
G02Y1500236I1664J1456D01*
G03X1329450Y1500368I-150J132D01*
G01Y1500989D01*
G02X1329653Y1501192I203J0D01*
G37*
G36*
G01X1346976D02*
X1349796D01*
G02X1349998Y1500989I-1J-203D01*
G01Y1500370D01*
G03X1350048Y1500238I200J0D01*
G02Y1497322I-1661J-1458D01*
G03X1349998Y1497190I150J-132D01*
G01Y1495252D01*
G03X1350048Y1495120I200J0D01*
G02Y1492204I-1661J-1458D01*
G03X1349998Y1492072I150J-132D01*
G01Y1491451D01*
G02X1349796Y1491248I-202J-1D01*
G01X1346976D01*
G02X1346774Y1491451I1J203D01*
G01Y1492072D01*
G03X1346724Y1492204I-200J0D01*
G02Y1495120I1661J1458D01*
G03X1346774Y1495252I-150J132D01*
G01Y1497190D01*
G03X1346724Y1497322I-200J0D01*
G02Y1500238I1661J1458D01*
G03X1346774Y1500370I-150J132D01*
G01Y1500989D01*
G02X1346976Y1501192I202J1D01*
G37*
G36*
G01X1364299D02*
X1367119D01*
G02X1367322Y1500989I0J-203D01*
G01Y1500368D01*
G03X1367372Y1500236I200J0D01*
G02Y1497324I-1664J-1456D01*
G03X1367322Y1497192I150J-132D01*
G01Y1495250D01*
G03X1367372Y1495118I200J0D01*
G02Y1492206I-1664J-1456D01*
G03X1367322Y1492074I150J-132D01*
G01Y1491451D01*
G02X1367119Y1491248I-203J0D01*
G01X1364299D01*
G02X1364096Y1491451I0J203D01*
G01Y1492074D01*
G03X1364046Y1492206I-200J0D01*
G02Y1495118I1664J1456D01*
G03X1364096Y1495250I-150J132D01*
G01Y1497192D01*
G03X1364046Y1497324I-200J0D01*
G02Y1500236I1664J1456D01*
G03X1364096Y1500368I-150J132D01*
G01Y1500989D01*
G02X1364299Y1501192I203J0D01*
G37*
G36*
G01X1485558D02*
X1488378D01*
G02X1488580Y1500989I-1J-203D01*
G01Y1500370D01*
G03X1488630Y1500238I200J0D01*
G02Y1497322I-1661J-1458D01*
G03X1488580Y1497190I150J-132D01*
G01Y1495252D01*
G03X1488630Y1495120I200J0D01*
G02Y1492204I-1661J-1458D01*
G03X1488580Y1492072I150J-132D01*
G01Y1491451D01*
G02X1488378Y1491248I-202J-1D01*
G01X1485558D01*
G02X1485356Y1491451I1J203D01*
G01Y1492072D01*
G03X1485306Y1492204I-200J0D01*
G02Y1495120I1661J1458D01*
G03X1485356Y1495252I-150J132D01*
G01Y1497190D01*
G03X1485306Y1497322I-200J0D01*
G02Y1500238I1661J1458D01*
G03X1485356Y1500370I-150J132D01*
G01Y1500989D01*
G02X1485558Y1501192I202J1D01*
G37*
G36*
G01X1502881D02*
X1505701D01*
G02X1505904Y1500989I0J-203D01*
G01Y1500368D01*
G03X1505954Y1500236I200J0D01*
G02Y1497324I-1664J-1456D01*
G03X1505904Y1497192I150J-132D01*
G01Y1495250D01*
G03X1505954Y1495118I200J0D01*
G02Y1492206I-1664J-1456D01*
G03X1505904Y1492074I150J-132D01*
G01Y1491451D01*
G02X1505701Y1491248I-203J0D01*
G01X1502881D01*
G02X1502678Y1491451I0J203D01*
G01Y1492074D01*
G03X1502628Y1492206I-200J0D01*
G02Y1495118I1664J1456D01*
G03X1502678Y1495250I-150J132D01*
G01Y1497192D01*
G03X1502628Y1497324I-200J0D01*
G02Y1500236I1664J1456D01*
G03X1502678Y1500368I-150J132D01*
G01Y1500989D01*
G02X1502881Y1501192I203J0D01*
G37*
G36*
G01X1520204D02*
X1523024D01*
G02X1523226Y1500989I-1J-203D01*
G01Y1500370D01*
G03X1523276Y1500238I200J0D01*
G02Y1497322I-1661J-1458D01*
G03X1523226Y1497190I150J-132D01*
G01Y1495252D01*
G03X1523276Y1495120I200J0D01*
G02Y1492204I-1661J-1458D01*
G03X1523226Y1492072I150J-132D01*
G01Y1491451D01*
G02X1523024Y1491248I-202J-1D01*
G01X1520204D01*
G02X1520002Y1491451I1J203D01*
G01Y1492072D01*
G03X1519952Y1492204I-200J0D01*
G02Y1495120I1661J1458D01*
G03X1520002Y1495252I-150J132D01*
G01Y1497190D01*
G03X1519952Y1497322I-200J0D01*
G02Y1500238I1661J1458D01*
G03X1520002Y1500370I-150J132D01*
G01Y1500989D01*
G02X1520204Y1501192I202J1D01*
G37*
G36*
G01X1537527D02*
X1540347D01*
G02X1540550Y1500989I0J-203D01*
G01Y1500368D01*
G03X1540600Y1500236I200J0D01*
G02Y1497324I-1664J-1456D01*
G03X1540550Y1497192I150J-132D01*
G01Y1495250D01*
G03X1540600Y1495118I200J0D01*
G02Y1492206I-1664J-1456D01*
G03X1540550Y1492074I150J-132D01*
G01Y1491451D01*
G02X1540347Y1491248I-203J0D01*
G01X1537527D01*
G02X1537324Y1491451I0J203D01*
G01Y1492074D01*
G03X1537274Y1492206I-200J0D01*
G02Y1495118I1664J1456D01*
G03X1537324Y1495250I-150J132D01*
G01Y1497192D01*
G03X1537274Y1497324I-200J0D01*
G02Y1500236I1664J1456D01*
G03X1537324Y1500368I-150J132D01*
G01Y1500989D01*
G02X1537527Y1501192I203J0D01*
G37*
G36*
G01X1693432D02*
X1696252D01*
G02X1696454Y1500989I-1J-203D01*
G01Y1500370D01*
G03X1696504Y1500238I200J0D01*
G02Y1497322I-1661J-1458D01*
G03X1696454Y1497190I150J-132D01*
G01Y1495252D01*
G03X1696504Y1495120I200J0D01*
G02Y1492204I-1661J-1458D01*
G03X1696454Y1492072I150J-132D01*
G01Y1491451D01*
G02X1696252Y1491248I-202J-1D01*
G01X1693432D01*
G02X1693230Y1491451I1J203D01*
G01Y1492072D01*
G03X1693180Y1492204I-200J0D01*
G02Y1495120I1661J1458D01*
G03X1693230Y1495252I-150J132D01*
G01Y1497190D01*
G03X1693180Y1497322I-200J0D01*
G02Y1500238I1661J1458D01*
G03X1693230Y1500370I-150J132D01*
G01Y1500989D01*
G02X1693432Y1501192I202J1D01*
G37*
G36*
G01X1710755D02*
X1713575D01*
G02X1713778Y1500989I0J-203D01*
G01Y1500368D01*
G03X1713828Y1500236I200J0D01*
G02Y1497324I-1664J-1456D01*
G03X1713778Y1497192I150J-132D01*
G01Y1495250D01*
G03X1713828Y1495118I200J0D01*
G02Y1492206I-1664J-1456D01*
G03X1713778Y1492074I150J-132D01*
G01Y1491451D01*
G02X1713575Y1491248I-203J0D01*
G01X1710755D01*
G02X1710552Y1491451I0J203D01*
G01Y1492074D01*
G03X1710502Y1492206I-200J0D01*
G02Y1495118I1664J1456D01*
G03X1710552Y1495250I-150J132D01*
G01Y1497192D01*
G03X1710502Y1497324I-200J0D01*
G02Y1500236I1664J1456D01*
G03X1710552Y1500368I-150J132D01*
G01Y1500989D01*
G02X1710755Y1501192I203J0D01*
G37*
G36*
G01X143118Y1512216D02*
X145938D01*
G02X146140Y1512014I0J-202D01*
G01Y1511394D01*
G03X146190Y1511262I200J0D01*
G02Y1508346I-1661J-1458D01*
G03X146140Y1508214I150J-132D01*
G01Y1506275D01*
G03X146190Y1506143I200J0D01*
G02Y1503227I-1661J-1458D01*
G03X146140Y1503095I150J-132D01*
G01Y1502476D01*
G02X145938Y1502274I-202J0D01*
G01X143118D01*
G02X142916Y1502476I0J202D01*
G01Y1503095D01*
G03X142866Y1503227I-200J0D01*
G02Y1506143I1661J1458D01*
G03X142916Y1506275I-150J132D01*
G01Y1508214D01*
G03X142866Y1508346I-200J0D01*
G02Y1511262I1661J1458D01*
G03X142916Y1511394I-150J132D01*
G01Y1512014D01*
G02X143118Y1512216I202J0D01*
G37*
G36*
G01X160440D02*
X163260D01*
G02X163462Y1512014I0J-202D01*
G01Y1511394D01*
G03X163512Y1511262I200J0D01*
G02Y1508346I-1661J-1458D01*
G03X163462Y1508214I150J-132D01*
G01Y1506275D01*
G03X163512Y1506143I200J0D01*
G02Y1503227I-1661J-1458D01*
G03X163462Y1503095I150J-132D01*
G01Y1502476D01*
G02X163260Y1502274I-202J0D01*
G01X160440D01*
G02X160238Y1502476I0J202D01*
G01Y1503095D01*
G03X160188Y1503227I-200J0D01*
G02Y1506143I1661J1458D01*
G03X160238Y1506275I-150J132D01*
G01Y1508214D01*
G03X160188Y1508346I-200J0D01*
G02Y1511262I1661J1458D01*
G03X160238Y1511394I-150J132D01*
G01Y1512014D01*
G02X160440Y1512216I202J0D01*
G37*
G36*
G01X281700D02*
X284520D01*
G02X284722Y1512014I0J-202D01*
G01Y1511394D01*
G03X284772Y1511262I200J0D01*
G02Y1508346I-1661J-1458D01*
G03X284722Y1508214I150J-132D01*
G01Y1506275D01*
G03X284772Y1506143I200J0D01*
G02Y1503227I-1661J-1458D01*
G03X284722Y1503095I150J-132D01*
G01Y1502476D01*
G02X284520Y1502274I-202J0D01*
G01X281700D01*
G02X281498Y1502476I0J202D01*
G01Y1503095D01*
G03X281448Y1503227I-200J0D01*
G02Y1506143I1661J1458D01*
G03X281498Y1506275I-150J132D01*
G01Y1508214D01*
G03X281448Y1508346I-200J0D01*
G02Y1511262I1661J1458D01*
G03X281498Y1511394I-150J132D01*
G01Y1512014D01*
G02X281700Y1512216I202J0D01*
G37*
G36*
G01X472252D02*
X475072D01*
G02X475274Y1512014I0J-202D01*
G01Y1511394D01*
G03X475324Y1511262I200J0D01*
G02Y1508346I-1661J-1458D01*
G03X475274Y1508214I150J-132D01*
G01Y1506275D01*
G03X475324Y1506143I200J0D01*
G02Y1503227I-1661J-1458D01*
G03X475274Y1503095I150J-132D01*
G01Y1502476D01*
G02X475072Y1502274I-202J0D01*
G01X472252D01*
G02X472050Y1502476I0J202D01*
G01Y1503095D01*
G03X472000Y1503227I-200J0D01*
G02Y1506143I1661J1458D01*
G03X472050Y1506275I-150J132D01*
G01Y1508214D01*
G03X472000Y1508346I-200J0D01*
G02Y1511262I1661J1458D01*
G03X472050Y1511394I-150J132D01*
G01Y1512014D01*
G02X472252Y1512216I202J0D01*
G37*
G36*
G01X645480D02*
X648300D01*
G02X648502Y1512014I0J-202D01*
G01Y1511394D01*
G03X648552Y1511262I200J0D01*
G02Y1508346I-1661J-1458D01*
G03X648502Y1508214I150J-132D01*
G01Y1506275D01*
G03X648552Y1506143I200J0D01*
G02Y1503227I-1661J-1458D01*
G03X648502Y1503095I150J-132D01*
G01Y1502476D01*
G02X648300Y1502274I-202J0D01*
G01X645480D01*
G02X645278Y1502476I0J202D01*
G01Y1503095D01*
G03X645228Y1503227I-200J0D01*
G02Y1506143I1661J1458D01*
G03X645278Y1506275I-150J132D01*
G01Y1508214D01*
G03X645228Y1508346I-200J0D01*
G02Y1511262I1661J1458D01*
G03X645278Y1511394I-150J132D01*
G01Y1512014D01*
G02X645480Y1512216I202J0D01*
G37*
G36*
G01X1165086D02*
X1167906D01*
G02X1168108Y1512014I0J-202D01*
G01Y1511394D01*
G03X1168158Y1511262I200J0D01*
G02Y1508346I-1661J-1458D01*
G03X1168108Y1508214I150J-132D01*
G01Y1506275D01*
G03X1168158Y1506143I200J0D01*
G02Y1503227I-1661J-1458D01*
G03X1168108Y1503095I150J-132D01*
G01Y1502476D01*
G02X1167906Y1502274I-202J0D01*
G01X1165086D01*
G02X1164884Y1502476I0J202D01*
G01Y1503095D01*
G03X1164834Y1503227I-200J0D01*
G02Y1506143I1661J1458D01*
G03X1164884Y1506275I-150J132D01*
G01Y1508214D01*
G03X1164834Y1508346I-200J0D01*
G02Y1511262I1661J1458D01*
G03X1164884Y1511394I-150J132D01*
G01Y1512014D01*
G02X1165086Y1512216I202J0D01*
G37*
G36*
G01X1182408D02*
X1185228D01*
G02X1185430Y1512014I0J-202D01*
G01Y1511394D01*
G03X1185480Y1511262I200J0D01*
G02Y1508346I-1661J-1458D01*
G03X1185430Y1508214I150J-132D01*
G01Y1506275D01*
G03X1185480Y1506143I200J0D01*
G02Y1503227I-1661J-1458D01*
G03X1185430Y1503095I150J-132D01*
G01Y1502476D01*
G02X1185228Y1502274I-202J0D01*
G01X1182408D01*
G02X1182206Y1502476I0J202D01*
G01Y1503095D01*
G03X1182156Y1503227I-200J0D01*
G02Y1506143I1661J1458D01*
G03X1182206Y1506275I-150J132D01*
G01Y1508214D01*
G03X1182156Y1508346I-200J0D01*
G02Y1511262I1661J1458D01*
G03X1182206Y1511394I-150J132D01*
G01Y1512014D01*
G02X1182408Y1512216I202J0D01*
G37*
G36*
G01X1320992D02*
X1323812D01*
G02X1324014Y1512014I0J-202D01*
G01Y1511394D01*
G03X1324064Y1511262I200J0D01*
G02Y1508346I-1661J-1458D01*
G03X1324014Y1508214I150J-132D01*
G01Y1506275D01*
G03X1324064Y1506143I200J0D01*
G02Y1503227I-1661J-1458D01*
G03X1324014Y1503095I150J-132D01*
G01Y1502476D01*
G02X1323812Y1502274I-202J0D01*
G01X1320992D01*
G02X1320790Y1502476I0J202D01*
G01Y1503095D01*
G03X1320740Y1503227I-200J0D01*
G02Y1506143I1661J1458D01*
G03X1320790Y1506275I-150J132D01*
G01Y1508214D01*
G03X1320740Y1508346I-200J0D01*
G02Y1511262I1661J1458D01*
G03X1320790Y1511394I-150J132D01*
G01Y1512014D01*
G02X1320992Y1512216I202J0D01*
G37*
G36*
G01X1494220D02*
X1497040D01*
G02X1497242Y1512014I0J-202D01*
G01Y1511394D01*
G03X1497292Y1511262I200J0D01*
G02Y1508346I-1661J-1458D01*
G03X1497242Y1508214I150J-132D01*
G01Y1506275D01*
G03X1497292Y1506143I200J0D01*
G02Y1503227I-1661J-1458D01*
G03X1497242Y1503095I150J-132D01*
G01Y1502476D01*
G02X1497040Y1502274I-202J0D01*
G01X1494220D01*
G02X1494018Y1502476I0J202D01*
G01Y1503095D01*
G03X1493968Y1503227I-200J0D01*
G02Y1506143I1661J1458D01*
G03X1494018Y1506275I-150J132D01*
G01Y1508214D01*
G03X1493968Y1508346I-200J0D01*
G02Y1511262I1661J1458D01*
G03X1494018Y1511394I-150J132D01*
G01Y1512014D01*
G02X1494220Y1512216I202J0D01*
G37*
G36*
G01X125795D02*
X128615D01*
G02X128818Y1512014I1J-202D01*
G01Y1511392D01*
G03X128868Y1511260I200J0D01*
G02Y1508348I-1664J-1456D01*
G03X128818Y1508216I150J-132D01*
G01Y1506273D01*
G03X128868Y1506141I200J0D01*
G02Y1503229I-1664J-1456D01*
G03X128818Y1503097I150J-132D01*
G01Y1502476D01*
G02X128615Y1502274I-203J1D01*
G01X125795D01*
G02X125592Y1502476I-1J202D01*
G01Y1503097D01*
G03X125542Y1503229I-200J0D01*
G02Y1506141I1664J1456D01*
G03X125592Y1506273I-150J132D01*
G01Y1508216D01*
G03X125542Y1508348I-200J0D01*
G02Y1511260I1664J1456D01*
G03X125592Y1511392I-150J132D01*
G01Y1512014D01*
G02X125795Y1512216I203J-1D01*
G37*
G36*
G01X299023D02*
X301843D01*
G02X302046Y1512014I1J-202D01*
G01Y1511392D01*
G03X302096Y1511260I200J0D01*
G02Y1508348I-1664J-1456D01*
G03X302046Y1508216I150J-132D01*
G01Y1506273D01*
G03X302096Y1506141I200J0D01*
G02Y1503229I-1664J-1456D01*
G03X302046Y1503097I150J-132D01*
G01Y1502476D01*
G02X301843Y1502274I-203J1D01*
G01X299023D01*
G02X298820Y1502476I-1J202D01*
G01Y1503097D01*
G03X298770Y1503229I-200J0D01*
G02Y1506141I1664J1456D01*
G03X298820Y1506273I-150J132D01*
G01Y1508216D01*
G03X298770Y1508348I-200J0D01*
G02Y1511260I1664J1456D01*
G03X298820Y1511392I-150J132D01*
G01Y1512014D01*
G02X299023Y1512216I203J-1D01*
G37*
G36*
G01X454929D02*
X457749D01*
G02X457952Y1512014I1J-202D01*
G01Y1511392D01*
G03X458002Y1511260I200J0D01*
G02Y1508348I-1664J-1456D01*
G03X457952Y1508216I150J-132D01*
G01Y1506273D01*
G03X458002Y1506141I200J0D01*
G02Y1503229I-1664J-1456D01*
G03X457952Y1503097I150J-132D01*
G01Y1502476D01*
G02X457749Y1502274I-203J1D01*
G01X454929D01*
G02X454726Y1502476I-1J202D01*
G01Y1503097D01*
G03X454676Y1503229I-200J0D01*
G02Y1506141I1664J1456D01*
G03X454726Y1506273I-150J132D01*
G01Y1508216D01*
G03X454676Y1508348I-200J0D01*
G02Y1511260I1664J1456D01*
G03X454726Y1511392I-150J132D01*
G01Y1512014D01*
G02X454929Y1512216I203J-1D01*
G37*
G36*
G01X489575D02*
X492395D01*
G02X492598Y1512014I1J-202D01*
G01Y1511392D01*
G03X492648Y1511260I200J0D01*
G02Y1508348I-1664J-1456D01*
G03X492598Y1508216I150J-132D01*
G01Y1506273D01*
G03X492648Y1506141I200J0D01*
G02Y1503229I-1664J-1456D01*
G03X492598Y1503097I150J-132D01*
G01Y1502476D01*
G02X492395Y1502274I-203J1D01*
G01X489575D01*
G02X489372Y1502476I-1J202D01*
G01Y1503097D01*
G03X489322Y1503229I-200J0D01*
G02Y1506141I1664J1456D01*
G03X489372Y1506273I-150J132D01*
G01Y1508216D01*
G03X489322Y1508348I-200J0D01*
G02Y1511260I1664J1456D01*
G03X489372Y1511392I-150J132D01*
G01Y1512014D01*
G02X489575Y1512216I203J-1D01*
G37*
G36*
G01X506897D02*
X509717D01*
G02X509920Y1512014I1J-202D01*
G01Y1511392D01*
G03X509970Y1511260I200J0D01*
G02Y1508348I-1664J-1456D01*
G03X509920Y1508216I150J-132D01*
G01Y1506273D01*
G03X509970Y1506141I200J0D01*
G02Y1503229I-1664J-1456D01*
G03X509920Y1503097I150J-132D01*
G01Y1502476D01*
G02X509717Y1502274I-203J1D01*
G01X506897D01*
G02X506694Y1502476I-1J202D01*
G01Y1503097D01*
G03X506644Y1503229I-200J0D01*
G02Y1506141I1664J1456D01*
G03X506694Y1506273I-150J132D01*
G01Y1508216D01*
G03X506644Y1508348I-200J0D01*
G02Y1511260I1664J1456D01*
G03X506694Y1511392I-150J132D01*
G01Y1512014D01*
G02X506897Y1512216I203J-1D01*
G37*
G36*
G01X662803D02*
X665623D01*
G02X665826Y1512014I1J-202D01*
G01Y1511392D01*
G03X665876Y1511260I200J0D01*
G02Y1508348I-1664J-1456D01*
G03X665826Y1508216I150J-132D01*
G01Y1506273D01*
G03X665876Y1506141I200J0D01*
G02Y1503229I-1664J-1456D01*
G03X665826Y1503097I150J-132D01*
G01Y1502476D01*
G02X665623Y1502274I-203J1D01*
G01X662803D01*
G02X662600Y1502476I-1J202D01*
G01Y1503097D01*
G03X662550Y1503229I-200J0D01*
G02Y1506141I1664J1456D01*
G03X662600Y1506273I-150J132D01*
G01Y1508216D01*
G03X662550Y1508348I-200J0D01*
G02Y1511260I1664J1456D01*
G03X662600Y1511392I-150J132D01*
G01Y1512014D01*
G02X662803Y1512216I203J-1D01*
G37*
G36*
G01X680125D02*
X682945D01*
G02X683148Y1512014I1J-202D01*
G01Y1511392D01*
G03X683198Y1511260I200J0D01*
G02Y1508348I-1664J-1456D01*
G03X683148Y1508216I150J-132D01*
G01Y1506273D01*
G03X683198Y1506141I200J0D01*
G02Y1503229I-1664J-1456D01*
G03X683148Y1503097I150J-132D01*
G01Y1502476D01*
G02X682945Y1502274I-203J1D01*
G01X680125D01*
G02X679922Y1502476I-1J202D01*
G01Y1503097D01*
G03X679872Y1503229I-200J0D01*
G02Y1506141I1664J1456D01*
G03X679922Y1506273I-150J132D01*
G01Y1508216D01*
G03X679872Y1508348I-200J0D01*
G02Y1511260I1664J1456D01*
G03X679922Y1511392I-150J132D01*
G01Y1512014D01*
G02X680125Y1512216I203J-1D01*
G37*
G36*
G01X1303669D02*
X1306489D01*
G02X1306692Y1512014I1J-202D01*
G01Y1511392D01*
G03X1306742Y1511260I200J0D01*
G02Y1508348I-1664J-1456D01*
G03X1306692Y1508216I150J-132D01*
G01Y1506273D01*
G03X1306742Y1506141I200J0D01*
G02Y1503229I-1664J-1456D01*
G03X1306692Y1503097I150J-132D01*
G01Y1502476D01*
G02X1306489Y1502274I-203J1D01*
G01X1303669D01*
G02X1303466Y1502476I-1J202D01*
G01Y1503097D01*
G03X1303416Y1503229I-200J0D01*
G02Y1506141I1664J1456D01*
G03X1303466Y1506273I-150J132D01*
G01Y1508216D01*
G03X1303416Y1508348I-200J0D01*
G02Y1511260I1664J1456D01*
G03X1303466Y1511392I-150J132D01*
G01Y1512014D01*
G02X1303669Y1512216I203J-1D01*
G37*
G36*
G01X1338315D02*
X1341135D01*
G02X1341338Y1512014I1J-202D01*
G01Y1511392D01*
G03X1341388Y1511260I200J0D01*
G02Y1508348I-1664J-1456D01*
G03X1341338Y1508216I150J-132D01*
G01Y1506273D01*
G03X1341388Y1506141I200J0D01*
G02Y1503229I-1664J-1456D01*
G03X1341338Y1503097I150J-132D01*
G01Y1502476D01*
G02X1341135Y1502274I-203J1D01*
G01X1338315D01*
G02X1338112Y1502476I-1J202D01*
G01Y1503097D01*
G03X1338062Y1503229I-200J0D01*
G02Y1506141I1664J1456D01*
G03X1338112Y1506273I-150J132D01*
G01Y1508216D01*
G03X1338062Y1508348I-200J0D01*
G02Y1511260I1664J1456D01*
G03X1338112Y1511392I-150J132D01*
G01Y1512014D01*
G02X1338315Y1512216I203J-1D01*
G37*
G36*
G01X1355637D02*
X1358457D01*
G02X1358660Y1512014I1J-202D01*
G01Y1511392D01*
G03X1358710Y1511260I200J0D01*
G02Y1508348I-1664J-1456D01*
G03X1358660Y1508216I150J-132D01*
G01Y1506273D01*
G03X1358710Y1506141I200J0D01*
G02Y1503229I-1664J-1456D01*
G03X1358660Y1503097I150J-132D01*
G01Y1502476D01*
G02X1358457Y1502274I-203J1D01*
G01X1355637D01*
G02X1355434Y1502476I-1J202D01*
G01Y1503097D01*
G03X1355384Y1503229I-200J0D01*
G02Y1506141I1664J1456D01*
G03X1355434Y1506273I-150J132D01*
G01Y1508216D01*
G03X1355384Y1508348I-200J0D01*
G02Y1511260I1664J1456D01*
G03X1355434Y1511392I-150J132D01*
G01Y1512014D01*
G02X1355637Y1512216I203J-1D01*
G37*
G36*
G01X1476897D02*
X1479717D01*
G02X1479920Y1512014I1J-202D01*
G01Y1511392D01*
G03X1479970Y1511260I200J0D01*
G02Y1508348I-1664J-1456D01*
G03X1479920Y1508216I150J-132D01*
G01Y1506273D01*
G03X1479970Y1506141I200J0D01*
G02Y1503229I-1664J-1456D01*
G03X1479920Y1503097I150J-132D01*
G01Y1502476D01*
G02X1479717Y1502274I-203J1D01*
G01X1476897D01*
G02X1476694Y1502476I-1J202D01*
G01Y1503097D01*
G03X1476644Y1503229I-200J0D01*
G02Y1506141I1664J1456D01*
G03X1476694Y1506273I-150J132D01*
G01Y1508216D01*
G03X1476644Y1508348I-200J0D01*
G02Y1511260I1664J1456D01*
G03X1476694Y1511392I-150J132D01*
G01Y1512014D01*
G02X1476897Y1512216I203J-1D01*
G37*
G36*
G01X1511543D02*
X1514363D01*
G02X1514566Y1512014I1J-202D01*
G01Y1511392D01*
G03X1514616Y1511260I200J0D01*
G02Y1508348I-1664J-1456D01*
G03X1514566Y1508216I150J-132D01*
G01Y1506273D01*
G03X1514616Y1506141I200J0D01*
G02Y1503229I-1664J-1456D01*
G03X1514566Y1503097I150J-132D01*
G01Y1502476D01*
G02X1514363Y1502274I-203J1D01*
G01X1511543D01*
G02X1511340Y1502476I-1J202D01*
G01Y1503097D01*
G03X1511290Y1503229I-200J0D01*
G02Y1506141I1664J1456D01*
G03X1511340Y1506273I-150J132D01*
G01Y1508216D01*
G03X1511290Y1508348I-200J0D01*
G02Y1511260I1664J1456D01*
G03X1511340Y1511392I-150J132D01*
G01Y1512014D01*
G02X1511543Y1512216I203J-1D01*
G37*
G36*
G01X1528865D02*
X1531685D01*
G02X1531888Y1512014I1J-202D01*
G01Y1511392D01*
G03X1531938Y1511260I200J0D01*
G02Y1508348I-1664J-1456D01*
G03X1531888Y1508216I150J-132D01*
G01Y1506273D01*
G03X1531938Y1506141I200J0D01*
G02Y1503229I-1664J-1456D01*
G03X1531888Y1503097I150J-132D01*
G01Y1502476D01*
G02X1531685Y1502274I-203J1D01*
G01X1528865D01*
G02X1528662Y1502476I-1J202D01*
G01Y1503097D01*
G03X1528612Y1503229I-200J0D01*
G02Y1506141I1664J1456D01*
G03X1528662Y1506273I-150J132D01*
G01Y1508216D01*
G03X1528612Y1508348I-200J0D01*
G02Y1511260I1664J1456D01*
G03X1528662Y1511392I-150J132D01*
G01Y1512014D01*
G02X1528865Y1512216I203J-1D01*
G37*
G36*
G01X1684771D02*
X1687591D01*
G02X1687794Y1512014I1J-202D01*
G01Y1511392D01*
G03X1687844Y1511260I200J0D01*
G02Y1508348I-1664J-1456D01*
G03X1687794Y1508216I150J-132D01*
G01Y1506273D01*
G03X1687844Y1506141I200J0D01*
G02Y1503229I-1664J-1456D01*
G03X1687794Y1503097I150J-132D01*
G01Y1502476D01*
G02X1687591Y1502274I-203J1D01*
G01X1684771D01*
G02X1684568Y1502476I-1J202D01*
G01Y1503097D01*
G03X1684518Y1503229I-200J0D01*
G02Y1506141I1664J1456D01*
G03X1684568Y1506273I-150J132D01*
G01Y1508216D01*
G03X1684518Y1508348I-200J0D01*
G02Y1511260I1664J1456D01*
G03X1684568Y1511392I-150J132D01*
G01Y1512014D01*
G02X1684771Y1512216I203J-1D01*
G37*
G36*
G01X1702093D02*
X1704913D01*
G02X1705116Y1512014I1J-202D01*
G01Y1511392D01*
G03X1705166Y1511260I200J0D01*
G02Y1508348I-1664J-1456D01*
G03X1705116Y1508216I150J-132D01*
G01Y1506273D01*
G03X1705166Y1506141I200J0D01*
G02Y1503229I-1664J-1456D01*
G03X1705116Y1503097I150J-132D01*
G01Y1502476D01*
G02X1704913Y1502274I-203J1D01*
G01X1702093D01*
G02X1701890Y1502476I-1J202D01*
G01Y1503097D01*
G03X1701840Y1503229I-200J0D01*
G02Y1506141I1664J1456D01*
G03X1701890Y1506273I-150J132D01*
G01Y1508216D01*
G03X1701840Y1508348I-200J0D01*
G02Y1511260I1664J1456D01*
G03X1701890Y1511392I-150J132D01*
G01Y1512014D01*
G02X1702093Y1512216I203J-1D01*
G37*
G36*
G01X134456Y1516546D02*
X137276D01*
G02X137478Y1516344I0J-202D01*
G01Y1515724D01*
G03X137528Y1515592I200J0D01*
G02Y1512676I-1661J-1458D01*
G03X137478Y1512544I150J-132D01*
G01Y1510606D01*
G03X137528Y1510474I200J0D01*
G02Y1507558I-1661J-1458D01*
G03X137478Y1507426I150J-132D01*
G01Y1506806D01*
G02X137276Y1506604I-202J0D01*
G01X134456D01*
G02X134254Y1506806I0J202D01*
G01Y1507426D01*
G03X134204Y1507558I-200J0D01*
G02Y1510474I1661J1458D01*
G03X134254Y1510606I-150J132D01*
G01Y1512544D01*
G03X134204Y1512676I-200J0D01*
G02Y1515592I1661J1458D01*
G03X134254Y1515724I-150J132D01*
G01Y1516344D01*
G02X134456Y1516546I202J0D01*
G37*
G36*
G01X169102D02*
X171922D01*
G02X172124Y1516344I0J-202D01*
G01Y1515724D01*
G03X172174Y1515592I200J0D01*
G02Y1512676I-1661J-1458D01*
G03X172124Y1512544I150J-132D01*
G01Y1510606D01*
G03X172174Y1510474I200J0D01*
G02Y1507558I-1661J-1458D01*
G03X172124Y1507426I150J-132D01*
G01Y1506806D01*
G02X171922Y1506604I-202J0D01*
G01X169102D01*
G02X168900Y1506806I0J202D01*
G01Y1507426D01*
G03X168850Y1507558I-200J0D01*
G02Y1510474I1661J1458D01*
G03X168900Y1510606I-150J132D01*
G01Y1512544D01*
G03X168850Y1512676I-200J0D01*
G02Y1515592I1661J1458D01*
G03X168900Y1515724I-150J132D01*
G01Y1516344D01*
G02X169102Y1516546I202J0D01*
G37*
G36*
G01X463590D02*
X466410D01*
G02X466612Y1516344I0J-202D01*
G01Y1515724D01*
G03X466662Y1515592I200J0D01*
G02Y1512676I-1661J-1458D01*
G03X466612Y1512544I150J-132D01*
G01Y1510606D01*
G03X466662Y1510474I200J0D01*
G02Y1507558I-1661J-1458D01*
G03X466612Y1507426I150J-132D01*
G01Y1506806D01*
G02X466410Y1506604I-202J0D01*
G01X463590D01*
G02X463388Y1506806I0J202D01*
G01Y1507426D01*
G03X463338Y1507558I-200J0D01*
G02Y1510474I1661J1458D01*
G03X463388Y1510606I-150J132D01*
G01Y1512544D01*
G03X463338Y1512676I-200J0D01*
G02Y1515592I1661J1458D01*
G03X463388Y1515724I-150J132D01*
G01Y1516344D01*
G02X463590Y1516546I202J0D01*
G37*
G36*
G01X498236D02*
X501056D01*
G02X501258Y1516344I0J-202D01*
G01Y1515724D01*
G03X501308Y1515592I200J0D01*
G02Y1512676I-1661J-1458D01*
G03X501258Y1512544I150J-132D01*
G01Y1510606D01*
G03X501308Y1510474I200J0D01*
G02Y1507558I-1661J-1458D01*
G03X501258Y1507426I150J-132D01*
G01Y1506806D01*
G02X501056Y1506604I-202J0D01*
G01X498236D01*
G02X498034Y1506806I0J202D01*
G01Y1507426D01*
G03X497984Y1507558I-200J0D01*
G02Y1510474I1661J1458D01*
G03X498034Y1510606I-150J132D01*
G01Y1512544D01*
G03X497984Y1512676I-200J0D01*
G02Y1515592I1661J1458D01*
G03X498034Y1515724I-150J132D01*
G01Y1516344D01*
G02X498236Y1516546I202J0D01*
G37*
G36*
G01X671464D02*
X674284D01*
G02X674486Y1516344I0J-202D01*
G01Y1515724D01*
G03X674536Y1515592I200J0D01*
G02Y1512676I-1661J-1458D01*
G03X674486Y1512544I150J-132D01*
G01Y1510606D01*
G03X674536Y1510474I200J0D01*
G02Y1507558I-1661J-1458D01*
G03X674486Y1507426I150J-132D01*
G01Y1506806D01*
G02X674284Y1506604I-202J0D01*
G01X671464D01*
G02X671262Y1506806I0J202D01*
G01Y1507426D01*
G03X671212Y1507558I-200J0D01*
G02Y1510474I1661J1458D01*
G03X671262Y1510606I-150J132D01*
G01Y1512544D01*
G03X671212Y1512676I-200J0D01*
G02Y1515592I1661J1458D01*
G03X671262Y1515724I-150J132D01*
G01Y1516344D01*
G02X671464Y1516546I202J0D01*
G37*
G36*
G01X1191070D02*
X1193890D01*
G02X1194092Y1516344I0J-202D01*
G01Y1515724D01*
G03X1194142Y1515592I200J0D01*
G02Y1512676I-1661J-1458D01*
G03X1194092Y1512544I150J-132D01*
G01Y1510606D01*
G03X1194142Y1510474I200J0D01*
G02Y1507558I-1661J-1458D01*
G03X1194092Y1507426I150J-132D01*
G01Y1506806D01*
G02X1193890Y1506604I-202J0D01*
G01X1191070D01*
G02X1190868Y1506806I0J202D01*
G01Y1507426D01*
G03X1190818Y1507558I-200J0D01*
G02Y1510474I1661J1458D01*
G03X1190868Y1510606I-150J132D01*
G01Y1512544D01*
G03X1190818Y1512676I-200J0D01*
G02Y1515592I1661J1458D01*
G03X1190868Y1515724I-150J132D01*
G01Y1516344D01*
G02X1191070Y1516546I202J0D01*
G37*
G36*
G01X1312330D02*
X1315150D01*
G02X1315352Y1516344I0J-202D01*
G01Y1515724D01*
G03X1315402Y1515592I200J0D01*
G02Y1512676I-1661J-1458D01*
G03X1315352Y1512544I150J-132D01*
G01Y1510606D01*
G03X1315402Y1510474I200J0D01*
G02Y1507558I-1661J-1458D01*
G03X1315352Y1507426I150J-132D01*
G01Y1506806D01*
G02X1315150Y1506604I-202J0D01*
G01X1312330D01*
G02X1312128Y1506806I0J202D01*
G01Y1507426D01*
G03X1312078Y1507558I-200J0D01*
G02Y1510474I1661J1458D01*
G03X1312128Y1510606I-150J132D01*
G01Y1512544D01*
G03X1312078Y1512676I-200J0D01*
G02Y1515592I1661J1458D01*
G03X1312128Y1515724I-150J132D01*
G01Y1516344D01*
G02X1312330Y1516546I202J0D01*
G37*
G36*
G01X1346976D02*
X1349796D01*
G02X1349998Y1516344I0J-202D01*
G01Y1515724D01*
G03X1350048Y1515592I200J0D01*
G02Y1512676I-1661J-1458D01*
G03X1349998Y1512544I150J-132D01*
G01Y1510606D01*
G03X1350048Y1510474I200J0D01*
G02Y1507558I-1661J-1458D01*
G03X1349998Y1507426I150J-132D01*
G01Y1506806D01*
G02X1349796Y1506604I-202J0D01*
G01X1346976D01*
G02X1346774Y1506806I0J202D01*
G01Y1507426D01*
G03X1346724Y1507558I-200J0D01*
G02Y1510474I1661J1458D01*
G03X1346774Y1510606I-150J132D01*
G01Y1512544D01*
G03X1346724Y1512676I-200J0D01*
G02Y1515592I1661J1458D01*
G03X1346774Y1515724I-150J132D01*
G01Y1516344D01*
G02X1346976Y1516546I202J0D01*
G37*
G36*
G01X1485558D02*
X1488378D01*
G02X1488580Y1516344I0J-202D01*
G01Y1515724D01*
G03X1488630Y1515592I200J0D01*
G02Y1512676I-1661J-1458D01*
G03X1488580Y1512544I150J-132D01*
G01Y1510606D01*
G03X1488630Y1510474I200J0D01*
G02Y1507558I-1661J-1458D01*
G03X1488580Y1507426I150J-132D01*
G01Y1506806D01*
G02X1488378Y1506604I-202J0D01*
G01X1485558D01*
G02X1485356Y1506806I0J202D01*
G01Y1507426D01*
G03X1485306Y1507558I-200J0D01*
G02Y1510474I1661J1458D01*
G03X1485356Y1510606I-150J132D01*
G01Y1512544D01*
G03X1485306Y1512676I-200J0D01*
G02Y1515592I1661J1458D01*
G03X1485356Y1515724I-150J132D01*
G01Y1516344D01*
G02X1485558Y1516546I202J0D01*
G37*
G36*
G01X1520204D02*
X1523024D01*
G02X1523226Y1516344I0J-202D01*
G01Y1515724D01*
G03X1523276Y1515592I200J0D01*
G02Y1512676I-1661J-1458D01*
G03X1523226Y1512544I150J-132D01*
G01Y1510606D01*
G03X1523276Y1510474I200J0D01*
G02Y1507558I-1661J-1458D01*
G03X1523226Y1507426I150J-132D01*
G01Y1506806D01*
G02X1523024Y1506604I-202J0D01*
G01X1520204D01*
G02X1520002Y1506806I0J202D01*
G01Y1507426D01*
G03X1519952Y1507558I-200J0D01*
G02Y1510474I1661J1458D01*
G03X1520002Y1510606I-150J132D01*
G01Y1512544D01*
G03X1519952Y1512676I-200J0D01*
G02Y1515592I1661J1458D01*
G03X1520002Y1515724I-150J132D01*
G01Y1516344D01*
G02X1520204Y1516546I202J0D01*
G37*
G36*
G01X1693432D02*
X1696252D01*
G02X1696454Y1516344I0J-202D01*
G01Y1515724D01*
G03X1696504Y1515592I200J0D01*
G02Y1512676I-1661J-1458D01*
G03X1696454Y1512544I150J-132D01*
G01Y1510606D01*
G03X1696504Y1510474I200J0D01*
G02Y1507558I-1661J-1458D01*
G03X1696454Y1507426I150J-132D01*
G01Y1506806D01*
G02X1696252Y1506604I-202J0D01*
G01X1693432D01*
G02X1693230Y1506806I0J202D01*
G01Y1507426D01*
G03X1693180Y1507558I-200J0D01*
G02Y1510474I1661J1458D01*
G03X1693230Y1510606I-150J132D01*
G01Y1512544D01*
G03X1693180Y1512676I-200J0D01*
G02Y1515592I1661J1458D01*
G03X1693230Y1515724I-150J132D01*
G01Y1516344D01*
G02X1693432Y1516546I202J0D01*
G37*
G36*
G01X151779D02*
X154599D01*
G02X154802Y1516344I1J-202D01*
G01Y1515722D01*
G03X154852Y1515590I200J0D01*
G02Y1512678I-1664J-1456D01*
G03X154802Y1512546I150J-132D01*
G01Y1510604D01*
G03X154852Y1510472I200J0D01*
G02Y1507560I-1664J-1456D01*
G03X154802Y1507428I150J-132D01*
G01Y1506806D01*
G02X154599Y1506604I-203J1D01*
G01X151779D01*
G02X151576Y1506806I-1J202D01*
G01Y1507428D01*
G03X151526Y1507560I-200J0D01*
G02Y1510472I1664J1456D01*
G03X151576Y1510604I-150J132D01*
G01Y1512546D01*
G03X151526Y1512678I-200J0D01*
G02Y1515590I1664J1456D01*
G03X151576Y1515722I-150J132D01*
G01Y1516344D01*
G02X151779Y1516546I203J-1D01*
G37*
G36*
G01X290361D02*
X293181D01*
G02X293384Y1516344I1J-202D01*
G01Y1515722D01*
G03X293434Y1515590I200J0D01*
G02Y1512678I-1664J-1456D01*
G03X293384Y1512546I150J-132D01*
G01Y1510604D01*
G03X293434Y1510472I200J0D01*
G02Y1507560I-1664J-1456D01*
G03X293384Y1507428I150J-132D01*
G01Y1506806D01*
G02X293181Y1506604I-203J1D01*
G01X290361D01*
G02X290158Y1506806I-1J202D01*
G01Y1507428D01*
G03X290108Y1507560I-200J0D01*
G02Y1510472I1664J1456D01*
G03X290158Y1510604I-150J132D01*
G01Y1512546D01*
G03X290108Y1512678I-200J0D01*
G02Y1515590I1664J1456D01*
G03X290158Y1515722I-150J132D01*
G01Y1516344D01*
G02X290361Y1516546I203J-1D01*
G37*
G36*
G01X480913D02*
X483733D01*
G02X483936Y1516344I1J-202D01*
G01Y1515722D01*
G03X483986Y1515590I200J0D01*
G02Y1512678I-1664J-1456D01*
G03X483936Y1512546I150J-132D01*
G01Y1510604D01*
G03X483986Y1510472I200J0D01*
G02Y1507560I-1664J-1456D01*
G03X483936Y1507428I150J-132D01*
G01Y1506806D01*
G02X483733Y1506604I-203J1D01*
G01X480913D01*
G02X480710Y1506806I-1J202D01*
G01Y1507428D01*
G03X480660Y1507560I-200J0D01*
G02Y1510472I1664J1456D01*
G03X480710Y1510604I-150J132D01*
G01Y1512546D01*
G03X480660Y1512678I-200J0D01*
G02Y1515590I1664J1456D01*
G03X480710Y1515722I-150J132D01*
G01Y1516344D01*
G02X480913Y1516546I203J-1D01*
G37*
G36*
G01X515559D02*
X518379D01*
G02X518582Y1516344I1J-202D01*
G01Y1515722D01*
G03X518632Y1515590I200J0D01*
G02Y1512678I-1664J-1456D01*
G03X518582Y1512546I150J-132D01*
G01Y1510604D01*
G03X518632Y1510472I200J0D01*
G02Y1507560I-1664J-1456D01*
G03X518582Y1507428I150J-132D01*
G01Y1506806D01*
G02X518379Y1506604I-203J1D01*
G01X515559D01*
G02X515356Y1506806I-1J202D01*
G01Y1507428D01*
G03X515306Y1507560I-200J0D01*
G02Y1510472I1664J1456D01*
G03X515356Y1510604I-150J132D01*
G01Y1512546D01*
G03X515306Y1512678I-200J0D01*
G02Y1515590I1664J1456D01*
G03X515356Y1515722I-150J132D01*
G01Y1516344D01*
G02X515559Y1516546I203J-1D01*
G37*
G36*
G01X654141D02*
X656961D01*
G02X657164Y1516344I1J-202D01*
G01Y1515722D01*
G03X657214Y1515590I200J0D01*
G02Y1512678I-1664J-1456D01*
G03X657164Y1512546I150J-132D01*
G01Y1510604D01*
G03X657214Y1510472I200J0D01*
G02Y1507560I-1664J-1456D01*
G03X657164Y1507428I150J-132D01*
G01Y1506806D01*
G02X656961Y1506604I-203J1D01*
G01X654141D01*
G02X653938Y1506806I-1J202D01*
G01Y1507428D01*
G03X653888Y1507560I-200J0D01*
G02Y1510472I1664J1456D01*
G03X653938Y1510604I-150J132D01*
G01Y1512546D01*
G03X653888Y1512678I-200J0D01*
G02Y1515590I1664J1456D01*
G03X653938Y1515722I-150J132D01*
G01Y1516344D01*
G02X654141Y1516546I203J-1D01*
G37*
G36*
G01X688787D02*
X691607D01*
G02X691810Y1516344I1J-202D01*
G01Y1515722D01*
G03X691860Y1515590I200J0D01*
G02Y1512678I-1664J-1456D01*
G03X691810Y1512546I150J-132D01*
G01Y1510604D01*
G03X691860Y1510472I200J0D01*
G02Y1507560I-1664J-1456D01*
G03X691810Y1507428I150J-132D01*
G01Y1506806D01*
G02X691607Y1506604I-203J1D01*
G01X688787D01*
G02X688584Y1506806I-1J202D01*
G01Y1507428D01*
G03X688534Y1507560I-200J0D01*
G02Y1510472I1664J1456D01*
G03X688584Y1510604I-150J132D01*
G01Y1512546D01*
G03X688534Y1512678I-200J0D01*
G02Y1515590I1664J1456D01*
G03X688584Y1515722I-150J132D01*
G01Y1516344D01*
G02X688787Y1516546I203J-1D01*
G37*
G36*
G01X1173747D02*
X1176567D01*
G02X1176770Y1516344I1J-202D01*
G01Y1515722D01*
G03X1176820Y1515590I200J0D01*
G02Y1512678I-1664J-1456D01*
G03X1176770Y1512546I150J-132D01*
G01Y1510604D01*
G03X1176820Y1510472I200J0D01*
G02Y1507560I-1664J-1456D01*
G03X1176770Y1507428I150J-132D01*
G01Y1506806D01*
G02X1176567Y1506604I-203J1D01*
G01X1173747D01*
G02X1173544Y1506806I-1J202D01*
G01Y1507428D01*
G03X1173494Y1507560I-200J0D01*
G02Y1510472I1664J1456D01*
G03X1173544Y1510604I-150J132D01*
G01Y1512546D01*
G03X1173494Y1512678I-200J0D01*
G02Y1515590I1664J1456D01*
G03X1173544Y1515722I-150J132D01*
G01Y1516344D01*
G02X1173747Y1516546I203J-1D01*
G37*
G36*
G01X1329653D02*
X1332473D01*
G02X1332676Y1516344I1J-202D01*
G01Y1515722D01*
G03X1332726Y1515590I200J0D01*
G02Y1512678I-1664J-1456D01*
G03X1332676Y1512546I150J-132D01*
G01Y1510604D01*
G03X1332726Y1510472I200J0D01*
G02Y1507560I-1664J-1456D01*
G03X1332676Y1507428I150J-132D01*
G01Y1506806D01*
G02X1332473Y1506604I-203J1D01*
G01X1329653D01*
G02X1329450Y1506806I-1J202D01*
G01Y1507428D01*
G03X1329400Y1507560I-200J0D01*
G02Y1510472I1664J1456D01*
G03X1329450Y1510604I-150J132D01*
G01Y1512546D01*
G03X1329400Y1512678I-200J0D01*
G02Y1515590I1664J1456D01*
G03X1329450Y1515722I-150J132D01*
G01Y1516344D01*
G02X1329653Y1516546I203J-1D01*
G37*
G36*
G01X1364299D02*
X1367119D01*
G02X1367322Y1516344I1J-202D01*
G01Y1515722D01*
G03X1367372Y1515590I200J0D01*
G02Y1512678I-1664J-1456D01*
G03X1367322Y1512546I150J-132D01*
G01Y1510604D01*
G03X1367372Y1510472I200J0D01*
G02Y1507560I-1664J-1456D01*
G03X1367322Y1507428I150J-132D01*
G01Y1506806D01*
G02X1367119Y1506604I-203J1D01*
G01X1364299D01*
G02X1364096Y1506806I-1J202D01*
G01Y1507428D01*
G03X1364046Y1507560I-200J0D01*
G02Y1510472I1664J1456D01*
G03X1364096Y1510604I-150J132D01*
G01Y1512546D01*
G03X1364046Y1512678I-200J0D01*
G02Y1515590I1664J1456D01*
G03X1364096Y1515722I-150J132D01*
G01Y1516344D01*
G02X1364299Y1516546I203J-1D01*
G37*
G36*
G01X1502881D02*
X1505701D01*
G02X1505904Y1516344I1J-202D01*
G01Y1515722D01*
G03X1505954Y1515590I200J0D01*
G02Y1512678I-1664J-1456D01*
G03X1505904Y1512546I150J-132D01*
G01Y1510604D01*
G03X1505954Y1510472I200J0D01*
G02Y1507560I-1664J-1456D01*
G03X1505904Y1507428I150J-132D01*
G01Y1506806D01*
G02X1505701Y1506604I-203J1D01*
G01X1502881D01*
G02X1502678Y1506806I-1J202D01*
G01Y1507428D01*
G03X1502628Y1507560I-200J0D01*
G02Y1510472I1664J1456D01*
G03X1502678Y1510604I-150J132D01*
G01Y1512546D01*
G03X1502628Y1512678I-200J0D01*
G02Y1515590I1664J1456D01*
G03X1502678Y1515722I-150J132D01*
G01Y1516344D01*
G02X1502881Y1516546I203J-1D01*
G37*
G36*
G01X1537527D02*
X1540347D01*
G02X1540550Y1516344I1J-202D01*
G01Y1515722D01*
G03X1540600Y1515590I200J0D01*
G02Y1512678I-1664J-1456D01*
G03X1540550Y1512546I150J-132D01*
G01Y1510604D01*
G03X1540600Y1510472I200J0D01*
G02Y1507560I-1664J-1456D01*
G03X1540550Y1507428I150J-132D01*
G01Y1506806D01*
G02X1540347Y1506604I-203J1D01*
G01X1537527D01*
G02X1537324Y1506806I-1J202D01*
G01Y1507428D01*
G03X1537274Y1507560I-200J0D01*
G02Y1510472I1664J1456D01*
G03X1537324Y1510604I-150J132D01*
G01Y1512546D01*
G03X1537274Y1512678I-200J0D01*
G02Y1515590I1664J1456D01*
G03X1537324Y1515722I-150J132D01*
G01Y1516344D01*
G02X1537527Y1516546I203J-1D01*
G37*
G36*
G01X1710755D02*
X1713575D01*
G02X1713778Y1516344I1J-202D01*
G01Y1515722D01*
G03X1713828Y1515590I200J0D01*
G02Y1512678I-1664J-1456D01*
G03X1713778Y1512546I150J-132D01*
G01Y1510604D01*
G03X1713828Y1510472I200J0D01*
G02Y1507560I-1664J-1456D01*
G03X1713778Y1507428I150J-132D01*
G01Y1506806D01*
G02X1713575Y1506604I-203J1D01*
G01X1710755D01*
G02X1710552Y1506806I-1J202D01*
G01Y1507428D01*
G03X1710502Y1507560I-200J0D01*
G02Y1510472I1664J1456D01*
G03X1710552Y1510604I-150J132D01*
G01Y1512546D01*
G03X1710502Y1512678I-200J0D01*
G02Y1515590I1664J1456D01*
G03X1710552Y1515722I-150J132D01*
G01Y1516344D01*
G02X1710755Y1516546I203J-1D01*
G37*
G36*
G01X108472Y1568516D02*
X111292D01*
G02X111494Y1568313I-1J-203D01*
G01Y1567693D01*
G03X111544Y1567561I200J0D01*
G02Y1564645I-1661J-1458D01*
G03X111494Y1564513I150J-132D01*
G01Y1562575D01*
G03X111544Y1562443I200J0D01*
G02Y1559527I-1661J-1458D01*
G03X111494Y1559395I150J-132D01*
G01Y1558775D01*
G02X111292Y1558572I-202J-1D01*
G01X108472D01*
G02X108270Y1558775I1J203D01*
G01Y1559395D01*
G03X108220Y1559527I-200J0D01*
G02Y1562443I1661J1458D01*
G03X108270Y1562575I-150J132D01*
G01Y1564513D01*
G03X108220Y1564645I-200J0D01*
G02Y1567561I1661J1458D01*
G03X108270Y1567693I-150J132D01*
G01Y1568313D01*
G02X108472Y1568516I202J1D01*
G37*
G36*
G01X125795D02*
X128615D01*
G02X128818Y1568313I0J-203D01*
G01Y1567691D01*
G03X128868Y1567559I200J0D01*
G02Y1564647I-1664J-1456D01*
G03X128818Y1564515I150J-132D01*
G01Y1562573D01*
G03X128868Y1562441I200J0D01*
G02Y1559529I-1664J-1456D01*
G03X128818Y1559397I150J-132D01*
G01Y1558775D01*
G02X128615Y1558572I-203J0D01*
G01X125795D01*
G02X125592Y1558775I0J203D01*
G01Y1559397D01*
G03X125542Y1559529I-200J0D01*
G02Y1562441I1664J1456D01*
G03X125592Y1562573I-150J132D01*
G01Y1564515D01*
G03X125542Y1564647I-200J0D01*
G02Y1567559I1664J1456D01*
G03X125592Y1567691I-150J132D01*
G01Y1568313D01*
G02X125795Y1568516I203J0D01*
G37*
G36*
G01X143118D02*
X145938D01*
G02X146140Y1568313I-1J-203D01*
G01Y1567693D01*
G03X146190Y1567561I200J0D01*
G02Y1564645I-1661J-1458D01*
G03X146140Y1564513I150J-132D01*
G01Y1562575D01*
G03X146190Y1562443I200J0D01*
G02Y1559527I-1661J-1458D01*
G03X146140Y1559395I150J-132D01*
G01Y1558775D01*
G02X145938Y1558572I-202J-1D01*
G01X143118D01*
G02X142916Y1558775I1J203D01*
G01Y1559395D01*
G03X142866Y1559527I-200J0D01*
G02Y1562443I1661J1458D01*
G03X142916Y1562575I-150J132D01*
G01Y1564513D01*
G03X142866Y1564645I-200J0D01*
G02Y1567561I1661J1458D01*
G03X142916Y1567693I-150J132D01*
G01Y1568313D01*
G02X143118Y1568516I202J1D01*
G37*
G36*
G01X160440D02*
X163260D01*
G02X163462Y1568313I-1J-203D01*
G01Y1567693D01*
G03X163512Y1567561I200J0D01*
G02Y1564645I-1661J-1458D01*
G03X163462Y1564513I150J-132D01*
G01Y1562575D01*
G03X163512Y1562443I200J0D01*
G02Y1559527I-1661J-1458D01*
G03X163462Y1559395I150J-132D01*
G01Y1558775D01*
G02X163260Y1558572I-202J-1D01*
G01X160440D01*
G02X160238Y1558775I1J203D01*
G01Y1559395D01*
G03X160188Y1559527I-200J0D01*
G02Y1562443I1661J1458D01*
G03X160238Y1562575I-150J132D01*
G01Y1564513D01*
G03X160188Y1564645I-200J0D01*
G02Y1567561I1661J1458D01*
G03X160238Y1567693I-150J132D01*
G01Y1568313D01*
G02X160440Y1568516I202J1D01*
G37*
G36*
G01X281700D02*
X284520D01*
G02X284722Y1568313I-1J-203D01*
G01Y1567693D01*
G03X284772Y1567561I200J0D01*
G02Y1564645I-1661J-1458D01*
G03X284722Y1564513I150J-132D01*
G01Y1562575D01*
G03X284772Y1562443I200J0D01*
G02Y1559527I-1661J-1458D01*
G03X284722Y1559395I150J-132D01*
G01Y1558775D01*
G02X284520Y1558572I-202J-1D01*
G01X281700D01*
G02X281498Y1558775I1J203D01*
G01Y1559395D01*
G03X281448Y1559527I-200J0D01*
G02Y1562443I1661J1458D01*
G03X281498Y1562575I-150J132D01*
G01Y1564513D01*
G03X281448Y1564645I-200J0D01*
G02Y1567561I1661J1458D01*
G03X281498Y1567693I-150J132D01*
G01Y1568313D01*
G02X281700Y1568516I202J1D01*
G37*
G36*
G01X299023D02*
X301843D01*
G02X302046Y1568313I0J-203D01*
G01Y1567691D01*
G03X302096Y1567559I200J0D01*
G02Y1564647I-1664J-1456D01*
G03X302046Y1564515I150J-132D01*
G01Y1562573D01*
G03X302096Y1562441I200J0D01*
G02Y1559529I-1664J-1456D01*
G03X302046Y1559397I150J-132D01*
G01Y1558775D01*
G02X301843Y1558572I-203J0D01*
G01X299023D01*
G02X298820Y1558775I0J203D01*
G01Y1559397D01*
G03X298770Y1559529I-200J0D01*
G02Y1562441I1664J1456D01*
G03X298820Y1562573I-150J132D01*
G01Y1564515D01*
G03X298770Y1564647I-200J0D01*
G02Y1567559I1664J1456D01*
G03X298820Y1567691I-150J132D01*
G01Y1568313D01*
G02X299023Y1568516I203J0D01*
G37*
G36*
G01X316346D02*
X319166D01*
G02X319368Y1568313I-1J-203D01*
G01Y1567693D01*
G03X319418Y1567561I200J0D01*
G02Y1564645I-1661J-1458D01*
G03X319368Y1564513I150J-132D01*
G01Y1562575D01*
G03X319418Y1562443I200J0D01*
G02Y1559527I-1661J-1458D01*
G03X319368Y1559395I150J-132D01*
G01Y1558775D01*
G02X319166Y1558572I-202J-1D01*
G01X316346D01*
G02X316144Y1558775I1J203D01*
G01Y1559395D01*
G03X316094Y1559527I-200J0D01*
G02Y1562443I1661J1458D01*
G03X316144Y1562575I-150J132D01*
G01Y1564513D01*
G03X316094Y1564645I-200J0D01*
G02Y1567561I1661J1458D01*
G03X316144Y1567693I-150J132D01*
G01Y1568313D01*
G02X316346Y1568516I202J1D01*
G37*
G36*
G01X333668D02*
X336488D01*
G02X336690Y1568313I-1J-203D01*
G01Y1567693D01*
G03X336740Y1567561I200J0D01*
G02Y1564645I-1661J-1458D01*
G03X336690Y1564513I150J-132D01*
G01Y1562575D01*
G03X336740Y1562443I200J0D01*
G02Y1559527I-1661J-1458D01*
G03X336690Y1559395I150J-132D01*
G01Y1558775D01*
G02X336488Y1558572I-202J-1D01*
G01X333668D01*
G02X333466Y1558775I1J203D01*
G01Y1559395D01*
G03X333416Y1559527I-200J0D01*
G02Y1562443I1661J1458D01*
G03X333466Y1562575I-150J132D01*
G01Y1564513D01*
G03X333416Y1564645I-200J0D01*
G02Y1567561I1661J1458D01*
G03X333466Y1567693I-150J132D01*
G01Y1568313D01*
G02X333668Y1568516I202J1D01*
G37*
G36*
G01X628157D02*
X630977D01*
G02X631180Y1568313I0J-203D01*
G01Y1567691D01*
G03X631230Y1567559I200J0D01*
G02Y1564647I-1664J-1456D01*
G03X631180Y1564515I150J-132D01*
G01Y1562573D01*
G03X631230Y1562441I200J0D01*
G02Y1559529I-1664J-1456D01*
G03X631180Y1559397I150J-132D01*
G01Y1558775D01*
G02X630977Y1558572I-203J0D01*
G01X628157D01*
G02X627954Y1558775I0J203D01*
G01Y1559397D01*
G03X627904Y1559529I-200J0D01*
G02Y1562441I1664J1456D01*
G03X627954Y1562573I-150J132D01*
G01Y1564515D01*
G03X627904Y1564647I-200J0D01*
G02Y1567559I1664J1456D01*
G03X627954Y1567691I-150J132D01*
G01Y1568313D01*
G02X628157Y1568516I203J0D01*
G37*
G36*
G01X645480D02*
X648300D01*
G02X648502Y1568313I-1J-203D01*
G01Y1567693D01*
G03X648552Y1567561I200J0D01*
G02Y1564645I-1661J-1458D01*
G03X648502Y1564513I150J-132D01*
G01Y1562575D01*
G03X648552Y1562443I200J0D01*
G02Y1559527I-1661J-1458D01*
G03X648502Y1559395I150J-132D01*
G01Y1558775D01*
G02X648300Y1558572I-202J-1D01*
G01X645480D01*
G02X645278Y1558775I1J203D01*
G01Y1559395D01*
G03X645228Y1559527I-200J0D01*
G02Y1562443I1661J1458D01*
G03X645278Y1562575I-150J132D01*
G01Y1564513D01*
G03X645228Y1564645I-200J0D01*
G02Y1567561I1661J1458D01*
G03X645278Y1567693I-150J132D01*
G01Y1568313D01*
G02X645480Y1568516I202J1D01*
G37*
G36*
G01X662803D02*
X665623D01*
G02X665826Y1568313I0J-203D01*
G01Y1567691D01*
G03X665876Y1567559I200J0D01*
G02Y1564647I-1664J-1456D01*
G03X665826Y1564515I150J-132D01*
G01Y1562573D01*
G03X665876Y1562441I200J0D01*
G02Y1559529I-1664J-1456D01*
G03X665826Y1559397I150J-132D01*
G01Y1558775D01*
G02X665623Y1558572I-203J0D01*
G01X662803D01*
G02X662600Y1558775I0J203D01*
G01Y1559397D01*
G03X662550Y1559529I-200J0D01*
G02Y1562441I1664J1456D01*
G03X662600Y1562573I-150J132D01*
G01Y1564515D01*
G03X662550Y1564647I-200J0D01*
G02Y1567559I1664J1456D01*
G03X662600Y1567691I-150J132D01*
G01Y1568313D01*
G02X662803Y1568516I203J0D01*
G37*
G36*
G01X680125D02*
X682945D01*
G02X683148Y1568313I0J-203D01*
G01Y1567691D01*
G03X683198Y1567559I200J0D01*
G02Y1564647I-1664J-1456D01*
G03X683148Y1564515I150J-132D01*
G01Y1562573D01*
G03X683198Y1562441I200J0D01*
G02Y1559529I-1664J-1456D01*
G03X683148Y1559397I150J-132D01*
G01Y1558775D01*
G02X682945Y1558572I-203J0D01*
G01X680125D01*
G02X679922Y1558775I0J203D01*
G01Y1559397D01*
G03X679872Y1559529I-200J0D01*
G02Y1562441I1664J1456D01*
G03X679922Y1562573I-150J132D01*
G01Y1564515D01*
G03X679872Y1564647I-200J0D01*
G02Y1567559I1664J1456D01*
G03X679922Y1567691I-150J132D01*
G01Y1568313D01*
G02X680125Y1568516I203J0D01*
G37*
G36*
G01X1130440D02*
X1133260D01*
G02X1133462Y1568313I-1J-203D01*
G01Y1567693D01*
G03X1133512Y1567561I200J0D01*
G02Y1564645I-1661J-1458D01*
G03X1133462Y1564513I150J-132D01*
G01Y1562575D01*
G03X1133512Y1562443I200J0D01*
G02Y1559527I-1661J-1458D01*
G03X1133462Y1559395I150J-132D01*
G01Y1558775D01*
G02X1133260Y1558572I-202J-1D01*
G01X1130440D01*
G02X1130238Y1558775I1J203D01*
G01Y1559395D01*
G03X1130188Y1559527I-200J0D01*
G02Y1562443I1661J1458D01*
G03X1130238Y1562575I-150J132D01*
G01Y1564513D01*
G03X1130188Y1564645I-200J0D01*
G02Y1567561I1661J1458D01*
G03X1130238Y1567693I-150J132D01*
G01Y1568313D01*
G02X1130440Y1568516I202J1D01*
G37*
G36*
G01X1147763D02*
X1150583D01*
G02X1150786Y1568313I0J-203D01*
G01Y1567691D01*
G03X1150836Y1567559I200J0D01*
G02Y1564647I-1664J-1456D01*
G03X1150786Y1564515I150J-132D01*
G01Y1562573D01*
G03X1150836Y1562441I200J0D01*
G02Y1559529I-1664J-1456D01*
G03X1150786Y1559397I150J-132D01*
G01Y1558775D01*
G02X1150583Y1558572I-203J0D01*
G01X1147763D01*
G02X1147560Y1558775I0J203D01*
G01Y1559397D01*
G03X1147510Y1559529I-200J0D01*
G02Y1562441I1664J1456D01*
G03X1147560Y1562573I-150J132D01*
G01Y1564515D01*
G03X1147510Y1564647I-200J0D01*
G02Y1567559I1664J1456D01*
G03X1147560Y1567691I-150J132D01*
G01Y1568313D01*
G02X1147763Y1568516I203J0D01*
G37*
G36*
G01X1165086D02*
X1167906D01*
G02X1168108Y1568313I-1J-203D01*
G01Y1567693D01*
G03X1168158Y1567561I200J0D01*
G02Y1564645I-1661J-1458D01*
G03X1168108Y1564513I150J-132D01*
G01Y1562575D01*
G03X1168158Y1562443I200J0D01*
G02Y1559527I-1661J-1458D01*
G03X1168108Y1559395I150J-132D01*
G01Y1558775D01*
G02X1167906Y1558572I-202J-1D01*
G01X1165086D01*
G02X1164884Y1558775I1J203D01*
G01Y1559395D01*
G03X1164834Y1559527I-200J0D01*
G02Y1562443I1661J1458D01*
G03X1164884Y1562575I-150J132D01*
G01Y1564513D01*
G03X1164834Y1564645I-200J0D01*
G02Y1567561I1661J1458D01*
G03X1164884Y1567693I-150J132D01*
G01Y1568313D01*
G02X1165086Y1568516I202J1D01*
G37*
G36*
G01X1182408D02*
X1185228D01*
G02X1185430Y1568313I-1J-203D01*
G01Y1567693D01*
G03X1185480Y1567561I200J0D01*
G02Y1564645I-1661J-1458D01*
G03X1185430Y1564513I150J-132D01*
G01Y1562575D01*
G03X1185480Y1562443I200J0D01*
G02Y1559527I-1661J-1458D01*
G03X1185430Y1559395I150J-132D01*
G01Y1558775D01*
G02X1185228Y1558572I-202J-1D01*
G01X1182408D01*
G02X1182206Y1558775I1J203D01*
G01Y1559395D01*
G03X1182156Y1559527I-200J0D01*
G02Y1562443I1661J1458D01*
G03X1182206Y1562575I-150J132D01*
G01Y1564513D01*
G03X1182156Y1564645I-200J0D01*
G02Y1567561I1661J1458D01*
G03X1182206Y1567693I-150J132D01*
G01Y1568313D01*
G02X1182408Y1568516I202J1D01*
G37*
G36*
G01X1303669D02*
X1306489D01*
G02X1306692Y1568313I0J-203D01*
G01Y1567691D01*
G03X1306742Y1567559I200J0D01*
G02Y1564647I-1664J-1456D01*
G03X1306692Y1564515I150J-132D01*
G01Y1562573D01*
G03X1306742Y1562441I200J0D01*
G02Y1559529I-1664J-1456D01*
G03X1306692Y1559397I150J-132D01*
G01Y1558775D01*
G02X1306489Y1558572I-203J0D01*
G01X1303669D01*
G02X1303466Y1558775I0J203D01*
G01Y1559397D01*
G03X1303416Y1559529I-200J0D01*
G02Y1562441I1664J1456D01*
G03X1303466Y1562573I-150J132D01*
G01Y1564515D01*
G03X1303416Y1564647I-200J0D01*
G02Y1567559I1664J1456D01*
G03X1303466Y1567691I-150J132D01*
G01Y1568313D01*
G02X1303669Y1568516I203J0D01*
G37*
G36*
G01X1320992D02*
X1323812D01*
G02X1324014Y1568313I-1J-203D01*
G01Y1567693D01*
G03X1324064Y1567561I200J0D01*
G02Y1564645I-1661J-1458D01*
G03X1324014Y1564513I150J-132D01*
G01Y1562575D01*
G03X1324064Y1562443I200J0D01*
G02Y1559527I-1661J-1458D01*
G03X1324014Y1559395I150J-132D01*
G01Y1558775D01*
G02X1323812Y1558572I-202J-1D01*
G01X1320992D01*
G02X1320790Y1558775I1J203D01*
G01Y1559395D01*
G03X1320740Y1559527I-200J0D01*
G02Y1562443I1661J1458D01*
G03X1320790Y1562575I-150J132D01*
G01Y1564513D01*
G03X1320740Y1564645I-200J0D01*
G02Y1567561I1661J1458D01*
G03X1320790Y1567693I-150J132D01*
G01Y1568313D01*
G02X1320992Y1568516I202J1D01*
G37*
G36*
G01X1338315D02*
X1341135D01*
G02X1341338Y1568313I0J-203D01*
G01Y1567691D01*
G03X1341388Y1567559I200J0D01*
G02Y1564647I-1664J-1456D01*
G03X1341338Y1564515I150J-132D01*
G01Y1562573D01*
G03X1341388Y1562441I200J0D01*
G02Y1559529I-1664J-1456D01*
G03X1341338Y1559397I150J-132D01*
G01Y1558775D01*
G02X1341135Y1558572I-203J0D01*
G01X1338315D01*
G02X1338112Y1558775I0J203D01*
G01Y1559397D01*
G03X1338062Y1559529I-200J0D01*
G02Y1562441I1664J1456D01*
G03X1338112Y1562573I-150J132D01*
G01Y1564515D01*
G03X1338062Y1564647I-200J0D01*
G02Y1567559I1664J1456D01*
G03X1338112Y1567691I-150J132D01*
G01Y1568313D01*
G02X1338315Y1568516I203J0D01*
G37*
G36*
G01X1355637D02*
X1358457D01*
G02X1358660Y1568313I0J-203D01*
G01Y1567691D01*
G03X1358710Y1567559I200J0D01*
G02Y1564647I-1664J-1456D01*
G03X1358660Y1564515I150J-132D01*
G01Y1562573D01*
G03X1358710Y1562441I200J0D01*
G02Y1559529I-1664J-1456D01*
G03X1358660Y1559397I150J-132D01*
G01Y1558775D01*
G02X1358457Y1558572I-203J0D01*
G01X1355637D01*
G02X1355434Y1558775I0J203D01*
G01Y1559397D01*
G03X1355384Y1559529I-200J0D01*
G02Y1562441I1664J1456D01*
G03X1355434Y1562573I-150J132D01*
G01Y1564515D01*
G03X1355384Y1564647I-200J0D01*
G02Y1567559I1664J1456D01*
G03X1355434Y1567691I-150J132D01*
G01Y1568313D01*
G02X1355637Y1568516I203J0D01*
G37*
G36*
G01X1476897D02*
X1479717D01*
G02X1479920Y1568313I0J-203D01*
G01Y1567691D01*
G03X1479970Y1567559I200J0D01*
G02Y1564647I-1664J-1456D01*
G03X1479920Y1564515I150J-132D01*
G01Y1562573D01*
G03X1479970Y1562441I200J0D01*
G02Y1559529I-1664J-1456D01*
G03X1479920Y1559397I150J-132D01*
G01Y1558775D01*
G02X1479717Y1558572I-203J0D01*
G01X1476897D01*
G02X1476694Y1558775I0J203D01*
G01Y1559397D01*
G03X1476644Y1559529I-200J0D01*
G02Y1562441I1664J1456D01*
G03X1476694Y1562573I-150J132D01*
G01Y1564515D01*
G03X1476644Y1564647I-200J0D01*
G02Y1567559I1664J1456D01*
G03X1476694Y1567691I-150J132D01*
G01Y1568313D01*
G02X1476897Y1568516I203J0D01*
G37*
G36*
G01X1650125D02*
X1652945D01*
G02X1653148Y1568313I0J-203D01*
G01Y1567691D01*
G03X1653198Y1567559I200J0D01*
G02Y1564647I-1664J-1456D01*
G03X1653148Y1564515I150J-132D01*
G01Y1562573D01*
G03X1653198Y1562441I200J0D01*
G02Y1559529I-1664J-1456D01*
G03X1653148Y1559397I150J-132D01*
G01Y1558775D01*
G02X1652945Y1558572I-203J0D01*
G01X1650125D01*
G02X1649922Y1558775I0J203D01*
G01Y1559397D01*
G03X1649872Y1559529I-200J0D01*
G02Y1562441I1664J1456D01*
G03X1649922Y1562573I-150J132D01*
G01Y1564515D01*
G03X1649872Y1564647I-200J0D01*
G02Y1567559I1664J1456D01*
G03X1649922Y1567691I-150J132D01*
G01Y1568313D01*
G02X1650125Y1568516I203J0D01*
G37*
G36*
G01X1667448D02*
X1670268D01*
G02X1670470Y1568313I-1J-203D01*
G01Y1567693D01*
G03X1670520Y1567561I200J0D01*
G02Y1564645I-1661J-1458D01*
G03X1670470Y1564513I150J-132D01*
G01Y1562575D01*
G03X1670520Y1562443I200J0D01*
G02Y1559527I-1661J-1458D01*
G03X1670470Y1559395I150J-132D01*
G01Y1558775D01*
G02X1670268Y1558572I-202J-1D01*
G01X1667448D01*
G02X1667246Y1558775I1J203D01*
G01Y1559395D01*
G03X1667196Y1559527I-200J0D01*
G02Y1562443I1661J1458D01*
G03X1667246Y1562575I-150J132D01*
G01Y1564513D01*
G03X1667196Y1564645I-200J0D01*
G02Y1567561I1661J1458D01*
G03X1667246Y1567693I-150J132D01*
G01Y1568313D01*
G02X1667448Y1568516I202J1D01*
G37*
G36*
G01X1684771D02*
X1687591D01*
G02X1687794Y1568313I0J-203D01*
G01Y1567691D01*
G03X1687844Y1567559I200J0D01*
G02Y1564647I-1664J-1456D01*
G03X1687794Y1564515I150J-132D01*
G01Y1562573D01*
G03X1687844Y1562441I200J0D01*
G02Y1559529I-1664J-1456D01*
G03X1687794Y1559397I150J-132D01*
G01Y1558775D01*
G02X1687591Y1558572I-203J0D01*
G01X1684771D01*
G02X1684568Y1558775I0J203D01*
G01Y1559397D01*
G03X1684518Y1559529I-200J0D01*
G02Y1562441I1664J1456D01*
G03X1684568Y1562573I-150J132D01*
G01Y1564515D01*
G03X1684518Y1564647I-200J0D01*
G02Y1567559I1664J1456D01*
G03X1684568Y1567691I-150J132D01*
G01Y1568313D01*
G02X1684771Y1568516I203J0D01*
G37*
G36*
G01X1702093D02*
X1704913D01*
G02X1705116Y1568313I0J-203D01*
G01Y1567691D01*
G03X1705166Y1567559I200J0D01*
G02Y1564647I-1664J-1456D01*
G03X1705116Y1564515I150J-132D01*
G01Y1562573D01*
G03X1705166Y1562441I200J0D01*
G02Y1559529I-1664J-1456D01*
G03X1705116Y1559397I150J-132D01*
G01Y1558775D01*
G02X1704913Y1558572I-203J0D01*
G01X1702093D01*
G02X1701890Y1558775I0J203D01*
G01Y1559397D01*
G03X1701840Y1559529I-200J0D01*
G02Y1562441I1664J1456D01*
G03X1701890Y1562573I-150J132D01*
G01Y1564515D01*
G03X1701840Y1564647I-200J0D01*
G02Y1567559I1664J1456D01*
G03X1701890Y1567691I-150J132D01*
G01Y1568313D01*
G02X1702093Y1568516I203J0D01*
G37*
G36*
G01X134456Y1572846D02*
X137276D01*
G02X137478Y1572644I0J-202D01*
G01Y1572024D01*
G03X137528Y1571892I200J0D01*
G02Y1568976I-1661J-1458D01*
G03X137478Y1568844I150J-132D01*
G01Y1566905D01*
G03X137528Y1566773I200J0D01*
G02Y1563857I-1661J-1458D01*
G03X137478Y1563725I150J-132D01*
G01Y1563106D01*
G02X137276Y1562904I-202J0D01*
G01X134456D01*
G02X134254Y1563106I0J202D01*
G01Y1563725D01*
G03X134204Y1563857I-200J0D01*
G02Y1566773I1661J1458D01*
G03X134254Y1566905I-150J132D01*
G01Y1568844D01*
G03X134204Y1568976I-200J0D01*
G02Y1571892I1661J1458D01*
G03X134254Y1572024I-150J132D01*
G01Y1572644D01*
G02X134456Y1572846I202J0D01*
G37*
G36*
G01X169102D02*
X171922D01*
G02X172124Y1572644I0J-202D01*
G01Y1572024D01*
G03X172174Y1571892I200J0D01*
G02Y1568976I-1661J-1458D01*
G03X172124Y1568844I150J-132D01*
G01Y1566905D01*
G03X172174Y1566773I200J0D01*
G02Y1563857I-1661J-1458D01*
G03X172124Y1563725I150J-132D01*
G01Y1563106D01*
G02X171922Y1562904I-202J0D01*
G01X169102D01*
G02X168900Y1563106I0J202D01*
G01Y1563725D01*
G03X168850Y1563857I-200J0D01*
G02Y1566773I1661J1458D01*
G03X168900Y1566905I-150J132D01*
G01Y1568844D01*
G03X168850Y1568976I-200J0D01*
G02Y1571892I1661J1458D01*
G03X168900Y1572024I-150J132D01*
G01Y1572644D01*
G02X169102Y1572846I202J0D01*
G37*
G36*
G01X307684D02*
X310504D01*
G02X310706Y1572644I0J-202D01*
G01Y1572024D01*
G03X310756Y1571892I200J0D01*
G02Y1568976I-1661J-1458D01*
G03X310706Y1568844I150J-132D01*
G01Y1566905D01*
G03X310756Y1566773I200J0D01*
G02Y1563857I-1661J-1458D01*
G03X310706Y1563725I150J-132D01*
G01Y1563106D01*
G02X310504Y1562904I-202J0D01*
G01X307684D01*
G02X307482Y1563106I0J202D01*
G01Y1563725D01*
G03X307432Y1563857I-200J0D01*
G02Y1566773I1661J1458D01*
G03X307482Y1566905I-150J132D01*
G01Y1568844D01*
G03X307432Y1568976I-200J0D01*
G02Y1571892I1661J1458D01*
G03X307482Y1572024I-150J132D01*
G01Y1572644D01*
G02X307684Y1572846I202J0D01*
G37*
G36*
G01X342330D02*
X345150D01*
G02X345352Y1572644I0J-202D01*
G01Y1572024D01*
G03X345402Y1571892I200J0D01*
G02Y1568976I-1661J-1458D01*
G03X345352Y1568844I150J-132D01*
G01Y1566905D01*
G03X345402Y1566773I200J0D01*
G02Y1563857I-1661J-1458D01*
G03X345352Y1563725I150J-132D01*
G01Y1563106D01*
G02X345150Y1562904I-202J0D01*
G01X342330D01*
G02X342128Y1563106I0J202D01*
G01Y1563725D01*
G03X342078Y1563857I-200J0D01*
G02Y1566773I1661J1458D01*
G03X342128Y1566905I-150J132D01*
G01Y1568844D01*
G03X342078Y1568976I-200J0D01*
G02Y1571892I1661J1458D01*
G03X342128Y1572024I-150J132D01*
G01Y1572644D01*
G02X342330Y1572846I202J0D01*
G37*
G36*
G01X636818D02*
X639638D01*
G02X639840Y1572644I0J-202D01*
G01Y1572024D01*
G03X639890Y1571892I200J0D01*
G02Y1568976I-1661J-1458D01*
G03X639840Y1568844I150J-132D01*
G01Y1566905D01*
G03X639890Y1566773I200J0D01*
G02Y1563857I-1661J-1458D01*
G03X639840Y1563725I150J-132D01*
G01Y1563106D01*
G02X639638Y1562904I-202J0D01*
G01X636818D01*
G02X636616Y1563106I0J202D01*
G01Y1563725D01*
G03X636566Y1563857I-200J0D01*
G02Y1566773I1661J1458D01*
G03X636616Y1566905I-150J132D01*
G01Y1568844D01*
G03X636566Y1568976I-200J0D01*
G02Y1571892I1661J1458D01*
G03X636616Y1572024I-150J132D01*
G01Y1572644D01*
G02X636818Y1572846I202J0D01*
G37*
G36*
G01X671464D02*
X674284D01*
G02X674486Y1572644I0J-202D01*
G01Y1572024D01*
G03X674536Y1571892I200J0D01*
G02Y1568976I-1661J-1458D01*
G03X674486Y1568844I150J-132D01*
G01Y1566905D01*
G03X674536Y1566773I200J0D01*
G02Y1563857I-1661J-1458D01*
G03X674486Y1563725I150J-132D01*
G01Y1563106D01*
G02X674284Y1562904I-202J0D01*
G01X671464D01*
G02X671262Y1563106I0J202D01*
G01Y1563725D01*
G03X671212Y1563857I-200J0D01*
G02Y1566773I1661J1458D01*
G03X671262Y1566905I-150J132D01*
G01Y1568844D01*
G03X671212Y1568976I-200J0D01*
G02Y1571892I1661J1458D01*
G03X671262Y1572024I-150J132D01*
G01Y1572644D01*
G02X671464Y1572846I202J0D01*
G37*
G36*
G01X1156424D02*
X1159244D01*
G02X1159446Y1572644I0J-202D01*
G01Y1572024D01*
G03X1159496Y1571892I200J0D01*
G02Y1568976I-1661J-1458D01*
G03X1159446Y1568844I150J-132D01*
G01Y1566905D01*
G03X1159496Y1566773I200J0D01*
G02Y1563857I-1661J-1458D01*
G03X1159446Y1563725I150J-132D01*
G01Y1563106D01*
G02X1159244Y1562904I-202J0D01*
G01X1156424D01*
G02X1156222Y1563106I0J202D01*
G01Y1563725D01*
G03X1156172Y1563857I-200J0D01*
G02Y1566773I1661J1458D01*
G03X1156222Y1566905I-150J132D01*
G01Y1568844D01*
G03X1156172Y1568976I-200J0D01*
G02Y1571892I1661J1458D01*
G03X1156222Y1572024I-150J132D01*
G01Y1572644D01*
G02X1156424Y1572846I202J0D01*
G37*
G36*
G01X1191070D02*
X1193890D01*
G02X1194092Y1572644I0J-202D01*
G01Y1572024D01*
G03X1194142Y1571892I200J0D01*
G02Y1568976I-1661J-1458D01*
G03X1194092Y1568844I150J-132D01*
G01Y1566905D01*
G03X1194142Y1566773I200J0D01*
G02Y1563857I-1661J-1458D01*
G03X1194092Y1563725I150J-132D01*
G01Y1563106D01*
G02X1193890Y1562904I-202J0D01*
G01X1191070D01*
G02X1190868Y1563106I0J202D01*
G01Y1563725D01*
G03X1190818Y1563857I-200J0D01*
G02Y1566773I1661J1458D01*
G03X1190868Y1566905I-150J132D01*
G01Y1568844D01*
G03X1190818Y1568976I-200J0D01*
G02Y1571892I1661J1458D01*
G03X1190868Y1572024I-150J132D01*
G01Y1572644D01*
G02X1191070Y1572846I202J0D01*
G37*
G36*
G01X1312330D02*
X1315150D01*
G02X1315352Y1572644I0J-202D01*
G01Y1572024D01*
G03X1315402Y1571892I200J0D01*
G02Y1568976I-1661J-1458D01*
G03X1315352Y1568844I150J-132D01*
G01Y1566905D01*
G03X1315402Y1566773I200J0D01*
G02Y1563857I-1661J-1458D01*
G03X1315352Y1563725I150J-132D01*
G01Y1563106D01*
G02X1315150Y1562904I-202J0D01*
G01X1312330D01*
G02X1312128Y1563106I0J202D01*
G01Y1563725D01*
G03X1312078Y1563857I-200J0D01*
G02Y1566773I1661J1458D01*
G03X1312128Y1566905I-150J132D01*
G01Y1568844D01*
G03X1312078Y1568976I-200J0D01*
G02Y1571892I1661J1458D01*
G03X1312128Y1572024I-150J132D01*
G01Y1572644D01*
G02X1312330Y1572846I202J0D01*
G37*
G36*
G01X1346976D02*
X1349796D01*
G02X1349998Y1572644I0J-202D01*
G01Y1572024D01*
G03X1350048Y1571892I200J0D01*
G02Y1568976I-1661J-1458D01*
G03X1349998Y1568844I150J-132D01*
G01Y1566905D01*
G03X1350048Y1566773I200J0D01*
G02Y1563857I-1661J-1458D01*
G03X1349998Y1563725I150J-132D01*
G01Y1563106D01*
G02X1349796Y1562904I-202J0D01*
G01X1346976D01*
G02X1346774Y1563106I0J202D01*
G01Y1563725D01*
G03X1346724Y1563857I-200J0D01*
G02Y1566773I1661J1458D01*
G03X1346774Y1566905I-150J132D01*
G01Y1568844D01*
G03X1346724Y1568976I-200J0D01*
G02Y1571892I1661J1458D01*
G03X1346774Y1572024I-150J132D01*
G01Y1572644D01*
G02X1346976Y1572846I202J0D01*
G37*
G36*
G01X1658786D02*
X1661606D01*
G02X1661808Y1572644I0J-202D01*
G01Y1572024D01*
G03X1661858Y1571892I200J0D01*
G02Y1568976I-1661J-1458D01*
G03X1661808Y1568844I150J-132D01*
G01Y1566905D01*
G03X1661858Y1566773I200J0D01*
G02Y1563857I-1661J-1458D01*
G03X1661808Y1563725I150J-132D01*
G01Y1563106D01*
G02X1661606Y1562904I-202J0D01*
G01X1658786D01*
G02X1658584Y1563106I0J202D01*
G01Y1563725D01*
G03X1658534Y1563857I-200J0D01*
G02Y1566773I1661J1458D01*
G03X1658584Y1566905I-150J132D01*
G01Y1568844D01*
G03X1658534Y1568976I-200J0D01*
G02Y1571892I1661J1458D01*
G03X1658584Y1572024I-150J132D01*
G01Y1572644D01*
G02X1658786Y1572846I202J0D01*
G37*
G36*
G01X1693432D02*
X1696252D01*
G02X1696454Y1572644I0J-202D01*
G01Y1572024D01*
G03X1696504Y1571892I200J0D01*
G02Y1568976I-1661J-1458D01*
G03X1696454Y1568844I150J-132D01*
G01Y1566905D01*
G03X1696504Y1566773I200J0D01*
G02Y1563857I-1661J-1458D01*
G03X1696454Y1563725I150J-132D01*
G01Y1563106D01*
G02X1696252Y1562904I-202J0D01*
G01X1693432D01*
G02X1693230Y1563106I0J202D01*
G01Y1563725D01*
G03X1693180Y1563857I-200J0D01*
G02Y1566773I1661J1458D01*
G03X1693230Y1566905I-150J132D01*
G01Y1568844D01*
G03X1693180Y1568976I-200J0D01*
G02Y1571892I1661J1458D01*
G03X1693230Y1572024I-150J132D01*
G01Y1572644D01*
G02X1693432Y1572846I202J0D01*
G37*
G36*
G01X117133D02*
X119953D01*
G02X120156Y1572644I1J-202D01*
G01Y1572022D01*
G03X120206Y1571890I200J0D01*
G02Y1568978I-1664J-1456D01*
G03X120156Y1568846I150J-132D01*
G01Y1566903D01*
G03X120206Y1566771I200J0D01*
G02Y1563859I-1664J-1456D01*
G03X120156Y1563727I150J-132D01*
G01Y1563106D01*
G02X119953Y1562904I-203J1D01*
G01X117133D01*
G02X116930Y1563106I-1J202D01*
G01Y1563727D01*
G03X116880Y1563859I-200J0D01*
G02Y1566771I1664J1456D01*
G03X116930Y1566903I-150J132D01*
G01Y1568846D01*
G03X116880Y1568978I-200J0D01*
G02Y1571890I1664J1456D01*
G03X116930Y1572022I-150J132D01*
G01Y1572644D01*
G02X117133Y1572846I203J-1D01*
G37*
G36*
G01X151779D02*
X154599D01*
G02X154802Y1572644I1J-202D01*
G01Y1572022D01*
G03X154852Y1571890I200J0D01*
G02Y1568978I-1664J-1456D01*
G03X154802Y1568846I150J-132D01*
G01Y1566903D01*
G03X154852Y1566771I200J0D01*
G02Y1563859I-1664J-1456D01*
G03X154802Y1563727I150J-132D01*
G01Y1563106D01*
G02X154599Y1562904I-203J1D01*
G01X151779D01*
G02X151576Y1563106I-1J202D01*
G01Y1563727D01*
G03X151526Y1563859I-200J0D01*
G02Y1566771I1664J1456D01*
G03X151576Y1566903I-150J132D01*
G01Y1568846D01*
G03X151526Y1568978I-200J0D01*
G02Y1571890I1664J1456D01*
G03X151576Y1572022I-150J132D01*
G01Y1572644D01*
G02X151779Y1572846I203J-1D01*
G37*
G36*
G01X290361D02*
X293181D01*
G02X293384Y1572644I1J-202D01*
G01Y1572022D01*
G03X293434Y1571890I200J0D01*
G02Y1568978I-1664J-1456D01*
G03X293384Y1568846I150J-132D01*
G01Y1566903D01*
G03X293434Y1566771I200J0D01*
G02Y1563859I-1664J-1456D01*
G03X293384Y1563727I150J-132D01*
G01Y1563106D01*
G02X293181Y1562904I-203J1D01*
G01X290361D01*
G02X290158Y1563106I-1J202D01*
G01Y1563727D01*
G03X290108Y1563859I-200J0D01*
G02Y1566771I1664J1456D01*
G03X290158Y1566903I-150J132D01*
G01Y1568846D01*
G03X290108Y1568978I-200J0D01*
G02Y1571890I1664J1456D01*
G03X290158Y1572022I-150J132D01*
G01Y1572644D01*
G02X290361Y1572846I203J-1D01*
G37*
G36*
G01X325007D02*
X327827D01*
G02X328030Y1572644I1J-202D01*
G01Y1572022D01*
G03X328080Y1571890I200J0D01*
G02Y1568978I-1664J-1456D01*
G03X328030Y1568846I150J-132D01*
G01Y1566903D01*
G03X328080Y1566771I200J0D01*
G02Y1563859I-1664J-1456D01*
G03X328030Y1563727I150J-132D01*
G01Y1563106D01*
G02X327827Y1562904I-203J1D01*
G01X325007D01*
G02X324804Y1563106I-1J202D01*
G01Y1563727D01*
G03X324754Y1563859I-200J0D01*
G02Y1566771I1664J1456D01*
G03X324804Y1566903I-150J132D01*
G01Y1568846D01*
G03X324754Y1568978I-200J0D01*
G02Y1571890I1664J1456D01*
G03X324804Y1572022I-150J132D01*
G01Y1572644D01*
G02X325007Y1572846I203J-1D01*
G37*
G36*
G01X515559D02*
X518379D01*
G02X518582Y1572644I1J-202D01*
G01Y1572022D01*
G03X518632Y1571890I200J0D01*
G02Y1568978I-1664J-1456D01*
G03X518582Y1568846I150J-132D01*
G01Y1566903D01*
G03X518632Y1566771I200J0D01*
G02Y1563859I-1664J-1456D01*
G03X518582Y1563727I150J-132D01*
G01Y1563106D01*
G02X518379Y1562904I-203J1D01*
G01X515559D01*
G02X515356Y1563106I-1J202D01*
G01Y1563727D01*
G03X515306Y1563859I-200J0D01*
G02Y1566771I1664J1456D01*
G03X515356Y1566903I-150J132D01*
G01Y1568846D01*
G03X515306Y1568978I-200J0D01*
G02Y1571890I1664J1456D01*
G03X515356Y1572022I-150J132D01*
G01Y1572644D01*
G02X515559Y1572846I203J-1D01*
G37*
G36*
G01X654141D02*
X656961D01*
G02X657164Y1572644I1J-202D01*
G01Y1572022D01*
G03X657214Y1571890I200J0D01*
G02Y1568978I-1664J-1456D01*
G03X657164Y1568846I150J-132D01*
G01Y1566903D01*
G03X657214Y1566771I200J0D01*
G02Y1563859I-1664J-1456D01*
G03X657164Y1563727I150J-132D01*
G01Y1563106D01*
G02X656961Y1562904I-203J1D01*
G01X654141D01*
G02X653938Y1563106I-1J202D01*
G01Y1563727D01*
G03X653888Y1563859I-200J0D01*
G02Y1566771I1664J1456D01*
G03X653938Y1566903I-150J132D01*
G01Y1568846D01*
G03X653888Y1568978I-200J0D01*
G02Y1571890I1664J1456D01*
G03X653938Y1572022I-150J132D01*
G01Y1572644D01*
G02X654141Y1572846I203J-1D01*
G37*
G36*
G01X688787D02*
X691607D01*
G02X691810Y1572644I1J-202D01*
G01Y1572022D01*
G03X691860Y1571890I200J0D01*
G02Y1568978I-1664J-1456D01*
G03X691810Y1568846I150J-132D01*
G01Y1566903D01*
G03X691860Y1566771I200J0D01*
G02Y1563859I-1664J-1456D01*
G03X691810Y1563727I150J-132D01*
G01Y1563106D01*
G02X691607Y1562904I-203J1D01*
G01X688787D01*
G02X688584Y1563106I-1J202D01*
G01Y1563727D01*
G03X688534Y1563859I-200J0D01*
G02Y1566771I1664J1456D01*
G03X688584Y1566903I-150J132D01*
G01Y1568846D01*
G03X688534Y1568978I-200J0D01*
G02Y1571890I1664J1456D01*
G03X688584Y1572022I-150J132D01*
G01Y1572644D01*
G02X688787Y1572846I203J-1D01*
G37*
G36*
G01X1139101D02*
X1141921D01*
G02X1142124Y1572644I1J-202D01*
G01Y1572022D01*
G03X1142174Y1571890I200J0D01*
G02Y1568978I-1664J-1456D01*
G03X1142124Y1568846I150J-132D01*
G01Y1566903D01*
G03X1142174Y1566771I200J0D01*
G02Y1563859I-1664J-1456D01*
G03X1142124Y1563727I150J-132D01*
G01Y1563106D01*
G02X1141921Y1562904I-203J1D01*
G01X1139101D01*
G02X1138898Y1563106I-1J202D01*
G01Y1563727D01*
G03X1138848Y1563859I-200J0D01*
G02Y1566771I1664J1456D01*
G03X1138898Y1566903I-150J132D01*
G01Y1568846D01*
G03X1138848Y1568978I-200J0D01*
G02Y1571890I1664J1456D01*
G03X1138898Y1572022I-150J132D01*
G01Y1572644D01*
G02X1139101Y1572846I203J-1D01*
G37*
G36*
G01X1173747D02*
X1176567D01*
G02X1176770Y1572644I1J-202D01*
G01Y1572022D01*
G03X1176820Y1571890I200J0D01*
G02Y1568978I-1664J-1456D01*
G03X1176770Y1568846I150J-132D01*
G01Y1566903D01*
G03X1176820Y1566771I200J0D01*
G02Y1563859I-1664J-1456D01*
G03X1176770Y1563727I150J-132D01*
G01Y1563106D01*
G02X1176567Y1562904I-203J1D01*
G01X1173747D01*
G02X1173544Y1563106I-1J202D01*
G01Y1563727D01*
G03X1173494Y1563859I-200J0D01*
G02Y1566771I1664J1456D01*
G03X1173544Y1566903I-150J132D01*
G01Y1568846D01*
G03X1173494Y1568978I-200J0D01*
G02Y1571890I1664J1456D01*
G03X1173544Y1572022I-150J132D01*
G01Y1572644D01*
G02X1173747Y1572846I203J-1D01*
G37*
G36*
G01X1329653D02*
X1332473D01*
G02X1332676Y1572644I1J-202D01*
G01Y1572022D01*
G03X1332726Y1571890I200J0D01*
G02Y1568978I-1664J-1456D01*
G03X1332676Y1568846I150J-132D01*
G01Y1566903D01*
G03X1332726Y1566771I200J0D01*
G02Y1563859I-1664J-1456D01*
G03X1332676Y1563727I150J-132D01*
G01Y1563106D01*
G02X1332473Y1562904I-203J1D01*
G01X1329653D01*
G02X1329450Y1563106I-1J202D01*
G01Y1563727D01*
G03X1329400Y1563859I-200J0D01*
G02Y1566771I1664J1456D01*
G03X1329450Y1566903I-150J132D01*
G01Y1568846D01*
G03X1329400Y1568978I-200J0D01*
G02Y1571890I1664J1456D01*
G03X1329450Y1572022I-150J132D01*
G01Y1572644D01*
G02X1329653Y1572846I203J-1D01*
G37*
G36*
G01X1364299D02*
X1367119D01*
G02X1367322Y1572644I1J-202D01*
G01Y1572022D01*
G03X1367372Y1571890I200J0D01*
G02Y1568978I-1664J-1456D01*
G03X1367322Y1568846I150J-132D01*
G01Y1566903D01*
G03X1367372Y1566771I200J0D01*
G02Y1563859I-1664J-1456D01*
G03X1367322Y1563727I150J-132D01*
G01Y1563106D01*
G02X1367119Y1562904I-203J1D01*
G01X1364299D01*
G02X1364096Y1563106I-1J202D01*
G01Y1563727D01*
G03X1364046Y1563859I-200J0D01*
G02Y1566771I1664J1456D01*
G03X1364096Y1566903I-150J132D01*
G01Y1568846D01*
G03X1364046Y1568978I-200J0D01*
G02Y1571890I1664J1456D01*
G03X1364096Y1572022I-150J132D01*
G01Y1572644D01*
G02X1364299Y1572846I203J-1D01*
G37*
G36*
G01X1676109D02*
X1678929D01*
G02X1679132Y1572644I1J-202D01*
G01Y1572022D01*
G03X1679182Y1571890I200J0D01*
G02Y1568978I-1664J-1456D01*
G03X1679132Y1568846I150J-132D01*
G01Y1566903D01*
G03X1679182Y1566771I200J0D01*
G02Y1563859I-1664J-1456D01*
G03X1679132Y1563727I150J-132D01*
G01Y1563106D01*
G02X1678929Y1562904I-203J1D01*
G01X1676109D01*
G02X1675906Y1563106I-1J202D01*
G01Y1563727D01*
G03X1675856Y1563859I-200J0D01*
G02Y1566771I1664J1456D01*
G03X1675906Y1566903I-150J132D01*
G01Y1568846D01*
G03X1675856Y1568978I-200J0D01*
G02Y1571890I1664J1456D01*
G03X1675906Y1572022I-150J132D01*
G01Y1572644D01*
G02X1676109Y1572846I203J-1D01*
G37*
G36*
G01X1710755D02*
X1713575D01*
G02X1713778Y1572644I1J-202D01*
G01Y1572022D01*
G03X1713828Y1571890I200J0D01*
G02Y1568978I-1664J-1456D01*
G03X1713778Y1568846I150J-132D01*
G01Y1566903D01*
G03X1713828Y1566771I200J0D01*
G02Y1563859I-1664J-1456D01*
G03X1713778Y1563727I150J-132D01*
G01Y1563106D01*
G02X1713575Y1562904I-203J1D01*
G01X1710755D01*
G02X1710552Y1563106I-1J202D01*
G01Y1563727D01*
G03X1710502Y1563859I-200J0D01*
G02Y1566771I1664J1456D01*
G03X1710552Y1566903I-150J132D01*
G01Y1568846D01*
G03X1710502Y1568978I-200J0D01*
G02Y1571890I1664J1456D01*
G03X1710552Y1572022I-150J132D01*
G01Y1572644D01*
G02X1710755Y1572846I203J-1D01*
G37*
G36*
G01X108472Y1583870D02*
X111292D01*
G02X111494Y1583667I-1J-203D01*
G01Y1583047D01*
G03X111544Y1582915I200J0D01*
G02Y1579999I-1661J-1458D01*
G03X111494Y1579867I150J-132D01*
G01Y1577929D01*
G03X111544Y1577797I200J0D01*
G02Y1574881I-1661J-1458D01*
G03X111494Y1574749I150J-132D01*
G01Y1574129D01*
G02X111292Y1573926I-202J-1D01*
G01X108472D01*
G02X108270Y1574129I1J203D01*
G01Y1574749D01*
G03X108220Y1574881I-200J0D01*
G02Y1577797I1661J1458D01*
G03X108270Y1577929I-150J132D01*
G01Y1579867D01*
G03X108220Y1579999I-200J0D01*
G02Y1582915I1661J1458D01*
G03X108270Y1583047I-150J132D01*
G01Y1583667D01*
G02X108472Y1583870I202J1D01*
G37*
G36*
G01X125795D02*
X128615D01*
G02X128818Y1583667I0J-203D01*
G01Y1583045D01*
G03X128868Y1582913I200J0D01*
G02Y1580001I-1664J-1456D01*
G03X128818Y1579869I150J-132D01*
G01Y1577927D01*
G03X128868Y1577795I200J0D01*
G02Y1574883I-1664J-1456D01*
G03X128818Y1574751I150J-132D01*
G01Y1574129D01*
G02X128615Y1573926I-203J0D01*
G01X125795D01*
G02X125592Y1574129I0J203D01*
G01Y1574751D01*
G03X125542Y1574883I-200J0D01*
G02Y1577795I1664J1456D01*
G03X125592Y1577927I-150J132D01*
G01Y1579869D01*
G03X125542Y1580001I-200J0D01*
G02Y1582913I1664J1456D01*
G03X125592Y1583045I-150J132D01*
G01Y1583667D01*
G02X125795Y1583870I203J0D01*
G37*
G36*
G01X143118D02*
X145938D01*
G02X146140Y1583667I-1J-203D01*
G01Y1583047D01*
G03X146190Y1582915I200J0D01*
G02Y1579999I-1661J-1458D01*
G03X146140Y1579867I150J-132D01*
G01Y1577929D01*
G03X146190Y1577797I200J0D01*
G02Y1574881I-1661J-1458D01*
G03X146140Y1574749I150J-132D01*
G01Y1574129D01*
G02X145938Y1573926I-202J-1D01*
G01X143118D01*
G02X142916Y1574129I1J203D01*
G01Y1574749D01*
G03X142866Y1574881I-200J0D01*
G02Y1577797I1661J1458D01*
G03X142916Y1577929I-150J132D01*
G01Y1579867D01*
G03X142866Y1579999I-200J0D01*
G02Y1582915I1661J1458D01*
G03X142916Y1583047I-150J132D01*
G01Y1583667D01*
G02X143118Y1583870I202J1D01*
G37*
G36*
G01X160440D02*
X163260D01*
G02X163462Y1583667I-1J-203D01*
G01Y1583047D01*
G03X163512Y1582915I200J0D01*
G02Y1579999I-1661J-1458D01*
G03X163462Y1579867I150J-132D01*
G01Y1577929D01*
G03X163512Y1577797I200J0D01*
G02Y1574881I-1661J-1458D01*
G03X163462Y1574749I150J-132D01*
G01Y1574129D01*
G02X163260Y1573926I-202J-1D01*
G01X160440D01*
G02X160238Y1574129I1J203D01*
G01Y1574749D01*
G03X160188Y1574881I-200J0D01*
G02Y1577797I1661J1458D01*
G03X160238Y1577929I-150J132D01*
G01Y1579867D01*
G03X160188Y1579999I-200J0D01*
G02Y1582915I1661J1458D01*
G03X160238Y1583047I-150J132D01*
G01Y1583667D01*
G02X160440Y1583870I202J1D01*
G37*
G36*
G01X281700D02*
X284520D01*
G02X284722Y1583667I-1J-203D01*
G01Y1583047D01*
G03X284772Y1582915I200J0D01*
G02Y1579999I-1661J-1458D01*
G03X284722Y1579867I150J-132D01*
G01Y1577929D01*
G03X284772Y1577797I200J0D01*
G02Y1574881I-1661J-1458D01*
G03X284722Y1574749I150J-132D01*
G01Y1574129D01*
G02X284520Y1573926I-202J-1D01*
G01X281700D01*
G02X281498Y1574129I1J203D01*
G01Y1574749D01*
G03X281448Y1574881I-200J0D01*
G02Y1577797I1661J1458D01*
G03X281498Y1577929I-150J132D01*
G01Y1579867D01*
G03X281448Y1579999I-200J0D01*
G02Y1582915I1661J1458D01*
G03X281498Y1583047I-150J132D01*
G01Y1583667D01*
G02X281700Y1583870I202J1D01*
G37*
G36*
G01X299023D02*
X301843D01*
G02X302046Y1583667I0J-203D01*
G01Y1583045D01*
G03X302096Y1582913I200J0D01*
G02Y1580001I-1664J-1456D01*
G03X302046Y1579869I150J-132D01*
G01Y1577927D01*
G03X302096Y1577795I200J0D01*
G02Y1574883I-1664J-1456D01*
G03X302046Y1574751I150J-132D01*
G01Y1574129D01*
G02X301843Y1573926I-203J0D01*
G01X299023D01*
G02X298820Y1574129I0J203D01*
G01Y1574751D01*
G03X298770Y1574883I-200J0D01*
G02Y1577795I1664J1456D01*
G03X298820Y1577927I-150J132D01*
G01Y1579869D01*
G03X298770Y1580001I-200J0D01*
G02Y1582913I1664J1456D01*
G03X298820Y1583045I-150J132D01*
G01Y1583667D01*
G02X299023Y1583870I203J0D01*
G37*
G36*
G01X316346D02*
X319166D01*
G02X319368Y1583667I-1J-203D01*
G01Y1583047D01*
G03X319418Y1582915I200J0D01*
G02Y1579999I-1661J-1458D01*
G03X319368Y1579867I150J-132D01*
G01Y1577929D01*
G03X319418Y1577797I200J0D01*
G02Y1574881I-1661J-1458D01*
G03X319368Y1574749I150J-132D01*
G01Y1574129D01*
G02X319166Y1573926I-202J-1D01*
G01X316346D01*
G02X316144Y1574129I1J203D01*
G01Y1574749D01*
G03X316094Y1574881I-200J0D01*
G02Y1577797I1661J1458D01*
G03X316144Y1577929I-150J132D01*
G01Y1579867D01*
G03X316094Y1579999I-200J0D01*
G02Y1582915I1661J1458D01*
G03X316144Y1583047I-150J132D01*
G01Y1583667D01*
G02X316346Y1583870I202J1D01*
G37*
G36*
G01X333668D02*
X336488D01*
G02X336690Y1583667I-1J-203D01*
G01Y1583047D01*
G03X336740Y1582915I200J0D01*
G02Y1579999I-1661J-1458D01*
G03X336690Y1579867I150J-132D01*
G01Y1577929D01*
G03X336740Y1577797I200J0D01*
G02Y1574881I-1661J-1458D01*
G03X336690Y1574749I150J-132D01*
G01Y1574129D01*
G02X336488Y1573926I-202J-1D01*
G01X333668D01*
G02X333466Y1574129I1J203D01*
G01Y1574749D01*
G03X333416Y1574881I-200J0D01*
G02Y1577797I1661J1458D01*
G03X333466Y1577929I-150J132D01*
G01Y1579867D01*
G03X333416Y1579999I-200J0D01*
G02Y1582915I1661J1458D01*
G03X333466Y1583047I-150J132D01*
G01Y1583667D01*
G02X333668Y1583870I202J1D01*
G37*
G36*
G01X628157D02*
X630977D01*
G02X631180Y1583667I0J-203D01*
G01Y1583045D01*
G03X631230Y1582913I200J0D01*
G02Y1580001I-1664J-1456D01*
G03X631180Y1579869I150J-132D01*
G01Y1577927D01*
G03X631230Y1577795I200J0D01*
G02Y1574883I-1664J-1456D01*
G03X631180Y1574751I150J-132D01*
G01Y1574129D01*
G02X630977Y1573926I-203J0D01*
G01X628157D01*
G02X627954Y1574129I0J203D01*
G01Y1574751D01*
G03X627904Y1574883I-200J0D01*
G02Y1577795I1664J1456D01*
G03X627954Y1577927I-150J132D01*
G01Y1579869D01*
G03X627904Y1580001I-200J0D01*
G02Y1582913I1664J1456D01*
G03X627954Y1583045I-150J132D01*
G01Y1583667D01*
G02X628157Y1583870I203J0D01*
G37*
G36*
G01X645480D02*
X648300D01*
G02X648502Y1583667I-1J-203D01*
G01Y1583047D01*
G03X648552Y1582915I200J0D01*
G02Y1579999I-1661J-1458D01*
G03X648502Y1579867I150J-132D01*
G01Y1577929D01*
G03X648552Y1577797I200J0D01*
G02Y1574881I-1661J-1458D01*
G03X648502Y1574749I150J-132D01*
G01Y1574129D01*
G02X648300Y1573926I-202J-1D01*
G01X645480D01*
G02X645278Y1574129I1J203D01*
G01Y1574749D01*
G03X645228Y1574881I-200J0D01*
G02Y1577797I1661J1458D01*
G03X645278Y1577929I-150J132D01*
G01Y1579867D01*
G03X645228Y1579999I-200J0D01*
G02Y1582915I1661J1458D01*
G03X645278Y1583047I-150J132D01*
G01Y1583667D01*
G02X645480Y1583870I202J1D01*
G37*
G36*
G01X662803D02*
X665623D01*
G02X665826Y1583667I0J-203D01*
G01Y1583045D01*
G03X665876Y1582913I200J0D01*
G02Y1580001I-1664J-1456D01*
G03X665826Y1579869I150J-132D01*
G01Y1577927D01*
G03X665876Y1577795I200J0D01*
G02Y1574883I-1664J-1456D01*
G03X665826Y1574751I150J-132D01*
G01Y1574129D01*
G02X665623Y1573926I-203J0D01*
G01X662803D01*
G02X662600Y1574129I0J203D01*
G01Y1574751D01*
G03X662550Y1574883I-200J0D01*
G02Y1577795I1664J1456D01*
G03X662600Y1577927I-150J132D01*
G01Y1579869D01*
G03X662550Y1580001I-200J0D01*
G02Y1582913I1664J1456D01*
G03X662600Y1583045I-150J132D01*
G01Y1583667D01*
G02X662803Y1583870I203J0D01*
G37*
G36*
G01X680125D02*
X682945D01*
G02X683148Y1583667I0J-203D01*
G01Y1583045D01*
G03X683198Y1582913I200J0D01*
G02Y1580001I-1664J-1456D01*
G03X683148Y1579869I150J-132D01*
G01Y1577927D01*
G03X683198Y1577795I200J0D01*
G02Y1574883I-1664J-1456D01*
G03X683148Y1574751I150J-132D01*
G01Y1574129D01*
G02X682945Y1573926I-203J0D01*
G01X680125D01*
G02X679922Y1574129I0J203D01*
G01Y1574751D01*
G03X679872Y1574883I-200J0D01*
G02Y1577795I1664J1456D01*
G03X679922Y1577927I-150J132D01*
G01Y1579869D01*
G03X679872Y1580001I-200J0D01*
G02Y1582913I1664J1456D01*
G03X679922Y1583045I-150J132D01*
G01Y1583667D01*
G02X680125Y1583870I203J0D01*
G37*
G36*
G01X1130440D02*
X1133260D01*
G02X1133462Y1583667I-1J-203D01*
G01Y1583047D01*
G03X1133512Y1582915I200J0D01*
G02Y1579999I-1661J-1458D01*
G03X1133462Y1579867I150J-132D01*
G01Y1577929D01*
G03X1133512Y1577797I200J0D01*
G02Y1574881I-1661J-1458D01*
G03X1133462Y1574749I150J-132D01*
G01Y1574129D01*
G02X1133260Y1573926I-202J-1D01*
G01X1130440D01*
G02X1130238Y1574129I1J203D01*
G01Y1574749D01*
G03X1130188Y1574881I-200J0D01*
G02Y1577797I1661J1458D01*
G03X1130238Y1577929I-150J132D01*
G01Y1579867D01*
G03X1130188Y1579999I-200J0D01*
G02Y1582915I1661J1458D01*
G03X1130238Y1583047I-150J132D01*
G01Y1583667D01*
G02X1130440Y1583870I202J1D01*
G37*
G36*
G01X1147763D02*
X1150583D01*
G02X1150786Y1583667I0J-203D01*
G01Y1583045D01*
G03X1150836Y1582913I200J0D01*
G02Y1580001I-1664J-1456D01*
G03X1150786Y1579869I150J-132D01*
G01Y1577927D01*
G03X1150836Y1577795I200J0D01*
G02Y1574883I-1664J-1456D01*
G03X1150786Y1574751I150J-132D01*
G01Y1574129D01*
G02X1150583Y1573926I-203J0D01*
G01X1147763D01*
G02X1147560Y1574129I0J203D01*
G01Y1574751D01*
G03X1147510Y1574883I-200J0D01*
G02Y1577795I1664J1456D01*
G03X1147560Y1577927I-150J132D01*
G01Y1579869D01*
G03X1147510Y1580001I-200J0D01*
G02Y1582913I1664J1456D01*
G03X1147560Y1583045I-150J132D01*
G01Y1583667D01*
G02X1147763Y1583870I203J0D01*
G37*
G36*
G01X1165086D02*
X1167906D01*
G02X1168108Y1583667I-1J-203D01*
G01Y1583047D01*
G03X1168158Y1582915I200J0D01*
G02Y1579999I-1661J-1458D01*
G03X1168108Y1579867I150J-132D01*
G01Y1577929D01*
G03X1168158Y1577797I200J0D01*
G02Y1574881I-1661J-1458D01*
G03X1168108Y1574749I150J-132D01*
G01Y1574129D01*
G02X1167906Y1573926I-202J-1D01*
G01X1165086D01*
G02X1164884Y1574129I1J203D01*
G01Y1574749D01*
G03X1164834Y1574881I-200J0D01*
G02Y1577797I1661J1458D01*
G03X1164884Y1577929I-150J132D01*
G01Y1579867D01*
G03X1164834Y1579999I-200J0D01*
G02Y1582915I1661J1458D01*
G03X1164884Y1583047I-150J132D01*
G01Y1583667D01*
G02X1165086Y1583870I202J1D01*
G37*
G36*
G01X1182408D02*
X1185228D01*
G02X1185430Y1583667I-1J-203D01*
G01Y1583047D01*
G03X1185480Y1582915I200J0D01*
G02Y1579999I-1661J-1458D01*
G03X1185430Y1579867I150J-132D01*
G01Y1577929D01*
G03X1185480Y1577797I200J0D01*
G02Y1574881I-1661J-1458D01*
G03X1185430Y1574749I150J-132D01*
G01Y1574129D01*
G02X1185228Y1573926I-202J-1D01*
G01X1182408D01*
G02X1182206Y1574129I1J203D01*
G01Y1574749D01*
G03X1182156Y1574881I-200J0D01*
G02Y1577797I1661J1458D01*
G03X1182206Y1577929I-150J132D01*
G01Y1579867D01*
G03X1182156Y1579999I-200J0D01*
G02Y1582915I1661J1458D01*
G03X1182206Y1583047I-150J132D01*
G01Y1583667D01*
G02X1182408Y1583870I202J1D01*
G37*
G36*
G01X1303669D02*
X1306489D01*
G02X1306692Y1583667I0J-203D01*
G01Y1583045D01*
G03X1306742Y1582913I200J0D01*
G02Y1580001I-1664J-1456D01*
G03X1306692Y1579869I150J-132D01*
G01Y1577927D01*
G03X1306742Y1577795I200J0D01*
G02Y1574883I-1664J-1456D01*
G03X1306692Y1574751I150J-132D01*
G01Y1574129D01*
G02X1306489Y1573926I-203J0D01*
G01X1303669D01*
G02X1303466Y1574129I0J203D01*
G01Y1574751D01*
G03X1303416Y1574883I-200J0D01*
G02Y1577795I1664J1456D01*
G03X1303466Y1577927I-150J132D01*
G01Y1579869D01*
G03X1303416Y1580001I-200J0D01*
G02Y1582913I1664J1456D01*
G03X1303466Y1583045I-150J132D01*
G01Y1583667D01*
G02X1303669Y1583870I203J0D01*
G37*
G36*
G01X1320992D02*
X1323812D01*
G02X1324014Y1583667I-1J-203D01*
G01Y1583047D01*
G03X1324064Y1582915I200J0D01*
G02Y1579999I-1661J-1458D01*
G03X1324014Y1579867I150J-132D01*
G01Y1577929D01*
G03X1324064Y1577797I200J0D01*
G02Y1574881I-1661J-1458D01*
G03X1324014Y1574749I150J-132D01*
G01Y1574129D01*
G02X1323812Y1573926I-202J-1D01*
G01X1320992D01*
G02X1320790Y1574129I1J203D01*
G01Y1574749D01*
G03X1320740Y1574881I-200J0D01*
G02Y1577797I1661J1458D01*
G03X1320790Y1577929I-150J132D01*
G01Y1579867D01*
G03X1320740Y1579999I-200J0D01*
G02Y1582915I1661J1458D01*
G03X1320790Y1583047I-150J132D01*
G01Y1583667D01*
G02X1320992Y1583870I202J1D01*
G37*
G36*
G01X1338315D02*
X1341135D01*
G02X1341338Y1583667I0J-203D01*
G01Y1583045D01*
G03X1341388Y1582913I200J0D01*
G02Y1580001I-1664J-1456D01*
G03X1341338Y1579869I150J-132D01*
G01Y1577927D01*
G03X1341388Y1577795I200J0D01*
G02Y1574883I-1664J-1456D01*
G03X1341338Y1574751I150J-132D01*
G01Y1574129D01*
G02X1341135Y1573926I-203J0D01*
G01X1338315D01*
G02X1338112Y1574129I0J203D01*
G01Y1574751D01*
G03X1338062Y1574883I-200J0D01*
G02Y1577795I1664J1456D01*
G03X1338112Y1577927I-150J132D01*
G01Y1579869D01*
G03X1338062Y1580001I-200J0D01*
G02Y1582913I1664J1456D01*
G03X1338112Y1583045I-150J132D01*
G01Y1583667D01*
G02X1338315Y1583870I203J0D01*
G37*
G36*
G01X1355637D02*
X1358457D01*
G02X1358660Y1583667I0J-203D01*
G01Y1583045D01*
G03X1358710Y1582913I200J0D01*
G02Y1580001I-1664J-1456D01*
G03X1358660Y1579869I150J-132D01*
G01Y1577927D01*
G03X1358710Y1577795I200J0D01*
G02Y1574883I-1664J-1456D01*
G03X1358660Y1574751I150J-132D01*
G01Y1574129D01*
G02X1358457Y1573926I-203J0D01*
G01X1355637D01*
G02X1355434Y1574129I0J203D01*
G01Y1574751D01*
G03X1355384Y1574883I-200J0D01*
G02Y1577795I1664J1456D01*
G03X1355434Y1577927I-150J132D01*
G01Y1579869D01*
G03X1355384Y1580001I-200J0D01*
G02Y1582913I1664J1456D01*
G03X1355434Y1583045I-150J132D01*
G01Y1583667D01*
G02X1355637Y1583870I203J0D01*
G37*
G36*
G01X1476897D02*
X1479717D01*
G02X1479920Y1583667I0J-203D01*
G01Y1583045D01*
G03X1479970Y1582913I200J0D01*
G02Y1580001I-1664J-1456D01*
G03X1479920Y1579869I150J-132D01*
G01Y1577927D01*
G03X1479970Y1577795I200J0D01*
G02Y1574883I-1664J-1456D01*
G03X1479920Y1574751I150J-132D01*
G01Y1574129D01*
G02X1479717Y1573926I-203J0D01*
G01X1476897D01*
G02X1476694Y1574129I0J203D01*
G01Y1574751D01*
G03X1476644Y1574883I-200J0D01*
G02Y1577795I1664J1456D01*
G03X1476694Y1577927I-150J132D01*
G01Y1579869D01*
G03X1476644Y1580001I-200J0D01*
G02Y1582913I1664J1456D01*
G03X1476694Y1583045I-150J132D01*
G01Y1583667D01*
G02X1476897Y1583870I203J0D01*
G37*
G36*
G01X1650125D02*
X1652945D01*
G02X1653148Y1583667I0J-203D01*
G01Y1583045D01*
G03X1653198Y1582913I200J0D01*
G02Y1580001I-1664J-1456D01*
G03X1653148Y1579869I150J-132D01*
G01Y1577927D01*
G03X1653198Y1577795I200J0D01*
G02Y1574883I-1664J-1456D01*
G03X1653148Y1574751I150J-132D01*
G01Y1574129D01*
G02X1652945Y1573926I-203J0D01*
G01X1650125D01*
G02X1649922Y1574129I0J203D01*
G01Y1574751D01*
G03X1649872Y1574883I-200J0D01*
G02Y1577795I1664J1456D01*
G03X1649922Y1577927I-150J132D01*
G01Y1579869D01*
G03X1649872Y1580001I-200J0D01*
G02Y1582913I1664J1456D01*
G03X1649922Y1583045I-150J132D01*
G01Y1583667D01*
G02X1650125Y1583870I203J0D01*
G37*
G36*
G01X1667448D02*
X1670268D01*
G02X1670470Y1583667I-1J-203D01*
G01Y1583047D01*
G03X1670520Y1582915I200J0D01*
G02Y1579999I-1661J-1458D01*
G03X1670470Y1579867I150J-132D01*
G01Y1577929D01*
G03X1670520Y1577797I200J0D01*
G02Y1574881I-1661J-1458D01*
G03X1670470Y1574749I150J-132D01*
G01Y1574129D01*
G02X1670268Y1573926I-202J-1D01*
G01X1667448D01*
G02X1667246Y1574129I1J203D01*
G01Y1574749D01*
G03X1667196Y1574881I-200J0D01*
G02Y1577797I1661J1458D01*
G03X1667246Y1577929I-150J132D01*
G01Y1579867D01*
G03X1667196Y1579999I-200J0D01*
G02Y1582915I1661J1458D01*
G03X1667246Y1583047I-150J132D01*
G01Y1583667D01*
G02X1667448Y1583870I202J1D01*
G37*
G36*
G01X1684771D02*
X1687591D01*
G02X1687794Y1583667I0J-203D01*
G01Y1583045D01*
G03X1687844Y1582913I200J0D01*
G02Y1580001I-1664J-1456D01*
G03X1687794Y1579869I150J-132D01*
G01Y1577927D01*
G03X1687844Y1577795I200J0D01*
G02Y1574883I-1664J-1456D01*
G03X1687794Y1574751I150J-132D01*
G01Y1574129D01*
G02X1687591Y1573926I-203J0D01*
G01X1684771D01*
G02X1684568Y1574129I0J203D01*
G01Y1574751D01*
G03X1684518Y1574883I-200J0D01*
G02Y1577795I1664J1456D01*
G03X1684568Y1577927I-150J132D01*
G01Y1579869D01*
G03X1684518Y1580001I-200J0D01*
G02Y1582913I1664J1456D01*
G03X1684568Y1583045I-150J132D01*
G01Y1583667D01*
G02X1684771Y1583870I203J0D01*
G37*
G36*
G01X1702093D02*
X1704913D01*
G02X1705116Y1583667I0J-203D01*
G01Y1583045D01*
G03X1705166Y1582913I200J0D01*
G02Y1580001I-1664J-1456D01*
G03X1705116Y1579869I150J-132D01*
G01Y1577927D01*
G03X1705166Y1577795I200J0D01*
G02Y1574883I-1664J-1456D01*
G03X1705116Y1574751I150J-132D01*
G01Y1574129D01*
G02X1704913Y1573926I-203J0D01*
G01X1702093D01*
G02X1701890Y1574129I0J203D01*
G01Y1574751D01*
G03X1701840Y1574883I-200J0D01*
G02Y1577795I1664J1456D01*
G03X1701890Y1577927I-150J132D01*
G01Y1579869D01*
G03X1701840Y1580001I-200J0D01*
G02Y1582913I1664J1456D01*
G03X1701890Y1583045I-150J132D01*
G01Y1583667D01*
G02X1702093Y1583870I203J0D01*
G37*
G36*
G01X134456Y1588200D02*
X137276D01*
G02X137478Y1587998I0J-202D01*
G01Y1587378D01*
G03X137528Y1587246I200J0D01*
G02Y1584330I-1661J-1458D01*
G03X137478Y1584198I150J-132D01*
G01Y1582260D01*
G03X137528Y1582128I200J0D01*
G02Y1579212I-1661J-1458D01*
G03X137478Y1579080I150J-132D01*
G01Y1578460D01*
G02X137276Y1578258I-202J0D01*
G01X134456D01*
G02X134254Y1578460I0J202D01*
G01Y1579080D01*
G03X134204Y1579212I-200J0D01*
G02Y1582128I1661J1458D01*
G03X134254Y1582260I-150J132D01*
G01Y1584198D01*
G03X134204Y1584330I-200J0D01*
G02Y1587246I1661J1458D01*
G03X134254Y1587378I-150J132D01*
G01Y1587998D01*
G02X134456Y1588200I202J0D01*
G37*
G36*
G01X169102D02*
X171922D01*
G02X172124Y1587998I0J-202D01*
G01Y1587378D01*
G03X172174Y1587246I200J0D01*
G02Y1584330I-1661J-1458D01*
G03X172124Y1584198I150J-132D01*
G01Y1582260D01*
G03X172174Y1582128I200J0D01*
G02Y1579212I-1661J-1458D01*
G03X172124Y1579080I150J-132D01*
G01Y1578460D01*
G02X171922Y1578258I-202J0D01*
G01X169102D01*
G02X168900Y1578460I0J202D01*
G01Y1579080D01*
G03X168850Y1579212I-200J0D01*
G02Y1582128I1661J1458D01*
G03X168900Y1582260I-150J132D01*
G01Y1584198D01*
G03X168850Y1584330I-200J0D01*
G02Y1587246I1661J1458D01*
G03X168900Y1587378I-150J132D01*
G01Y1587998D01*
G02X169102Y1588200I202J0D01*
G37*
G36*
G01X307684D02*
X310504D01*
G02X310706Y1587998I0J-202D01*
G01Y1587378D01*
G03X310756Y1587246I200J0D01*
G02Y1584330I-1661J-1458D01*
G03X310706Y1584198I150J-132D01*
G01Y1582260D01*
G03X310756Y1582128I200J0D01*
G02Y1579212I-1661J-1458D01*
G03X310706Y1579080I150J-132D01*
G01Y1578460D01*
G02X310504Y1578258I-202J0D01*
G01X307684D01*
G02X307482Y1578460I0J202D01*
G01Y1579080D01*
G03X307432Y1579212I-200J0D01*
G02Y1582128I1661J1458D01*
G03X307482Y1582260I-150J132D01*
G01Y1584198D01*
G03X307432Y1584330I-200J0D01*
G02Y1587246I1661J1458D01*
G03X307482Y1587378I-150J132D01*
G01Y1587998D01*
G02X307684Y1588200I202J0D01*
G37*
G36*
G01X342330D02*
X345150D01*
G02X345352Y1587998I0J-202D01*
G01Y1587378D01*
G03X345402Y1587246I200J0D01*
G02Y1584330I-1661J-1458D01*
G03X345352Y1584198I150J-132D01*
G01Y1582260D01*
G03X345402Y1582128I200J0D01*
G02Y1579212I-1661J-1458D01*
G03X345352Y1579080I150J-132D01*
G01Y1578460D01*
G02X345150Y1578258I-202J0D01*
G01X342330D01*
G02X342128Y1578460I0J202D01*
G01Y1579080D01*
G03X342078Y1579212I-200J0D01*
G02Y1582128I1661J1458D01*
G03X342128Y1582260I-150J132D01*
G01Y1584198D01*
G03X342078Y1584330I-200J0D01*
G02Y1587246I1661J1458D01*
G03X342128Y1587378I-150J132D01*
G01Y1587998D01*
G02X342330Y1588200I202J0D01*
G37*
G36*
G01X636818D02*
X639638D01*
G02X639840Y1587998I0J-202D01*
G01Y1587378D01*
G03X639890Y1587246I200J0D01*
G02Y1584330I-1661J-1458D01*
G03X639840Y1584198I150J-132D01*
G01Y1582260D01*
G03X639890Y1582128I200J0D01*
G02Y1579212I-1661J-1458D01*
G03X639840Y1579080I150J-132D01*
G01Y1578460D01*
G02X639638Y1578258I-202J0D01*
G01X636818D01*
G02X636616Y1578460I0J202D01*
G01Y1579080D01*
G03X636566Y1579212I-200J0D01*
G02Y1582128I1661J1458D01*
G03X636616Y1582260I-150J132D01*
G01Y1584198D01*
G03X636566Y1584330I-200J0D01*
G02Y1587246I1661J1458D01*
G03X636616Y1587378I-150J132D01*
G01Y1587998D01*
G02X636818Y1588200I202J0D01*
G37*
G36*
G01X671464D02*
X674284D01*
G02X674486Y1587998I0J-202D01*
G01Y1587378D01*
G03X674536Y1587246I200J0D01*
G02Y1584330I-1661J-1458D01*
G03X674486Y1584198I150J-132D01*
G01Y1582260D01*
G03X674536Y1582128I200J0D01*
G02Y1579212I-1661J-1458D01*
G03X674486Y1579080I150J-132D01*
G01Y1578460D01*
G02X674284Y1578258I-202J0D01*
G01X671464D01*
G02X671262Y1578460I0J202D01*
G01Y1579080D01*
G03X671212Y1579212I-200J0D01*
G02Y1582128I1661J1458D01*
G03X671262Y1582260I-150J132D01*
G01Y1584198D01*
G03X671212Y1584330I-200J0D01*
G02Y1587246I1661J1458D01*
G03X671262Y1587378I-150J132D01*
G01Y1587998D01*
G02X671464Y1588200I202J0D01*
G37*
G36*
G01X1156424D02*
X1159244D01*
G02X1159446Y1587998I0J-202D01*
G01Y1587378D01*
G03X1159496Y1587246I200J0D01*
G02Y1584330I-1661J-1458D01*
G03X1159446Y1584198I150J-132D01*
G01Y1582260D01*
G03X1159496Y1582128I200J0D01*
G02Y1579212I-1661J-1458D01*
G03X1159446Y1579080I150J-132D01*
G01Y1578460D01*
G02X1159244Y1578258I-202J0D01*
G01X1156424D01*
G02X1156222Y1578460I0J202D01*
G01Y1579080D01*
G03X1156172Y1579212I-200J0D01*
G02Y1582128I1661J1458D01*
G03X1156222Y1582260I-150J132D01*
G01Y1584198D01*
G03X1156172Y1584330I-200J0D01*
G02Y1587246I1661J1458D01*
G03X1156222Y1587378I-150J132D01*
G01Y1587998D01*
G02X1156424Y1588200I202J0D01*
G37*
G36*
G01X1191070D02*
X1193890D01*
G02X1194092Y1587998I0J-202D01*
G01Y1587378D01*
G03X1194142Y1587246I200J0D01*
G02Y1584330I-1661J-1458D01*
G03X1194092Y1584198I150J-132D01*
G01Y1582260D01*
G03X1194142Y1582128I200J0D01*
G02Y1579212I-1661J-1458D01*
G03X1194092Y1579080I150J-132D01*
G01Y1578460D01*
G02X1193890Y1578258I-202J0D01*
G01X1191070D01*
G02X1190868Y1578460I0J202D01*
G01Y1579080D01*
G03X1190818Y1579212I-200J0D01*
G02Y1582128I1661J1458D01*
G03X1190868Y1582260I-150J132D01*
G01Y1584198D01*
G03X1190818Y1584330I-200J0D01*
G02Y1587246I1661J1458D01*
G03X1190868Y1587378I-150J132D01*
G01Y1587998D01*
G02X1191070Y1588200I202J0D01*
G37*
G36*
G01X1312330D02*
X1315150D01*
G02X1315352Y1587998I0J-202D01*
G01Y1587378D01*
G03X1315402Y1587246I200J0D01*
G02Y1584330I-1661J-1458D01*
G03X1315352Y1584198I150J-132D01*
G01Y1582260D01*
G03X1315402Y1582128I200J0D01*
G02Y1579212I-1661J-1458D01*
G03X1315352Y1579080I150J-132D01*
G01Y1578460D01*
G02X1315150Y1578258I-202J0D01*
G01X1312330D01*
G02X1312128Y1578460I0J202D01*
G01Y1579080D01*
G03X1312078Y1579212I-200J0D01*
G02Y1582128I1661J1458D01*
G03X1312128Y1582260I-150J132D01*
G01Y1584198D01*
G03X1312078Y1584330I-200J0D01*
G02Y1587246I1661J1458D01*
G03X1312128Y1587378I-150J132D01*
G01Y1587998D01*
G02X1312330Y1588200I202J0D01*
G37*
G36*
G01X1346976D02*
X1349796D01*
G02X1349998Y1587998I0J-202D01*
G01Y1587378D01*
G03X1350048Y1587246I200J0D01*
G02Y1584330I-1661J-1458D01*
G03X1349998Y1584198I150J-132D01*
G01Y1582260D01*
G03X1350048Y1582128I200J0D01*
G02Y1579212I-1661J-1458D01*
G03X1349998Y1579080I150J-132D01*
G01Y1578460D01*
G02X1349796Y1578258I-202J0D01*
G01X1346976D01*
G02X1346774Y1578460I0J202D01*
G01Y1579080D01*
G03X1346724Y1579212I-200J0D01*
G02Y1582128I1661J1458D01*
G03X1346774Y1582260I-150J132D01*
G01Y1584198D01*
G03X1346724Y1584330I-200J0D01*
G02Y1587246I1661J1458D01*
G03X1346774Y1587378I-150J132D01*
G01Y1587998D01*
G02X1346976Y1588200I202J0D01*
G37*
G36*
G01X1658786D02*
X1661606D01*
G02X1661808Y1587998I0J-202D01*
G01Y1587378D01*
G03X1661858Y1587246I200J0D01*
G02Y1584330I-1661J-1458D01*
G03X1661808Y1584198I150J-132D01*
G01Y1582260D01*
G03X1661858Y1582128I200J0D01*
G02Y1579212I-1661J-1458D01*
G03X1661808Y1579080I150J-132D01*
G01Y1578460D01*
G02X1661606Y1578258I-202J0D01*
G01X1658786D01*
G02X1658584Y1578460I0J202D01*
G01Y1579080D01*
G03X1658534Y1579212I-200J0D01*
G02Y1582128I1661J1458D01*
G03X1658584Y1582260I-150J132D01*
G01Y1584198D01*
G03X1658534Y1584330I-200J0D01*
G02Y1587246I1661J1458D01*
G03X1658584Y1587378I-150J132D01*
G01Y1587998D01*
G02X1658786Y1588200I202J0D01*
G37*
G36*
G01X1693432D02*
X1696252D01*
G02X1696454Y1587998I0J-202D01*
G01Y1587378D01*
G03X1696504Y1587246I200J0D01*
G02Y1584330I-1661J-1458D01*
G03X1696454Y1584198I150J-132D01*
G01Y1582260D01*
G03X1696504Y1582128I200J0D01*
G02Y1579212I-1661J-1458D01*
G03X1696454Y1579080I150J-132D01*
G01Y1578460D01*
G02X1696252Y1578258I-202J0D01*
G01X1693432D01*
G02X1693230Y1578460I0J202D01*
G01Y1579080D01*
G03X1693180Y1579212I-200J0D01*
G02Y1582128I1661J1458D01*
G03X1693230Y1582260I-150J132D01*
G01Y1584198D01*
G03X1693180Y1584330I-200J0D01*
G02Y1587246I1661J1458D01*
G03X1693230Y1587378I-150J132D01*
G01Y1587998D01*
G02X1693432Y1588200I202J0D01*
G37*
G36*
G01X117133D02*
X119953D01*
G02X120156Y1587998I1J-202D01*
G01Y1587376D01*
G03X120206Y1587244I200J0D01*
G02Y1584332I-1664J-1456D01*
G03X120156Y1584200I150J-132D01*
G01Y1582258D01*
G03X120206Y1582126I200J0D01*
G02Y1579214I-1664J-1456D01*
G03X120156Y1579082I150J-132D01*
G01Y1578460D01*
G02X119953Y1578258I-203J1D01*
G01X117133D01*
G02X116930Y1578460I-1J202D01*
G01Y1579082D01*
G03X116880Y1579214I-200J0D01*
G02Y1582126I1664J1456D01*
G03X116930Y1582258I-150J132D01*
G01Y1584200D01*
G03X116880Y1584332I-200J0D01*
G02Y1587244I1664J1456D01*
G03X116930Y1587376I-150J132D01*
G01Y1587998D01*
G02X117133Y1588200I203J-1D01*
G37*
G36*
G01X151779D02*
X154599D01*
G02X154802Y1587998I1J-202D01*
G01Y1587376D01*
G03X154852Y1587244I200J0D01*
G02Y1584332I-1664J-1456D01*
G03X154802Y1584200I150J-132D01*
G01Y1582258D01*
G03X154852Y1582126I200J0D01*
G02Y1579214I-1664J-1456D01*
G03X154802Y1579082I150J-132D01*
G01Y1578460D01*
G02X154599Y1578258I-203J1D01*
G01X151779D01*
G02X151576Y1578460I-1J202D01*
G01Y1579082D01*
G03X151526Y1579214I-200J0D01*
G02Y1582126I1664J1456D01*
G03X151576Y1582258I-150J132D01*
G01Y1584200D01*
G03X151526Y1584332I-200J0D01*
G02Y1587244I1664J1456D01*
G03X151576Y1587376I-150J132D01*
G01Y1587998D01*
G02X151779Y1588200I203J-1D01*
G37*
G36*
G01X290361D02*
X293181D01*
G02X293384Y1587998I1J-202D01*
G01Y1587376D01*
G03X293434Y1587244I200J0D01*
G02Y1584332I-1664J-1456D01*
G03X293384Y1584200I150J-132D01*
G01Y1582258D01*
G03X293434Y1582126I200J0D01*
G02Y1579214I-1664J-1456D01*
G03X293384Y1579082I150J-132D01*
G01Y1578460D01*
G02X293181Y1578258I-203J1D01*
G01X290361D01*
G02X290158Y1578460I-1J202D01*
G01Y1579082D01*
G03X290108Y1579214I-200J0D01*
G02Y1582126I1664J1456D01*
G03X290158Y1582258I-150J132D01*
G01Y1584200D01*
G03X290108Y1584332I-200J0D01*
G02Y1587244I1664J1456D01*
G03X290158Y1587376I-150J132D01*
G01Y1587998D01*
G02X290361Y1588200I203J-1D01*
G37*
G36*
G01X325007D02*
X327827D01*
G02X328030Y1587998I1J-202D01*
G01Y1587376D01*
G03X328080Y1587244I200J0D01*
G02Y1584332I-1664J-1456D01*
G03X328030Y1584200I150J-132D01*
G01Y1582258D01*
G03X328080Y1582126I200J0D01*
G02Y1579214I-1664J-1456D01*
G03X328030Y1579082I150J-132D01*
G01Y1578460D01*
G02X327827Y1578258I-203J1D01*
G01X325007D01*
G02X324804Y1578460I-1J202D01*
G01Y1579082D01*
G03X324754Y1579214I-200J0D01*
G02Y1582126I1664J1456D01*
G03X324804Y1582258I-150J132D01*
G01Y1584200D01*
G03X324754Y1584332I-200J0D01*
G02Y1587244I1664J1456D01*
G03X324804Y1587376I-150J132D01*
G01Y1587998D01*
G02X325007Y1588200I203J-1D01*
G37*
G36*
G01X515559D02*
X518379D01*
G02X518582Y1587998I1J-202D01*
G01Y1587376D01*
G03X518632Y1587244I200J0D01*
G02Y1584332I-1664J-1456D01*
G03X518582Y1584200I150J-132D01*
G01Y1582258D01*
G03X518632Y1582126I200J0D01*
G02Y1579214I-1664J-1456D01*
G03X518582Y1579082I150J-132D01*
G01Y1578460D01*
G02X518379Y1578258I-203J1D01*
G01X515559D01*
G02X515356Y1578460I-1J202D01*
G01Y1579082D01*
G03X515306Y1579214I-200J0D01*
G02Y1582126I1664J1456D01*
G03X515356Y1582258I-150J132D01*
G01Y1584200D01*
G03X515306Y1584332I-200J0D01*
G02Y1587244I1664J1456D01*
G03X515356Y1587376I-150J132D01*
G01Y1587998D01*
G02X515559Y1588200I203J-1D01*
G37*
G36*
G01X654141D02*
X656961D01*
G02X657164Y1587998I1J-202D01*
G01Y1587376D01*
G03X657214Y1587244I200J0D01*
G02Y1584332I-1664J-1456D01*
G03X657164Y1584200I150J-132D01*
G01Y1582258D01*
G03X657214Y1582126I200J0D01*
G02Y1579214I-1664J-1456D01*
G03X657164Y1579082I150J-132D01*
G01Y1578460D01*
G02X656961Y1578258I-203J1D01*
G01X654141D01*
G02X653938Y1578460I-1J202D01*
G01Y1579082D01*
G03X653888Y1579214I-200J0D01*
G02Y1582126I1664J1456D01*
G03X653938Y1582258I-150J132D01*
G01Y1584200D01*
G03X653888Y1584332I-200J0D01*
G02Y1587244I1664J1456D01*
G03X653938Y1587376I-150J132D01*
G01Y1587998D01*
G02X654141Y1588200I203J-1D01*
G37*
G36*
G01X688787D02*
X691607D01*
G02X691810Y1587998I1J-202D01*
G01Y1587376D01*
G03X691860Y1587244I200J0D01*
G02Y1584332I-1664J-1456D01*
G03X691810Y1584200I150J-132D01*
G01Y1582258D01*
G03X691860Y1582126I200J0D01*
G02Y1579214I-1664J-1456D01*
G03X691810Y1579082I150J-132D01*
G01Y1578460D01*
G02X691607Y1578258I-203J1D01*
G01X688787D01*
G02X688584Y1578460I-1J202D01*
G01Y1579082D01*
G03X688534Y1579214I-200J0D01*
G02Y1582126I1664J1456D01*
G03X688584Y1582258I-150J132D01*
G01Y1584200D01*
G03X688534Y1584332I-200J0D01*
G02Y1587244I1664J1456D01*
G03X688584Y1587376I-150J132D01*
G01Y1587998D01*
G02X688787Y1588200I203J-1D01*
G37*
G36*
G01X1139101D02*
X1141921D01*
G02X1142124Y1587998I1J-202D01*
G01Y1587376D01*
G03X1142174Y1587244I200J0D01*
G02Y1584332I-1664J-1456D01*
G03X1142124Y1584200I150J-132D01*
G01Y1582258D01*
G03X1142174Y1582126I200J0D01*
G02Y1579214I-1664J-1456D01*
G03X1142124Y1579082I150J-132D01*
G01Y1578460D01*
G02X1141921Y1578258I-203J1D01*
G01X1139101D01*
G02X1138898Y1578460I-1J202D01*
G01Y1579082D01*
G03X1138848Y1579214I-200J0D01*
G02Y1582126I1664J1456D01*
G03X1138898Y1582258I-150J132D01*
G01Y1584200D01*
G03X1138848Y1584332I-200J0D01*
G02Y1587244I1664J1456D01*
G03X1138898Y1587376I-150J132D01*
G01Y1587998D01*
G02X1139101Y1588200I203J-1D01*
G37*
G36*
G01X1173747D02*
X1176567D01*
G02X1176770Y1587998I1J-202D01*
G01Y1587376D01*
G03X1176820Y1587244I200J0D01*
G02Y1584332I-1664J-1456D01*
G03X1176770Y1584200I150J-132D01*
G01Y1582258D01*
G03X1176820Y1582126I200J0D01*
G02Y1579214I-1664J-1456D01*
G03X1176770Y1579082I150J-132D01*
G01Y1578460D01*
G02X1176567Y1578258I-203J1D01*
G01X1173747D01*
G02X1173544Y1578460I-1J202D01*
G01Y1579082D01*
G03X1173494Y1579214I-200J0D01*
G02Y1582126I1664J1456D01*
G03X1173544Y1582258I-150J132D01*
G01Y1584200D01*
G03X1173494Y1584332I-200J0D01*
G02Y1587244I1664J1456D01*
G03X1173544Y1587376I-150J132D01*
G01Y1587998D01*
G02X1173747Y1588200I203J-1D01*
G37*
G36*
G01X1329653D02*
X1332473D01*
G02X1332676Y1587998I1J-202D01*
G01Y1587376D01*
G03X1332726Y1587244I200J0D01*
G02Y1584332I-1664J-1456D01*
G03X1332676Y1584200I150J-132D01*
G01Y1582258D01*
G03X1332726Y1582126I200J0D01*
G02Y1579214I-1664J-1456D01*
G03X1332676Y1579082I150J-132D01*
G01Y1578460D01*
G02X1332473Y1578258I-203J1D01*
G01X1329653D01*
G02X1329450Y1578460I-1J202D01*
G01Y1579082D01*
G03X1329400Y1579214I-200J0D01*
G02Y1582126I1664J1456D01*
G03X1329450Y1582258I-150J132D01*
G01Y1584200D01*
G03X1329400Y1584332I-200J0D01*
G02Y1587244I1664J1456D01*
G03X1329450Y1587376I-150J132D01*
G01Y1587998D01*
G02X1329653Y1588200I203J-1D01*
G37*
G36*
G01X1364299D02*
X1367119D01*
G02X1367322Y1587998I1J-202D01*
G01Y1587376D01*
G03X1367372Y1587244I200J0D01*
G02Y1584332I-1664J-1456D01*
G03X1367322Y1584200I150J-132D01*
G01Y1582258D01*
G03X1367372Y1582126I200J0D01*
G02Y1579214I-1664J-1456D01*
G03X1367322Y1579082I150J-132D01*
G01Y1578460D01*
G02X1367119Y1578258I-203J1D01*
G01X1364299D01*
G02X1364096Y1578460I-1J202D01*
G01Y1579082D01*
G03X1364046Y1579214I-200J0D01*
G02Y1582126I1664J1456D01*
G03X1364096Y1582258I-150J132D01*
G01Y1584200D01*
G03X1364046Y1584332I-200J0D01*
G02Y1587244I1664J1456D01*
G03X1364096Y1587376I-150J132D01*
G01Y1587998D01*
G02X1364299Y1588200I203J-1D01*
G37*
G36*
G01X1676109D02*
X1678929D01*
G02X1679132Y1587998I1J-202D01*
G01Y1587376D01*
G03X1679182Y1587244I200J0D01*
G02Y1584332I-1664J-1456D01*
G03X1679132Y1584200I150J-132D01*
G01Y1582258D01*
G03X1679182Y1582126I200J0D01*
G02Y1579214I-1664J-1456D01*
G03X1679132Y1579082I150J-132D01*
G01Y1578460D01*
G02X1678929Y1578258I-203J1D01*
G01X1676109D01*
G02X1675906Y1578460I-1J202D01*
G01Y1579082D01*
G03X1675856Y1579214I-200J0D01*
G02Y1582126I1664J1456D01*
G03X1675906Y1582258I-150J132D01*
G01Y1584200D01*
G03X1675856Y1584332I-200J0D01*
G02Y1587244I1664J1456D01*
G03X1675906Y1587376I-150J132D01*
G01Y1587998D01*
G02X1676109Y1588200I203J-1D01*
G37*
G36*
G01X1710755D02*
X1713575D01*
G02X1713778Y1587998I1J-202D01*
G01Y1587376D01*
G03X1713828Y1587244I200J0D01*
G02Y1584332I-1664J-1456D01*
G03X1713778Y1584200I150J-132D01*
G01Y1582258D01*
G03X1713828Y1582126I200J0D01*
G02Y1579214I-1664J-1456D01*
G03X1713778Y1579082I150J-132D01*
G01Y1578460D01*
G02X1713575Y1578258I-203J1D01*
G01X1710755D01*
G02X1710552Y1578460I-1J202D01*
G01Y1579082D01*
G03X1710502Y1579214I-200J0D01*
G02Y1582126I1664J1456D01*
G03X1710552Y1582258I-150J132D01*
G01Y1584200D01*
G03X1710502Y1584332I-200J0D01*
G02Y1587244I1664J1456D01*
G03X1710552Y1587376I-150J132D01*
G01Y1587998D01*
G02X1710755Y1588200I203J-1D01*
G37*
G36*
G01X108472Y1599224D02*
X111292D01*
G02X111494Y1599021I-1J-203D01*
G01Y1598401D01*
G03X111544Y1598269I200J0D01*
G02Y1595353I-1661J-1458D01*
G03X111494Y1595221I150J-132D01*
G01Y1593283D01*
G03X111544Y1593151I200J0D01*
G02Y1590235I-1661J-1458D01*
G03X111494Y1590103I150J-132D01*
G01Y1589483D01*
G02X111292Y1589280I-202J-1D01*
G01X108472D01*
G02X108270Y1589483I1J203D01*
G01Y1590103D01*
G03X108220Y1590235I-200J0D01*
G02Y1593151I1661J1458D01*
G03X108270Y1593283I-150J132D01*
G01Y1595221D01*
G03X108220Y1595353I-200J0D01*
G02Y1598269I1661J1458D01*
G03X108270Y1598401I-150J132D01*
G01Y1599021D01*
G02X108472Y1599224I202J1D01*
G37*
G36*
G01X125795D02*
X128615D01*
G02X128818Y1599021I0J-203D01*
G01Y1598399D01*
G03X128868Y1598267I200J0D01*
G02Y1595355I-1664J-1456D01*
G03X128818Y1595223I150J-132D01*
G01Y1593281D01*
G03X128868Y1593149I200J0D01*
G02Y1590237I-1664J-1456D01*
G03X128818Y1590105I150J-132D01*
G01Y1589483D01*
G02X128615Y1589280I-203J0D01*
G01X125795D01*
G02X125592Y1589483I0J203D01*
G01Y1590105D01*
G03X125542Y1590237I-200J0D01*
G02Y1593149I1664J1456D01*
G03X125592Y1593281I-150J132D01*
G01Y1595223D01*
G03X125542Y1595355I-200J0D01*
G02Y1598267I1664J1456D01*
G03X125592Y1598399I-150J132D01*
G01Y1599021D01*
G02X125795Y1599224I203J0D01*
G37*
G36*
G01X143118D02*
X145938D01*
G02X146140Y1599021I-1J-203D01*
G01Y1598401D01*
G03X146190Y1598269I200J0D01*
G02Y1595353I-1661J-1458D01*
G03X146140Y1595221I150J-132D01*
G01Y1593283D01*
G03X146190Y1593151I200J0D01*
G02Y1590235I-1661J-1458D01*
G03X146140Y1590103I150J-132D01*
G01Y1589483D01*
G02X145938Y1589280I-202J-1D01*
G01X143118D01*
G02X142916Y1589483I1J203D01*
G01Y1590103D01*
G03X142866Y1590235I-200J0D01*
G02Y1593151I1661J1458D01*
G03X142916Y1593283I-150J132D01*
G01Y1595221D01*
G03X142866Y1595353I-200J0D01*
G02Y1598269I1661J1458D01*
G03X142916Y1598401I-150J132D01*
G01Y1599021D01*
G02X143118Y1599224I202J1D01*
G37*
G36*
G01X160440D02*
X163260D01*
G02X163462Y1599021I-1J-203D01*
G01Y1598401D01*
G03X163512Y1598269I200J0D01*
G02Y1595353I-1661J-1458D01*
G03X163462Y1595221I150J-132D01*
G01Y1593283D01*
G03X163512Y1593151I200J0D01*
G02Y1590235I-1661J-1458D01*
G03X163462Y1590103I150J-132D01*
G01Y1589483D01*
G02X163260Y1589280I-202J-1D01*
G01X160440D01*
G02X160238Y1589483I1J203D01*
G01Y1590103D01*
G03X160188Y1590235I-200J0D01*
G02Y1593151I1661J1458D01*
G03X160238Y1593283I-150J132D01*
G01Y1595221D01*
G03X160188Y1595353I-200J0D01*
G02Y1598269I1661J1458D01*
G03X160238Y1598401I-150J132D01*
G01Y1599021D01*
G02X160440Y1599224I202J1D01*
G37*
G36*
G01X281700D02*
X284520D01*
G02X284722Y1599021I-1J-203D01*
G01Y1598401D01*
G03X284772Y1598269I200J0D01*
G02Y1595353I-1661J-1458D01*
G03X284722Y1595221I150J-132D01*
G01Y1593283D01*
G03X284772Y1593151I200J0D01*
G02Y1590235I-1661J-1458D01*
G03X284722Y1590103I150J-132D01*
G01Y1589483D01*
G02X284520Y1589280I-202J-1D01*
G01X281700D01*
G02X281498Y1589483I1J203D01*
G01Y1590103D01*
G03X281448Y1590235I-200J0D01*
G02Y1593151I1661J1458D01*
G03X281498Y1593283I-150J132D01*
G01Y1595221D01*
G03X281448Y1595353I-200J0D01*
G02Y1598269I1661J1458D01*
G03X281498Y1598401I-150J132D01*
G01Y1599021D01*
G02X281700Y1599224I202J1D01*
G37*
G36*
G01X299023D02*
X301843D01*
G02X302046Y1599021I0J-203D01*
G01Y1598399D01*
G03X302096Y1598267I200J0D01*
G02Y1595355I-1664J-1456D01*
G03X302046Y1595223I150J-132D01*
G01Y1593281D01*
G03X302096Y1593149I200J0D01*
G02Y1590237I-1664J-1456D01*
G03X302046Y1590105I150J-132D01*
G01Y1589483D01*
G02X301843Y1589280I-203J0D01*
G01X299023D01*
G02X298820Y1589483I0J203D01*
G01Y1590105D01*
G03X298770Y1590237I-200J0D01*
G02Y1593149I1664J1456D01*
G03X298820Y1593281I-150J132D01*
G01Y1595223D01*
G03X298770Y1595355I-200J0D01*
G02Y1598267I1664J1456D01*
G03X298820Y1598399I-150J132D01*
G01Y1599021D01*
G02X299023Y1599224I203J0D01*
G37*
G36*
G01X316346D02*
X319166D01*
G02X319368Y1599021I-1J-203D01*
G01Y1598401D01*
G03X319418Y1598269I200J0D01*
G02Y1595353I-1661J-1458D01*
G03X319368Y1595221I150J-132D01*
G01Y1593283D01*
G03X319418Y1593151I200J0D01*
G02Y1590235I-1661J-1458D01*
G03X319368Y1590103I150J-132D01*
G01Y1589483D01*
G02X319166Y1589280I-202J-1D01*
G01X316346D01*
G02X316144Y1589483I1J203D01*
G01Y1590103D01*
G03X316094Y1590235I-200J0D01*
G02Y1593151I1661J1458D01*
G03X316144Y1593283I-150J132D01*
G01Y1595221D01*
G03X316094Y1595353I-200J0D01*
G02Y1598269I1661J1458D01*
G03X316144Y1598401I-150J132D01*
G01Y1599021D01*
G02X316346Y1599224I202J1D01*
G37*
G36*
G01X333668D02*
X336488D01*
G02X336690Y1599021I-1J-203D01*
G01Y1598401D01*
G03X336740Y1598269I200J0D01*
G02Y1595353I-1661J-1458D01*
G03X336690Y1595221I150J-132D01*
G01Y1593283D01*
G03X336740Y1593151I200J0D01*
G02Y1590235I-1661J-1458D01*
G03X336690Y1590103I150J-132D01*
G01Y1589483D01*
G02X336488Y1589280I-202J-1D01*
G01X333668D01*
G02X333466Y1589483I1J203D01*
G01Y1590103D01*
G03X333416Y1590235I-200J0D01*
G02Y1593151I1661J1458D01*
G03X333466Y1593283I-150J132D01*
G01Y1595221D01*
G03X333416Y1595353I-200J0D01*
G02Y1598269I1661J1458D01*
G03X333466Y1598401I-150J132D01*
G01Y1599021D01*
G02X333668Y1599224I202J1D01*
G37*
G36*
G01X628157D02*
X630977D01*
G02X631180Y1599021I0J-203D01*
G01Y1598399D01*
G03X631230Y1598267I200J0D01*
G02Y1595355I-1664J-1456D01*
G03X631180Y1595223I150J-132D01*
G01Y1593281D01*
G03X631230Y1593149I200J0D01*
G02Y1590237I-1664J-1456D01*
G03X631180Y1590105I150J-132D01*
G01Y1589483D01*
G02X630977Y1589280I-203J0D01*
G01X628157D01*
G02X627954Y1589483I0J203D01*
G01Y1590105D01*
G03X627904Y1590237I-200J0D01*
G02Y1593149I1664J1456D01*
G03X627954Y1593281I-150J132D01*
G01Y1595223D01*
G03X627904Y1595355I-200J0D01*
G02Y1598267I1664J1456D01*
G03X627954Y1598399I-150J132D01*
G01Y1599021D01*
G02X628157Y1599224I203J0D01*
G37*
G36*
G01X645480D02*
X648300D01*
G02X648502Y1599021I-1J-203D01*
G01Y1598401D01*
G03X648552Y1598269I200J0D01*
G02Y1595353I-1661J-1458D01*
G03X648502Y1595221I150J-132D01*
G01Y1593283D01*
G03X648552Y1593151I200J0D01*
G02Y1590235I-1661J-1458D01*
G03X648502Y1590103I150J-132D01*
G01Y1589483D01*
G02X648300Y1589280I-202J-1D01*
G01X645480D01*
G02X645278Y1589483I1J203D01*
G01Y1590103D01*
G03X645228Y1590235I-200J0D01*
G02Y1593151I1661J1458D01*
G03X645278Y1593283I-150J132D01*
G01Y1595221D01*
G03X645228Y1595353I-200J0D01*
G02Y1598269I1661J1458D01*
G03X645278Y1598401I-150J132D01*
G01Y1599021D01*
G02X645480Y1599224I202J1D01*
G37*
G36*
G01X662803D02*
X665623D01*
G02X665826Y1599021I0J-203D01*
G01Y1598399D01*
G03X665876Y1598267I200J0D01*
G02Y1595355I-1664J-1456D01*
G03X665826Y1595223I150J-132D01*
G01Y1593281D01*
G03X665876Y1593149I200J0D01*
G02Y1590237I-1664J-1456D01*
G03X665826Y1590105I150J-132D01*
G01Y1589483D01*
G02X665623Y1589280I-203J0D01*
G01X662803D01*
G02X662600Y1589483I0J203D01*
G01Y1590105D01*
G03X662550Y1590237I-200J0D01*
G02Y1593149I1664J1456D01*
G03X662600Y1593281I-150J132D01*
G01Y1595223D01*
G03X662550Y1595355I-200J0D01*
G02Y1598267I1664J1456D01*
G03X662600Y1598399I-150J132D01*
G01Y1599021D01*
G02X662803Y1599224I203J0D01*
G37*
G36*
G01X680125D02*
X682945D01*
G02X683148Y1599021I0J-203D01*
G01Y1598399D01*
G03X683198Y1598267I200J0D01*
G02Y1595355I-1664J-1456D01*
G03X683148Y1595223I150J-132D01*
G01Y1593281D01*
G03X683198Y1593149I200J0D01*
G02Y1590237I-1664J-1456D01*
G03X683148Y1590105I150J-132D01*
G01Y1589483D01*
G02X682945Y1589280I-203J0D01*
G01X680125D01*
G02X679922Y1589483I0J203D01*
G01Y1590105D01*
G03X679872Y1590237I-200J0D01*
G02Y1593149I1664J1456D01*
G03X679922Y1593281I-150J132D01*
G01Y1595223D01*
G03X679872Y1595355I-200J0D01*
G02Y1598267I1664J1456D01*
G03X679922Y1598399I-150J132D01*
G01Y1599021D01*
G02X680125Y1599224I203J0D01*
G37*
G36*
G01X1130440D02*
X1133260D01*
G02X1133462Y1599021I-1J-203D01*
G01Y1598401D01*
G03X1133512Y1598269I200J0D01*
G02Y1595353I-1661J-1458D01*
G03X1133462Y1595221I150J-132D01*
G01Y1593283D01*
G03X1133512Y1593151I200J0D01*
G02Y1590235I-1661J-1458D01*
G03X1133462Y1590103I150J-132D01*
G01Y1589483D01*
G02X1133260Y1589280I-202J-1D01*
G01X1130440D01*
G02X1130238Y1589483I1J203D01*
G01Y1590103D01*
G03X1130188Y1590235I-200J0D01*
G02Y1593151I1661J1458D01*
G03X1130238Y1593283I-150J132D01*
G01Y1595221D01*
G03X1130188Y1595353I-200J0D01*
G02Y1598269I1661J1458D01*
G03X1130238Y1598401I-150J132D01*
G01Y1599021D01*
G02X1130440Y1599224I202J1D01*
G37*
G36*
G01X1147763D02*
X1150583D01*
G02X1150786Y1599021I0J-203D01*
G01Y1598399D01*
G03X1150836Y1598267I200J0D01*
G02Y1595355I-1664J-1456D01*
G03X1150786Y1595223I150J-132D01*
G01Y1593281D01*
G03X1150836Y1593149I200J0D01*
G02Y1590237I-1664J-1456D01*
G03X1150786Y1590105I150J-132D01*
G01Y1589483D01*
G02X1150583Y1589280I-203J0D01*
G01X1147763D01*
G02X1147560Y1589483I0J203D01*
G01Y1590105D01*
G03X1147510Y1590237I-200J0D01*
G02Y1593149I1664J1456D01*
G03X1147560Y1593281I-150J132D01*
G01Y1595223D01*
G03X1147510Y1595355I-200J0D01*
G02Y1598267I1664J1456D01*
G03X1147560Y1598399I-150J132D01*
G01Y1599021D01*
G02X1147763Y1599224I203J0D01*
G37*
G36*
G01X1165086D02*
X1167906D01*
G02X1168108Y1599021I-1J-203D01*
G01Y1598401D01*
G03X1168158Y1598269I200J0D01*
G02Y1595353I-1661J-1458D01*
G03X1168108Y1595221I150J-132D01*
G01Y1593283D01*
G03X1168158Y1593151I200J0D01*
G02Y1590235I-1661J-1458D01*
G03X1168108Y1590103I150J-132D01*
G01Y1589483D01*
G02X1167906Y1589280I-202J-1D01*
G01X1165086D01*
G02X1164884Y1589483I1J203D01*
G01Y1590103D01*
G03X1164834Y1590235I-200J0D01*
G02Y1593151I1661J1458D01*
G03X1164884Y1593283I-150J132D01*
G01Y1595221D01*
G03X1164834Y1595353I-200J0D01*
G02Y1598269I1661J1458D01*
G03X1164884Y1598401I-150J132D01*
G01Y1599021D01*
G02X1165086Y1599224I202J1D01*
G37*
G36*
G01X1182408D02*
X1185228D01*
G02X1185430Y1599021I-1J-203D01*
G01Y1598401D01*
G03X1185480Y1598269I200J0D01*
G02Y1595353I-1661J-1458D01*
G03X1185430Y1595221I150J-132D01*
G01Y1593283D01*
G03X1185480Y1593151I200J0D01*
G02Y1590235I-1661J-1458D01*
G03X1185430Y1590103I150J-132D01*
G01Y1589483D01*
G02X1185228Y1589280I-202J-1D01*
G01X1182408D01*
G02X1182206Y1589483I1J203D01*
G01Y1590103D01*
G03X1182156Y1590235I-200J0D01*
G02Y1593151I1661J1458D01*
G03X1182206Y1593283I-150J132D01*
G01Y1595221D01*
G03X1182156Y1595353I-200J0D01*
G02Y1598269I1661J1458D01*
G03X1182206Y1598401I-150J132D01*
G01Y1599021D01*
G02X1182408Y1599224I202J1D01*
G37*
G36*
G01X1303669D02*
X1306489D01*
G02X1306692Y1599021I0J-203D01*
G01Y1598399D01*
G03X1306742Y1598267I200J0D01*
G02Y1595355I-1664J-1456D01*
G03X1306692Y1595223I150J-132D01*
G01Y1593281D01*
G03X1306742Y1593149I200J0D01*
G02Y1590237I-1664J-1456D01*
G03X1306692Y1590105I150J-132D01*
G01Y1589483D01*
G02X1306489Y1589280I-203J0D01*
G01X1303669D01*
G02X1303466Y1589483I0J203D01*
G01Y1590105D01*
G03X1303416Y1590237I-200J0D01*
G02Y1593149I1664J1456D01*
G03X1303466Y1593281I-150J132D01*
G01Y1595223D01*
G03X1303416Y1595355I-200J0D01*
G02Y1598267I1664J1456D01*
G03X1303466Y1598399I-150J132D01*
G01Y1599021D01*
G02X1303669Y1599224I203J0D01*
G37*
G36*
G01X1320992D02*
X1323812D01*
G02X1324014Y1599021I-1J-203D01*
G01Y1598401D01*
G03X1324064Y1598269I200J0D01*
G02Y1595353I-1661J-1458D01*
G03X1324014Y1595221I150J-132D01*
G01Y1593283D01*
G03X1324064Y1593151I200J0D01*
G02Y1590235I-1661J-1458D01*
G03X1324014Y1590103I150J-132D01*
G01Y1589483D01*
G02X1323812Y1589280I-202J-1D01*
G01X1320992D01*
G02X1320790Y1589483I1J203D01*
G01Y1590103D01*
G03X1320740Y1590235I-200J0D01*
G02Y1593151I1661J1458D01*
G03X1320790Y1593283I-150J132D01*
G01Y1595221D01*
G03X1320740Y1595353I-200J0D01*
G02Y1598269I1661J1458D01*
G03X1320790Y1598401I-150J132D01*
G01Y1599021D01*
G02X1320992Y1599224I202J1D01*
G37*
G36*
G01X1338315D02*
X1341135D01*
G02X1341338Y1599021I0J-203D01*
G01Y1598399D01*
G03X1341388Y1598267I200J0D01*
G02Y1595355I-1664J-1456D01*
G03X1341338Y1595223I150J-132D01*
G01Y1593281D01*
G03X1341388Y1593149I200J0D01*
G02Y1590237I-1664J-1456D01*
G03X1341338Y1590105I150J-132D01*
G01Y1589483D01*
G02X1341135Y1589280I-203J0D01*
G01X1338315D01*
G02X1338112Y1589483I0J203D01*
G01Y1590105D01*
G03X1338062Y1590237I-200J0D01*
G02Y1593149I1664J1456D01*
G03X1338112Y1593281I-150J132D01*
G01Y1595223D01*
G03X1338062Y1595355I-200J0D01*
G02Y1598267I1664J1456D01*
G03X1338112Y1598399I-150J132D01*
G01Y1599021D01*
G02X1338315Y1599224I203J0D01*
G37*
G36*
G01X1355637D02*
X1358457D01*
G02X1358660Y1599021I0J-203D01*
G01Y1598399D01*
G03X1358710Y1598267I200J0D01*
G02Y1595355I-1664J-1456D01*
G03X1358660Y1595223I150J-132D01*
G01Y1593281D01*
G03X1358710Y1593149I200J0D01*
G02Y1590237I-1664J-1456D01*
G03X1358660Y1590105I150J-132D01*
G01Y1589483D01*
G02X1358457Y1589280I-203J0D01*
G01X1355637D01*
G02X1355434Y1589483I0J203D01*
G01Y1590105D01*
G03X1355384Y1590237I-200J0D01*
G02Y1593149I1664J1456D01*
G03X1355434Y1593281I-150J132D01*
G01Y1595223D01*
G03X1355384Y1595355I-200J0D01*
G02Y1598267I1664J1456D01*
G03X1355434Y1598399I-150J132D01*
G01Y1599021D01*
G02X1355637Y1599224I203J0D01*
G37*
G36*
G01X1476897D02*
X1479717D01*
G02X1479920Y1599021I0J-203D01*
G01Y1598399D01*
G03X1479970Y1598267I200J0D01*
G02Y1595355I-1664J-1456D01*
G03X1479920Y1595223I150J-132D01*
G01Y1593281D01*
G03X1479970Y1593149I200J0D01*
G02Y1590237I-1664J-1456D01*
G03X1479920Y1590105I150J-132D01*
G01Y1589483D01*
G02X1479717Y1589280I-203J0D01*
G01X1476897D01*
G02X1476694Y1589483I0J203D01*
G01Y1590105D01*
G03X1476644Y1590237I-200J0D01*
G02Y1593149I1664J1456D01*
G03X1476694Y1593281I-150J132D01*
G01Y1595223D01*
G03X1476644Y1595355I-200J0D01*
G02Y1598267I1664J1456D01*
G03X1476694Y1598399I-150J132D01*
G01Y1599021D01*
G02X1476897Y1599224I203J0D01*
G37*
G36*
G01X1650125D02*
X1652945D01*
G02X1653148Y1599021I0J-203D01*
G01Y1598399D01*
G03X1653198Y1598267I200J0D01*
G02Y1595355I-1664J-1456D01*
G03X1653148Y1595223I150J-132D01*
G01Y1593281D01*
G03X1653198Y1593149I200J0D01*
G02Y1590237I-1664J-1456D01*
G03X1653148Y1590105I150J-132D01*
G01Y1589483D01*
G02X1652945Y1589280I-203J0D01*
G01X1650125D01*
G02X1649922Y1589483I0J203D01*
G01Y1590105D01*
G03X1649872Y1590237I-200J0D01*
G02Y1593149I1664J1456D01*
G03X1649922Y1593281I-150J132D01*
G01Y1595223D01*
G03X1649872Y1595355I-200J0D01*
G02Y1598267I1664J1456D01*
G03X1649922Y1598399I-150J132D01*
G01Y1599021D01*
G02X1650125Y1599224I203J0D01*
G37*
G36*
G01X1667448D02*
X1670268D01*
G02X1670470Y1599021I-1J-203D01*
G01Y1598401D01*
G03X1670520Y1598269I200J0D01*
G02Y1595353I-1661J-1458D01*
G03X1670470Y1595221I150J-132D01*
G01Y1593283D01*
G03X1670520Y1593151I200J0D01*
G02Y1590235I-1661J-1458D01*
G03X1670470Y1590103I150J-132D01*
G01Y1589483D01*
G02X1670268Y1589280I-202J-1D01*
G01X1667448D01*
G02X1667246Y1589483I1J203D01*
G01Y1590103D01*
G03X1667196Y1590235I-200J0D01*
G02Y1593151I1661J1458D01*
G03X1667246Y1593283I-150J132D01*
G01Y1595221D01*
G03X1667196Y1595353I-200J0D01*
G02Y1598269I1661J1458D01*
G03X1667246Y1598401I-150J132D01*
G01Y1599021D01*
G02X1667448Y1599224I202J1D01*
G37*
G36*
G01X1684771D02*
X1687591D01*
G02X1687794Y1599021I0J-203D01*
G01Y1598399D01*
G03X1687844Y1598267I200J0D01*
G02Y1595355I-1664J-1456D01*
G03X1687794Y1595223I150J-132D01*
G01Y1593281D01*
G03X1687844Y1593149I200J0D01*
G02Y1590237I-1664J-1456D01*
G03X1687794Y1590105I150J-132D01*
G01Y1589483D01*
G02X1687591Y1589280I-203J0D01*
G01X1684771D01*
G02X1684568Y1589483I0J203D01*
G01Y1590105D01*
G03X1684518Y1590237I-200J0D01*
G02Y1593149I1664J1456D01*
G03X1684568Y1593281I-150J132D01*
G01Y1595223D01*
G03X1684518Y1595355I-200J0D01*
G02Y1598267I1664J1456D01*
G03X1684568Y1598399I-150J132D01*
G01Y1599021D01*
G02X1684771Y1599224I203J0D01*
G37*
G36*
G01X1702093D02*
X1704913D01*
G02X1705116Y1599021I0J-203D01*
G01Y1598399D01*
G03X1705166Y1598267I200J0D01*
G02Y1595355I-1664J-1456D01*
G03X1705116Y1595223I150J-132D01*
G01Y1593281D01*
G03X1705166Y1593149I200J0D01*
G02Y1590237I-1664J-1456D01*
G03X1705116Y1590105I150J-132D01*
G01Y1589483D01*
G02X1704913Y1589280I-203J0D01*
G01X1702093D01*
G02X1701890Y1589483I0J203D01*
G01Y1590105D01*
G03X1701840Y1590237I-200J0D01*
G02Y1593149I1664J1456D01*
G03X1701890Y1593281I-150J132D01*
G01Y1595223D01*
G03X1701840Y1595355I-200J0D01*
G02Y1598267I1664J1456D01*
G03X1701890Y1598399I-150J132D01*
G01Y1599021D01*
G02X1702093Y1599224I203J0D01*
G37*
G36*
G01X134456Y1603554D02*
X137276D01*
G02X137478Y1603352I0J-202D01*
G01Y1602732D01*
G03X137528Y1602600I200J0D01*
G02Y1599684I-1661J-1458D01*
G03X137478Y1599552I150J-132D01*
G01Y1597614D01*
G03X137528Y1597482I200J0D01*
G02Y1594566I-1661J-1458D01*
G03X137478Y1594434I150J-132D01*
G01Y1593814D01*
G02X137276Y1593612I-202J0D01*
G01X134456D01*
G02X134254Y1593814I0J202D01*
G01Y1594434D01*
G03X134204Y1594566I-200J0D01*
G02Y1597482I1661J1458D01*
G03X134254Y1597614I-150J132D01*
G01Y1599552D01*
G03X134204Y1599684I-200J0D01*
G02Y1602600I1661J1458D01*
G03X134254Y1602732I-150J132D01*
G01Y1603352D01*
G02X134456Y1603554I202J0D01*
G37*
G36*
G01X169102D02*
X171922D01*
G02X172124Y1603352I0J-202D01*
G01Y1602732D01*
G03X172174Y1602600I200J0D01*
G02Y1599684I-1661J-1458D01*
G03X172124Y1599552I150J-132D01*
G01Y1597614D01*
G03X172174Y1597482I200J0D01*
G02Y1594566I-1661J-1458D01*
G03X172124Y1594434I150J-132D01*
G01Y1593814D01*
G02X171922Y1593612I-202J0D01*
G01X169102D01*
G02X168900Y1593814I0J202D01*
G01Y1594434D01*
G03X168850Y1594566I-200J0D01*
G02Y1597482I1661J1458D01*
G03X168900Y1597614I-150J132D01*
G01Y1599552D01*
G03X168850Y1599684I-200J0D01*
G02Y1602600I1661J1458D01*
G03X168900Y1602732I-150J132D01*
G01Y1603352D01*
G02X169102Y1603554I202J0D01*
G37*
G36*
G01X307684D02*
X310504D01*
G02X310706Y1603352I0J-202D01*
G01Y1602732D01*
G03X310756Y1602600I200J0D01*
G02Y1599684I-1661J-1458D01*
G03X310706Y1599552I150J-132D01*
G01Y1597614D01*
G03X310756Y1597482I200J0D01*
G02Y1594566I-1661J-1458D01*
G03X310706Y1594434I150J-132D01*
G01Y1593814D01*
G02X310504Y1593612I-202J0D01*
G01X307684D01*
G02X307482Y1593814I0J202D01*
G01Y1594434D01*
G03X307432Y1594566I-200J0D01*
G02Y1597482I1661J1458D01*
G03X307482Y1597614I-150J132D01*
G01Y1599552D01*
G03X307432Y1599684I-200J0D01*
G02Y1602600I1661J1458D01*
G03X307482Y1602732I-150J132D01*
G01Y1603352D01*
G02X307684Y1603554I202J0D01*
G37*
G36*
G01X342330D02*
X345150D01*
G02X345352Y1603352I0J-202D01*
G01Y1602732D01*
G03X345402Y1602600I200J0D01*
G02Y1599684I-1661J-1458D01*
G03X345352Y1599552I150J-132D01*
G01Y1597614D01*
G03X345402Y1597482I200J0D01*
G02Y1594566I-1661J-1458D01*
G03X345352Y1594434I150J-132D01*
G01Y1593814D01*
G02X345150Y1593612I-202J0D01*
G01X342330D01*
G02X342128Y1593814I0J202D01*
G01Y1594434D01*
G03X342078Y1594566I-200J0D01*
G02Y1597482I1661J1458D01*
G03X342128Y1597614I-150J132D01*
G01Y1599552D01*
G03X342078Y1599684I-200J0D01*
G02Y1602600I1661J1458D01*
G03X342128Y1602732I-150J132D01*
G01Y1603352D01*
G02X342330Y1603554I202J0D01*
G37*
G36*
G01X636818D02*
X639638D01*
G02X639840Y1603352I0J-202D01*
G01Y1602732D01*
G03X639890Y1602600I200J0D01*
G02Y1599684I-1661J-1458D01*
G03X639840Y1599552I150J-132D01*
G01Y1597614D01*
G03X639890Y1597482I200J0D01*
G02Y1594566I-1661J-1458D01*
G03X639840Y1594434I150J-132D01*
G01Y1593814D01*
G02X639638Y1593612I-202J0D01*
G01X636818D01*
G02X636616Y1593814I0J202D01*
G01Y1594434D01*
G03X636566Y1594566I-200J0D01*
G02Y1597482I1661J1458D01*
G03X636616Y1597614I-150J132D01*
G01Y1599552D01*
G03X636566Y1599684I-200J0D01*
G02Y1602600I1661J1458D01*
G03X636616Y1602732I-150J132D01*
G01Y1603352D01*
G02X636818Y1603554I202J0D01*
G37*
G36*
G01X671464D02*
X674284D01*
G02X674486Y1603352I0J-202D01*
G01Y1602732D01*
G03X674536Y1602600I200J0D01*
G02Y1599684I-1661J-1458D01*
G03X674486Y1599552I150J-132D01*
G01Y1597614D01*
G03X674536Y1597482I200J0D01*
G02Y1594566I-1661J-1458D01*
G03X674486Y1594434I150J-132D01*
G01Y1593814D01*
G02X674284Y1593612I-202J0D01*
G01X671464D01*
G02X671262Y1593814I0J202D01*
G01Y1594434D01*
G03X671212Y1594566I-200J0D01*
G02Y1597482I1661J1458D01*
G03X671262Y1597614I-150J132D01*
G01Y1599552D01*
G03X671212Y1599684I-200J0D01*
G02Y1602600I1661J1458D01*
G03X671262Y1602732I-150J132D01*
G01Y1603352D01*
G02X671464Y1603554I202J0D01*
G37*
G36*
G01X1156424D02*
X1159244D01*
G02X1159446Y1603352I0J-202D01*
G01Y1602732D01*
G03X1159496Y1602600I200J0D01*
G02Y1599684I-1661J-1458D01*
G03X1159446Y1599552I150J-132D01*
G01Y1597614D01*
G03X1159496Y1597482I200J0D01*
G02Y1594566I-1661J-1458D01*
G03X1159446Y1594434I150J-132D01*
G01Y1593814D01*
G02X1159244Y1593612I-202J0D01*
G01X1156424D01*
G02X1156222Y1593814I0J202D01*
G01Y1594434D01*
G03X1156172Y1594566I-200J0D01*
G02Y1597482I1661J1458D01*
G03X1156222Y1597614I-150J132D01*
G01Y1599552D01*
G03X1156172Y1599684I-200J0D01*
G02Y1602600I1661J1458D01*
G03X1156222Y1602732I-150J132D01*
G01Y1603352D01*
G02X1156424Y1603554I202J0D01*
G37*
G36*
G01X1191070D02*
X1193890D01*
G02X1194092Y1603352I0J-202D01*
G01Y1602732D01*
G03X1194142Y1602600I200J0D01*
G02Y1599684I-1661J-1458D01*
G03X1194092Y1599552I150J-132D01*
G01Y1597614D01*
G03X1194142Y1597482I200J0D01*
G02Y1594566I-1661J-1458D01*
G03X1194092Y1594434I150J-132D01*
G01Y1593814D01*
G02X1193890Y1593612I-202J0D01*
G01X1191070D01*
G02X1190868Y1593814I0J202D01*
G01Y1594434D01*
G03X1190818Y1594566I-200J0D01*
G02Y1597482I1661J1458D01*
G03X1190868Y1597614I-150J132D01*
G01Y1599552D01*
G03X1190818Y1599684I-200J0D01*
G02Y1602600I1661J1458D01*
G03X1190868Y1602732I-150J132D01*
G01Y1603352D01*
G02X1191070Y1603554I202J0D01*
G37*
G36*
G01X1312330D02*
X1315150D01*
G02X1315352Y1603352I0J-202D01*
G01Y1602732D01*
G03X1315402Y1602600I200J0D01*
G02Y1599684I-1661J-1458D01*
G03X1315352Y1599552I150J-132D01*
G01Y1597614D01*
G03X1315402Y1597482I200J0D01*
G02Y1594566I-1661J-1458D01*
G03X1315352Y1594434I150J-132D01*
G01Y1593814D01*
G02X1315150Y1593612I-202J0D01*
G01X1312330D01*
G02X1312128Y1593814I0J202D01*
G01Y1594434D01*
G03X1312078Y1594566I-200J0D01*
G02Y1597482I1661J1458D01*
G03X1312128Y1597614I-150J132D01*
G01Y1599552D01*
G03X1312078Y1599684I-200J0D01*
G02Y1602600I1661J1458D01*
G03X1312128Y1602732I-150J132D01*
G01Y1603352D01*
G02X1312330Y1603554I202J0D01*
G37*
G36*
G01X1346976D02*
X1349796D01*
G02X1349998Y1603352I0J-202D01*
G01Y1602732D01*
G03X1350048Y1602600I200J0D01*
G02Y1599684I-1661J-1458D01*
G03X1349998Y1599552I150J-132D01*
G01Y1597614D01*
G03X1350048Y1597482I200J0D01*
G02Y1594566I-1661J-1458D01*
G03X1349998Y1594434I150J-132D01*
G01Y1593814D01*
G02X1349796Y1593612I-202J0D01*
G01X1346976D01*
G02X1346774Y1593814I0J202D01*
G01Y1594434D01*
G03X1346724Y1594566I-200J0D01*
G02Y1597482I1661J1458D01*
G03X1346774Y1597614I-150J132D01*
G01Y1599552D01*
G03X1346724Y1599684I-200J0D01*
G02Y1602600I1661J1458D01*
G03X1346774Y1602732I-150J132D01*
G01Y1603352D01*
G02X1346976Y1603554I202J0D01*
G37*
G36*
G01X1658786D02*
X1661606D01*
G02X1661808Y1603352I0J-202D01*
G01Y1602732D01*
G03X1661858Y1602600I200J0D01*
G02Y1599684I-1661J-1458D01*
G03X1661808Y1599552I150J-132D01*
G01Y1597614D01*
G03X1661858Y1597482I200J0D01*
G02Y1594566I-1661J-1458D01*
G03X1661808Y1594434I150J-132D01*
G01Y1593814D01*
G02X1661606Y1593612I-202J0D01*
G01X1658786D01*
G02X1658584Y1593814I0J202D01*
G01Y1594434D01*
G03X1658534Y1594566I-200J0D01*
G02Y1597482I1661J1458D01*
G03X1658584Y1597614I-150J132D01*
G01Y1599552D01*
G03X1658534Y1599684I-200J0D01*
G02Y1602600I1661J1458D01*
G03X1658584Y1602732I-150J132D01*
G01Y1603352D01*
G02X1658786Y1603554I202J0D01*
G37*
G36*
G01X1693432D02*
X1696252D01*
G02X1696454Y1603352I0J-202D01*
G01Y1602732D01*
G03X1696504Y1602600I200J0D01*
G02Y1599684I-1661J-1458D01*
G03X1696454Y1599552I150J-132D01*
G01Y1597614D01*
G03X1696504Y1597482I200J0D01*
G02Y1594566I-1661J-1458D01*
G03X1696454Y1594434I150J-132D01*
G01Y1593814D01*
G02X1696252Y1593612I-202J0D01*
G01X1693432D01*
G02X1693230Y1593814I0J202D01*
G01Y1594434D01*
G03X1693180Y1594566I-200J0D01*
G02Y1597482I1661J1458D01*
G03X1693230Y1597614I-150J132D01*
G01Y1599552D01*
G03X1693180Y1599684I-200J0D01*
G02Y1602600I1661J1458D01*
G03X1693230Y1602732I-150J132D01*
G01Y1603352D01*
G02X1693432Y1603554I202J0D01*
G37*
G36*
G01X117133D02*
X119953D01*
G02X120156Y1603352I1J-202D01*
G01Y1602730D01*
G03X120206Y1602598I200J0D01*
G02Y1599686I-1664J-1456D01*
G03X120156Y1599554I150J-132D01*
G01Y1597612D01*
G03X120206Y1597480I200J0D01*
G02Y1594568I-1664J-1456D01*
G03X120156Y1594436I150J-132D01*
G01Y1593814D01*
G02X119953Y1593612I-203J1D01*
G01X117133D01*
G02X116930Y1593814I-1J202D01*
G01Y1594436D01*
G03X116880Y1594568I-200J0D01*
G02Y1597480I1664J1456D01*
G03X116930Y1597612I-150J132D01*
G01Y1599554D01*
G03X116880Y1599686I-200J0D01*
G02Y1602598I1664J1456D01*
G03X116930Y1602730I-150J132D01*
G01Y1603352D01*
G02X117133Y1603554I203J-1D01*
G37*
G36*
G01X151779D02*
X154599D01*
G02X154802Y1603352I1J-202D01*
G01Y1602730D01*
G03X154852Y1602598I200J0D01*
G02Y1599686I-1664J-1456D01*
G03X154802Y1599554I150J-132D01*
G01Y1597612D01*
G03X154852Y1597480I200J0D01*
G02Y1594568I-1664J-1456D01*
G03X154802Y1594436I150J-132D01*
G01Y1593814D01*
G02X154599Y1593612I-203J1D01*
G01X151779D01*
G02X151576Y1593814I-1J202D01*
G01Y1594436D01*
G03X151526Y1594568I-200J0D01*
G02Y1597480I1664J1456D01*
G03X151576Y1597612I-150J132D01*
G01Y1599554D01*
G03X151526Y1599686I-200J0D01*
G02Y1602598I1664J1456D01*
G03X151576Y1602730I-150J132D01*
G01Y1603352D01*
G02X151779Y1603554I203J-1D01*
G37*
G36*
G01X186425D02*
X189245D01*
G02X189448Y1603352I1J-202D01*
G01Y1602730D01*
G03X189498Y1602598I200J0D01*
G02Y1599686I-1664J-1456D01*
G03X189448Y1599554I150J-132D01*
G01Y1597612D01*
G03X189498Y1597480I200J0D01*
G02Y1594568I-1664J-1456D01*
G03X189448Y1594436I150J-132D01*
G01Y1593814D01*
G02X189245Y1593612I-203J1D01*
G01X186425D01*
G02X186222Y1593814I-1J202D01*
G01Y1594436D01*
G03X186172Y1594568I-200J0D01*
G02Y1597480I1664J1456D01*
G03X186222Y1597612I-150J132D01*
G01Y1599554D01*
G03X186172Y1599686I-200J0D01*
G02Y1602598I1664J1456D01*
G03X186222Y1602730I-150J132D01*
G01Y1603352D01*
G02X186425Y1603554I203J-1D01*
G37*
G36*
G01X290361D02*
X293181D01*
G02X293384Y1603352I1J-202D01*
G01Y1602730D01*
G03X293434Y1602598I200J0D01*
G02Y1599686I-1664J-1456D01*
G03X293384Y1599554I150J-132D01*
G01Y1597612D01*
G03X293434Y1597480I200J0D01*
G02Y1594568I-1664J-1456D01*
G03X293384Y1594436I150J-132D01*
G01Y1593814D01*
G02X293181Y1593612I-203J1D01*
G01X290361D01*
G02X290158Y1593814I-1J202D01*
G01Y1594436D01*
G03X290108Y1594568I-200J0D01*
G02Y1597480I1664J1456D01*
G03X290158Y1597612I-150J132D01*
G01Y1599554D01*
G03X290108Y1599686I-200J0D01*
G02Y1602598I1664J1456D01*
G03X290158Y1602730I-150J132D01*
G01Y1603352D01*
G02X290361Y1603554I203J-1D01*
G37*
G36*
G01X325007D02*
X327827D01*
G02X328030Y1603352I1J-202D01*
G01Y1602730D01*
G03X328080Y1602598I200J0D01*
G02Y1599686I-1664J-1456D01*
G03X328030Y1599554I150J-132D01*
G01Y1597612D01*
G03X328080Y1597480I200J0D01*
G02Y1594568I-1664J-1456D01*
G03X328030Y1594436I150J-132D01*
G01Y1593814D01*
G02X327827Y1593612I-203J1D01*
G01X325007D01*
G02X324804Y1593814I-1J202D01*
G01Y1594436D01*
G03X324754Y1594568I-200J0D01*
G02Y1597480I1664J1456D01*
G03X324804Y1597612I-150J132D01*
G01Y1599554D01*
G03X324754Y1599686I-200J0D01*
G02Y1602598I1664J1456D01*
G03X324804Y1602730I-150J132D01*
G01Y1603352D01*
G02X325007Y1603554I203J-1D01*
G37*
G36*
G01X359653D02*
X362473D01*
G02X362676Y1603352I1J-202D01*
G01Y1602730D01*
G03X362726Y1602598I200J0D01*
G02Y1599686I-1664J-1456D01*
G03X362676Y1599554I150J-132D01*
G01Y1597612D01*
G03X362726Y1597480I200J0D01*
G02Y1594568I-1664J-1456D01*
G03X362676Y1594436I150J-132D01*
G01Y1593814D01*
G02X362473Y1593612I-203J1D01*
G01X359653D01*
G02X359450Y1593814I-1J202D01*
G01Y1594436D01*
G03X359400Y1594568I-200J0D01*
G02Y1597480I1664J1456D01*
G03X359450Y1597612I-150J132D01*
G01Y1599554D01*
G03X359400Y1599686I-200J0D01*
G02Y1602598I1664J1456D01*
G03X359450Y1602730I-150J132D01*
G01Y1603352D01*
G02X359653Y1603554I203J-1D01*
G37*
G36*
G01X515559D02*
X518379D01*
G02X518582Y1603352I1J-202D01*
G01Y1602730D01*
G03X518632Y1602598I200J0D01*
G02Y1599686I-1664J-1456D01*
G03X518582Y1599554I150J-132D01*
G01Y1597612D01*
G03X518632Y1597480I200J0D01*
G02Y1594568I-1664J-1456D01*
G03X518582Y1594436I150J-132D01*
G01Y1593814D01*
G02X518379Y1593612I-203J1D01*
G01X515559D01*
G02X515356Y1593814I-1J202D01*
G01Y1594436D01*
G03X515306Y1594568I-200J0D01*
G02Y1597480I1664J1456D01*
G03X515356Y1597612I-150J132D01*
G01Y1599554D01*
G03X515306Y1599686I-200J0D01*
G02Y1602598I1664J1456D01*
G03X515356Y1602730I-150J132D01*
G01Y1603352D01*
G02X515559Y1603554I203J-1D01*
G37*
G36*
G01X654141D02*
X656961D01*
G02X657164Y1603352I1J-202D01*
G01Y1602730D01*
G03X657214Y1602598I200J0D01*
G02Y1599686I-1664J-1456D01*
G03X657164Y1599554I150J-132D01*
G01Y1597612D01*
G03X657214Y1597480I200J0D01*
G02Y1594568I-1664J-1456D01*
G03X657164Y1594436I150J-132D01*
G01Y1593814D01*
G02X656961Y1593612I-203J1D01*
G01X654141D01*
G02X653938Y1593814I-1J202D01*
G01Y1594436D01*
G03X653888Y1594568I-200J0D01*
G02Y1597480I1664J1456D01*
G03X653938Y1597612I-150J132D01*
G01Y1599554D01*
G03X653888Y1599686I-200J0D01*
G02Y1602598I1664J1456D01*
G03X653938Y1602730I-150J132D01*
G01Y1603352D01*
G02X654141Y1603554I203J-1D01*
G37*
G36*
G01X688787D02*
X691607D01*
G02X691810Y1603352I1J-202D01*
G01Y1602730D01*
G03X691860Y1602598I200J0D01*
G02Y1599686I-1664J-1456D01*
G03X691810Y1599554I150J-132D01*
G01Y1597612D01*
G03X691860Y1597480I200J0D01*
G02Y1594568I-1664J-1456D01*
G03X691810Y1594436I150J-132D01*
G01Y1593814D01*
G02X691607Y1593612I-203J1D01*
G01X688787D01*
G02X688584Y1593814I-1J202D01*
G01Y1594436D01*
G03X688534Y1594568I-200J0D01*
G02Y1597480I1664J1456D01*
G03X688584Y1597612I-150J132D01*
G01Y1599554D01*
G03X688534Y1599686I-200J0D01*
G02Y1602598I1664J1456D01*
G03X688584Y1602730I-150J132D01*
G01Y1603352D01*
G02X688787Y1603554I203J-1D01*
G37*
G36*
G01X1139101D02*
X1141921D01*
G02X1142124Y1603352I1J-202D01*
G01Y1602730D01*
G03X1142174Y1602598I200J0D01*
G02Y1599686I-1664J-1456D01*
G03X1142124Y1599554I150J-132D01*
G01Y1597612D01*
G03X1142174Y1597480I200J0D01*
G02Y1594568I-1664J-1456D01*
G03X1142124Y1594436I150J-132D01*
G01Y1593814D01*
G02X1141921Y1593612I-203J1D01*
G01X1139101D01*
G02X1138898Y1593814I-1J202D01*
G01Y1594436D01*
G03X1138848Y1594568I-200J0D01*
G02Y1597480I1664J1456D01*
G03X1138898Y1597612I-150J132D01*
G01Y1599554D01*
G03X1138848Y1599686I-200J0D01*
G02Y1602598I1664J1456D01*
G03X1138898Y1602730I-150J132D01*
G01Y1603352D01*
G02X1139101Y1603554I203J-1D01*
G37*
G36*
G01X1173747D02*
X1176567D01*
G02X1176770Y1603352I1J-202D01*
G01Y1602730D01*
G03X1176820Y1602598I200J0D01*
G02Y1599686I-1664J-1456D01*
G03X1176770Y1599554I150J-132D01*
G01Y1597612D01*
G03X1176820Y1597480I200J0D01*
G02Y1594568I-1664J-1456D01*
G03X1176770Y1594436I150J-132D01*
G01Y1593814D01*
G02X1176567Y1593612I-203J1D01*
G01X1173747D01*
G02X1173544Y1593814I-1J202D01*
G01Y1594436D01*
G03X1173494Y1594568I-200J0D01*
G02Y1597480I1664J1456D01*
G03X1173544Y1597612I-150J132D01*
G01Y1599554D01*
G03X1173494Y1599686I-200J0D01*
G02Y1602598I1664J1456D01*
G03X1173544Y1602730I-150J132D01*
G01Y1603352D01*
G02X1173747Y1603554I203J-1D01*
G37*
G36*
G01X1329653D02*
X1332473D01*
G02X1332676Y1603352I1J-202D01*
G01Y1602730D01*
G03X1332726Y1602598I200J0D01*
G02Y1599686I-1664J-1456D01*
G03X1332676Y1599554I150J-132D01*
G01Y1597612D01*
G03X1332726Y1597480I200J0D01*
G02Y1594568I-1664J-1456D01*
G03X1332676Y1594436I150J-132D01*
G01Y1593814D01*
G02X1332473Y1593612I-203J1D01*
G01X1329653D01*
G02X1329450Y1593814I-1J202D01*
G01Y1594436D01*
G03X1329400Y1594568I-200J0D01*
G02Y1597480I1664J1456D01*
G03X1329450Y1597612I-150J132D01*
G01Y1599554D01*
G03X1329400Y1599686I-200J0D01*
G02Y1602598I1664J1456D01*
G03X1329450Y1602730I-150J132D01*
G01Y1603352D01*
G02X1329653Y1603554I203J-1D01*
G37*
G36*
G01X1364299D02*
X1367119D01*
G02X1367322Y1603352I1J-202D01*
G01Y1602730D01*
G03X1367372Y1602598I200J0D01*
G02Y1599686I-1664J-1456D01*
G03X1367322Y1599554I150J-132D01*
G01Y1597612D01*
G03X1367372Y1597480I200J0D01*
G02Y1594568I-1664J-1456D01*
G03X1367322Y1594436I150J-132D01*
G01Y1593814D01*
G02X1367119Y1593612I-203J1D01*
G01X1364299D01*
G02X1364096Y1593814I-1J202D01*
G01Y1594436D01*
G03X1364046Y1594568I-200J0D01*
G02Y1597480I1664J1456D01*
G03X1364096Y1597612I-150J132D01*
G01Y1599554D01*
G03X1364046Y1599686I-200J0D01*
G02Y1602598I1664J1456D01*
G03X1364096Y1602730I-150J132D01*
G01Y1603352D01*
G02X1364299Y1603554I203J-1D01*
G37*
G36*
G01X1676109D02*
X1678929D01*
G02X1679132Y1603352I1J-202D01*
G01Y1602730D01*
G03X1679182Y1602598I200J0D01*
G02Y1599686I-1664J-1456D01*
G03X1679132Y1599554I150J-132D01*
G01Y1597612D01*
G03X1679182Y1597480I200J0D01*
G02Y1594568I-1664J-1456D01*
G03X1679132Y1594436I150J-132D01*
G01Y1593814D01*
G02X1678929Y1593612I-203J1D01*
G01X1676109D01*
G02X1675906Y1593814I-1J202D01*
G01Y1594436D01*
G03X1675856Y1594568I-200J0D01*
G02Y1597480I1664J1456D01*
G03X1675906Y1597612I-150J132D01*
G01Y1599554D01*
G03X1675856Y1599686I-200J0D01*
G02Y1602598I1664J1456D01*
G03X1675906Y1602730I-150J132D01*
G01Y1603352D01*
G02X1676109Y1603554I203J-1D01*
G37*
G36*
G01X1710755D02*
X1713575D01*
G02X1713778Y1603352I1J-202D01*
G01Y1602730D01*
G03X1713828Y1602598I200J0D01*
G02Y1599686I-1664J-1456D01*
G03X1713778Y1599554I150J-132D01*
G01Y1597612D01*
G03X1713828Y1597480I200J0D01*
G02Y1594568I-1664J-1456D01*
G03X1713778Y1594436I150J-132D01*
G01Y1593814D01*
G02X1713575Y1593612I-203J1D01*
G01X1710755D01*
G02X1710552Y1593814I-1J202D01*
G01Y1594436D01*
G03X1710502Y1594568I-200J0D01*
G02Y1597480I1664J1456D01*
G03X1710552Y1597612I-150J132D01*
G01Y1599554D01*
G03X1710502Y1599686I-200J0D01*
G02Y1602598I1664J1456D01*
G03X1710552Y1602730I-150J132D01*
G01Y1603352D01*
G02X1710755Y1603554I203J-1D01*
G37*
G36*
G01X108472Y1614578D02*
X111292D01*
G02X111494Y1614376I0J-202D01*
G01Y1613756D01*
G03X111544Y1613624I200J0D01*
G02Y1610708I-1661J-1458D01*
G03X111494Y1610576I150J-132D01*
G01Y1608638D01*
G03X111544Y1608506I200J0D01*
G02Y1605590I-1661J-1458D01*
G03X111494Y1605458I150J-132D01*
G01Y1604838D01*
G02X111292Y1604636I-202J0D01*
G01X108472D01*
G02X108270Y1604838I0J202D01*
G01Y1605458D01*
G03X108220Y1605590I-200J0D01*
G02Y1608506I1661J1458D01*
G03X108270Y1608638I-150J132D01*
G01Y1610576D01*
G03X108220Y1610708I-200J0D01*
G02Y1613624I1661J1458D01*
G03X108270Y1613756I-150J132D01*
G01Y1614376D01*
G02X108472Y1614578I202J0D01*
G37*
G36*
G01X143118D02*
X145938D01*
G02X146140Y1614376I0J-202D01*
G01Y1613756D01*
G03X146190Y1613624I200J0D01*
G02Y1610708I-1661J-1458D01*
G03X146140Y1610576I150J-132D01*
G01Y1608638D01*
G03X146190Y1608506I200J0D01*
G02Y1605590I-1661J-1458D01*
G03X146140Y1605458I150J-132D01*
G01Y1604838D01*
G02X145938Y1604636I-202J0D01*
G01X143118D01*
G02X142916Y1604838I0J202D01*
G01Y1605458D01*
G03X142866Y1605590I-200J0D01*
G02Y1608506I1661J1458D01*
G03X142916Y1608638I-150J132D01*
G01Y1610576D01*
G03X142866Y1610708I-200J0D01*
G02Y1613624I1661J1458D01*
G03X142916Y1613756I-150J132D01*
G01Y1614376D01*
G02X143118Y1614578I202J0D01*
G37*
G36*
G01X160440D02*
X163260D01*
G02X163462Y1614376I0J-202D01*
G01Y1613756D01*
G03X163512Y1613624I200J0D01*
G02Y1610708I-1661J-1458D01*
G03X163462Y1610576I150J-132D01*
G01Y1608638D01*
G03X163512Y1608506I200J0D01*
G02Y1605590I-1661J-1458D01*
G03X163462Y1605458I150J-132D01*
G01Y1604838D01*
G02X163260Y1604636I-202J0D01*
G01X160440D01*
G02X160238Y1604838I0J202D01*
G01Y1605458D01*
G03X160188Y1605590I-200J0D01*
G02Y1608506I1661J1458D01*
G03X160238Y1608638I-150J132D01*
G01Y1610576D01*
G03X160188Y1610708I-200J0D01*
G02Y1613624I1661J1458D01*
G03X160238Y1613756I-150J132D01*
G01Y1614376D01*
G02X160440Y1614578I202J0D01*
G37*
G36*
G01X281700D02*
X284520D01*
G02X284722Y1614376I0J-202D01*
G01Y1613756D01*
G03X284772Y1613624I200J0D01*
G02Y1610708I-1661J-1458D01*
G03X284722Y1610576I150J-132D01*
G01Y1608638D01*
G03X284772Y1608506I200J0D01*
G02Y1605590I-1661J-1458D01*
G03X284722Y1605458I150J-132D01*
G01Y1604838D01*
G02X284520Y1604636I-202J0D01*
G01X281700D01*
G02X281498Y1604838I0J202D01*
G01Y1605458D01*
G03X281448Y1605590I-200J0D01*
G02Y1608506I1661J1458D01*
G03X281498Y1608638I-150J132D01*
G01Y1610576D01*
G03X281448Y1610708I-200J0D01*
G02Y1613624I1661J1458D01*
G03X281498Y1613756I-150J132D01*
G01Y1614376D01*
G02X281700Y1614578I202J0D01*
G37*
G36*
G01X316346D02*
X319166D01*
G02X319368Y1614376I0J-202D01*
G01Y1613756D01*
G03X319418Y1613624I200J0D01*
G02Y1610708I-1661J-1458D01*
G03X319368Y1610576I150J-132D01*
G01Y1608638D01*
G03X319418Y1608506I200J0D01*
G02Y1605590I-1661J-1458D01*
G03X319368Y1605458I150J-132D01*
G01Y1604838D01*
G02X319166Y1604636I-202J0D01*
G01X316346D01*
G02X316144Y1604838I0J202D01*
G01Y1605458D01*
G03X316094Y1605590I-200J0D01*
G02Y1608506I1661J1458D01*
G03X316144Y1608638I-150J132D01*
G01Y1610576D01*
G03X316094Y1610708I-200J0D01*
G02Y1613624I1661J1458D01*
G03X316144Y1613756I-150J132D01*
G01Y1614376D01*
G02X316346Y1614578I202J0D01*
G37*
G36*
G01X333668D02*
X336488D01*
G02X336690Y1614376I0J-202D01*
G01Y1613756D01*
G03X336740Y1613624I200J0D01*
G02Y1610708I-1661J-1458D01*
G03X336690Y1610576I150J-132D01*
G01Y1608638D01*
G03X336740Y1608506I200J0D01*
G02Y1605590I-1661J-1458D01*
G03X336690Y1605458I150J-132D01*
G01Y1604838D01*
G02X336488Y1604636I-202J0D01*
G01X333668D01*
G02X333466Y1604838I0J202D01*
G01Y1605458D01*
G03X333416Y1605590I-200J0D01*
G02Y1608506I1661J1458D01*
G03X333466Y1608638I-150J132D01*
G01Y1610576D01*
G03X333416Y1610708I-200J0D01*
G02Y1613624I1661J1458D01*
G03X333466Y1613756I-150J132D01*
G01Y1614376D01*
G02X333668Y1614578I202J0D01*
G37*
G36*
G01X645480D02*
X648300D01*
G02X648502Y1614376I0J-202D01*
G01Y1613756D01*
G03X648552Y1613624I200J0D01*
G02Y1610708I-1661J-1458D01*
G03X648502Y1610576I150J-132D01*
G01Y1608638D01*
G03X648552Y1608506I200J0D01*
G02Y1605590I-1661J-1458D01*
G03X648502Y1605458I150J-132D01*
G01Y1604838D01*
G02X648300Y1604636I-202J0D01*
G01X645480D01*
G02X645278Y1604838I0J202D01*
G01Y1605458D01*
G03X645228Y1605590I-200J0D01*
G02Y1608506I1661J1458D01*
G03X645278Y1608638I-150J132D01*
G01Y1610576D01*
G03X645228Y1610708I-200J0D01*
G02Y1613624I1661J1458D01*
G03X645278Y1613756I-150J132D01*
G01Y1614376D01*
G02X645480Y1614578I202J0D01*
G37*
G36*
G01X1130440D02*
X1133260D01*
G02X1133462Y1614376I0J-202D01*
G01Y1613756D01*
G03X1133512Y1613624I200J0D01*
G02Y1610708I-1661J-1458D01*
G03X1133462Y1610576I150J-132D01*
G01Y1608638D01*
G03X1133512Y1608506I200J0D01*
G02Y1605590I-1661J-1458D01*
G03X1133462Y1605458I150J-132D01*
G01Y1604838D01*
G02X1133260Y1604636I-202J0D01*
G01X1130440D01*
G02X1130238Y1604838I0J202D01*
G01Y1605458D01*
G03X1130188Y1605590I-200J0D01*
G02Y1608506I1661J1458D01*
G03X1130238Y1608638I-150J132D01*
G01Y1610576D01*
G03X1130188Y1610708I-200J0D01*
G02Y1613624I1661J1458D01*
G03X1130238Y1613756I-150J132D01*
G01Y1614376D01*
G02X1130440Y1614578I202J0D01*
G37*
G36*
G01X1165086D02*
X1167906D01*
G02X1168108Y1614376I0J-202D01*
G01Y1613756D01*
G03X1168158Y1613624I200J0D01*
G02Y1610708I-1661J-1458D01*
G03X1168108Y1610576I150J-132D01*
G01Y1608638D01*
G03X1168158Y1608506I200J0D01*
G02Y1605590I-1661J-1458D01*
G03X1168108Y1605458I150J-132D01*
G01Y1604838D01*
G02X1167906Y1604636I-202J0D01*
G01X1165086D01*
G02X1164884Y1604838I0J202D01*
G01Y1605458D01*
G03X1164834Y1605590I-200J0D01*
G02Y1608506I1661J1458D01*
G03X1164884Y1608638I-150J132D01*
G01Y1610576D01*
G03X1164834Y1610708I-200J0D01*
G02Y1613624I1661J1458D01*
G03X1164884Y1613756I-150J132D01*
G01Y1614376D01*
G02X1165086Y1614578I202J0D01*
G37*
G36*
G01X1182408D02*
X1185228D01*
G02X1185430Y1614376I0J-202D01*
G01Y1613756D01*
G03X1185480Y1613624I200J0D01*
G02Y1610708I-1661J-1458D01*
G03X1185430Y1610576I150J-132D01*
G01Y1608638D01*
G03X1185480Y1608506I200J0D01*
G02Y1605590I-1661J-1458D01*
G03X1185430Y1605458I150J-132D01*
G01Y1604838D01*
G02X1185228Y1604636I-202J0D01*
G01X1182408D01*
G02X1182206Y1604838I0J202D01*
G01Y1605458D01*
G03X1182156Y1605590I-200J0D01*
G02Y1608506I1661J1458D01*
G03X1182206Y1608638I-150J132D01*
G01Y1610576D01*
G03X1182156Y1610708I-200J0D01*
G02Y1613624I1661J1458D01*
G03X1182206Y1613756I-150J132D01*
G01Y1614376D01*
G02X1182408Y1614578I202J0D01*
G37*
G36*
G01X1320992D02*
X1323812D01*
G02X1324014Y1614376I0J-202D01*
G01Y1613756D01*
G03X1324064Y1613624I200J0D01*
G02Y1610708I-1661J-1458D01*
G03X1324014Y1610576I150J-132D01*
G01Y1608638D01*
G03X1324064Y1608506I200J0D01*
G02Y1605590I-1661J-1458D01*
G03X1324014Y1605458I150J-132D01*
G01Y1604838D01*
G02X1323812Y1604636I-202J0D01*
G01X1320992D01*
G02X1320790Y1604838I0J202D01*
G01Y1605458D01*
G03X1320740Y1605590I-200J0D01*
G02Y1608506I1661J1458D01*
G03X1320790Y1608638I-150J132D01*
G01Y1610576D01*
G03X1320740Y1610708I-200J0D01*
G02Y1613624I1661J1458D01*
G03X1320790Y1613756I-150J132D01*
G01Y1614376D01*
G02X1320992Y1614578I202J0D01*
G37*
G36*
G01X1667448D02*
X1670268D01*
G02X1670470Y1614376I0J-202D01*
G01Y1613756D01*
G03X1670520Y1613624I200J0D01*
G02Y1610708I-1661J-1458D01*
G03X1670470Y1610576I150J-132D01*
G01Y1608638D01*
G03X1670520Y1608506I200J0D01*
G02Y1605590I-1661J-1458D01*
G03X1670470Y1605458I150J-132D01*
G01Y1604838D01*
G02X1670268Y1604636I-202J0D01*
G01X1667448D01*
G02X1667246Y1604838I0J202D01*
G01Y1605458D01*
G03X1667196Y1605590I-200J0D01*
G02Y1608506I1661J1458D01*
G03X1667246Y1608638I-150J132D01*
G01Y1610576D01*
G03X1667196Y1610708I-200J0D01*
G02Y1613624I1661J1458D01*
G03X1667246Y1613756I-150J132D01*
G01Y1614376D01*
G02X1667448Y1614578I202J0D01*
G37*
G36*
G01X125795D02*
X128615D01*
G02X128818Y1614376I1J-202D01*
G01Y1613754D01*
G03X128868Y1613622I200J0D01*
G02Y1610710I-1664J-1456D01*
G03X128818Y1610578I150J-132D01*
G01Y1608636D01*
G03X128868Y1608504I200J0D01*
G02Y1605592I-1664J-1456D01*
G03X128818Y1605460I150J-132D01*
G01Y1604838D01*
G02X128615Y1604636I-203J1D01*
G01X125795D01*
G02X125592Y1604838I-1J202D01*
G01Y1605460D01*
G03X125542Y1605592I-200J0D01*
G02Y1608504I1664J1456D01*
G03X125592Y1608636I-150J132D01*
G01Y1610578D01*
G03X125542Y1610710I-200J0D01*
G02Y1613622I1664J1456D01*
G03X125592Y1613754I-150J132D01*
G01Y1614376D01*
G02X125795Y1614578I203J-1D01*
G37*
G36*
G01X299023D02*
X301843D01*
G02X302046Y1614376I1J-202D01*
G01Y1613754D01*
G03X302096Y1613622I200J0D01*
G02Y1610710I-1664J-1456D01*
G03X302046Y1610578I150J-132D01*
G01Y1608636D01*
G03X302096Y1608504I200J0D01*
G02Y1605592I-1664J-1456D01*
G03X302046Y1605460I150J-132D01*
G01Y1604838D01*
G02X301843Y1604636I-203J1D01*
G01X299023D01*
G02X298820Y1604838I-1J202D01*
G01Y1605460D01*
G03X298770Y1605592I-200J0D01*
G02Y1608504I1664J1456D01*
G03X298820Y1608636I-150J132D01*
G01Y1610578D01*
G03X298770Y1610710I-200J0D01*
G02Y1613622I1664J1456D01*
G03X298820Y1613754I-150J132D01*
G01Y1614376D01*
G02X299023Y1614578I203J-1D01*
G37*
G36*
G01X628157D02*
X630977D01*
G02X631180Y1614376I1J-202D01*
G01Y1613754D01*
G03X631230Y1613622I200J0D01*
G02Y1610710I-1664J-1456D01*
G03X631180Y1610578I150J-132D01*
G01Y1608636D01*
G03X631230Y1608504I200J0D01*
G02Y1605592I-1664J-1456D01*
G03X631180Y1605460I150J-132D01*
G01Y1604838D01*
G02X630977Y1604636I-203J1D01*
G01X628157D01*
G02X627954Y1604838I-1J202D01*
G01Y1605460D01*
G03X627904Y1605592I-200J0D01*
G02Y1608504I1664J1456D01*
G03X627954Y1608636I-150J132D01*
G01Y1610578D01*
G03X627904Y1610710I-200J0D01*
G02Y1613622I1664J1456D01*
G03X627954Y1613754I-150J132D01*
G01Y1614376D01*
G02X628157Y1614578I203J-1D01*
G37*
G36*
G01X662803D02*
X665623D01*
G02X665826Y1614376I1J-202D01*
G01Y1613754D01*
G03X665876Y1613622I200J0D01*
G02Y1610710I-1664J-1456D01*
G03X665826Y1610578I150J-132D01*
G01Y1608636D01*
G03X665876Y1608504I200J0D01*
G02Y1605592I-1664J-1456D01*
G03X665826Y1605460I150J-132D01*
G01Y1604838D01*
G02X665623Y1604636I-203J1D01*
G01X662803D01*
G02X662600Y1604838I-1J202D01*
G01Y1605460D01*
G03X662550Y1605592I-200J0D01*
G02Y1608504I1664J1456D01*
G03X662600Y1608636I-150J132D01*
G01Y1610578D01*
G03X662550Y1610710I-200J0D01*
G02Y1613622I1664J1456D01*
G03X662600Y1613754I-150J132D01*
G01Y1614376D01*
G02X662803Y1614578I203J-1D01*
G37*
G36*
G01X680125D02*
X682945D01*
G02X683148Y1614376I1J-202D01*
G01Y1613754D01*
G03X683198Y1613622I200J0D01*
G02Y1610710I-1664J-1456D01*
G03X683148Y1610578I150J-132D01*
G01Y1608636D01*
G03X683198Y1608504I200J0D01*
G02Y1605592I-1664J-1456D01*
G03X683148Y1605460I150J-132D01*
G01Y1604838D01*
G02X682945Y1604636I-203J1D01*
G01X680125D01*
G02X679922Y1604838I-1J202D01*
G01Y1605460D01*
G03X679872Y1605592I-200J0D01*
G02Y1608504I1664J1456D01*
G03X679922Y1608636I-150J132D01*
G01Y1610578D01*
G03X679872Y1610710I-200J0D01*
G02Y1613622I1664J1456D01*
G03X679922Y1613754I-150J132D01*
G01Y1614376D01*
G02X680125Y1614578I203J-1D01*
G37*
G36*
G01X1147763D02*
X1150583D01*
G02X1150786Y1614376I1J-202D01*
G01Y1613754D01*
G03X1150836Y1613622I200J0D01*
G02Y1610710I-1664J-1456D01*
G03X1150786Y1610578I150J-132D01*
G01Y1608636D01*
G03X1150836Y1608504I200J0D01*
G02Y1605592I-1664J-1456D01*
G03X1150786Y1605460I150J-132D01*
G01Y1604838D01*
G02X1150583Y1604636I-203J1D01*
G01X1147763D01*
G02X1147560Y1604838I-1J202D01*
G01Y1605460D01*
G03X1147510Y1605592I-200J0D01*
G02Y1608504I1664J1456D01*
G03X1147560Y1608636I-150J132D01*
G01Y1610578D01*
G03X1147510Y1610710I-200J0D01*
G02Y1613622I1664J1456D01*
G03X1147560Y1613754I-150J132D01*
G01Y1614376D01*
G02X1147763Y1614578I203J-1D01*
G37*
G36*
G01X1303669D02*
X1306489D01*
G02X1306692Y1614376I1J-202D01*
G01Y1613754D01*
G03X1306742Y1613622I200J0D01*
G02Y1610710I-1664J-1456D01*
G03X1306692Y1610578I150J-132D01*
G01Y1608636D01*
G03X1306742Y1608504I200J0D01*
G02Y1605592I-1664J-1456D01*
G03X1306692Y1605460I150J-132D01*
G01Y1604838D01*
G02X1306489Y1604636I-203J1D01*
G01X1303669D01*
G02X1303466Y1604838I-1J202D01*
G01Y1605460D01*
G03X1303416Y1605592I-200J0D01*
G02Y1608504I1664J1456D01*
G03X1303466Y1608636I-150J132D01*
G01Y1610578D01*
G03X1303416Y1610710I-200J0D01*
G02Y1613622I1664J1456D01*
G03X1303466Y1613754I-150J132D01*
G01Y1614376D01*
G02X1303669Y1614578I203J-1D01*
G37*
G36*
G01X1338315D02*
X1341135D01*
G02X1341338Y1614376I1J-202D01*
G01Y1613754D01*
G03X1341388Y1613622I200J0D01*
G02Y1610710I-1664J-1456D01*
G03X1341338Y1610578I150J-132D01*
G01Y1608636D01*
G03X1341388Y1608504I200J0D01*
G02Y1605592I-1664J-1456D01*
G03X1341338Y1605460I150J-132D01*
G01Y1604838D01*
G02X1341135Y1604636I-203J1D01*
G01X1338315D01*
G02X1338112Y1604838I-1J202D01*
G01Y1605460D01*
G03X1338062Y1605592I-200J0D01*
G02Y1608504I1664J1456D01*
G03X1338112Y1608636I-150J132D01*
G01Y1610578D01*
G03X1338062Y1610710I-200J0D01*
G02Y1613622I1664J1456D01*
G03X1338112Y1613754I-150J132D01*
G01Y1614376D01*
G02X1338315Y1614578I203J-1D01*
G37*
G36*
G01X1355637D02*
X1358457D01*
G02X1358660Y1614376I1J-202D01*
G01Y1613754D01*
G03X1358710Y1613622I200J0D01*
G02Y1610710I-1664J-1456D01*
G03X1358660Y1610578I150J-132D01*
G01Y1608636D01*
G03X1358710Y1608504I200J0D01*
G02Y1605592I-1664J-1456D01*
G03X1358660Y1605460I150J-132D01*
G01Y1604838D01*
G02X1358457Y1604636I-203J1D01*
G01X1355637D01*
G02X1355434Y1604838I-1J202D01*
G01Y1605460D01*
G03X1355384Y1605592I-200J0D01*
G02Y1608504I1664J1456D01*
G03X1355434Y1608636I-150J132D01*
G01Y1610578D01*
G03X1355384Y1610710I-200J0D01*
G02Y1613622I1664J1456D01*
G03X1355434Y1613754I-150J132D01*
G01Y1614376D01*
G02X1355637Y1614578I203J-1D01*
G37*
G36*
G01X1476897D02*
X1479717D01*
G02X1479920Y1614376I1J-202D01*
G01Y1613754D01*
G03X1479970Y1613622I200J0D01*
G02Y1610710I-1664J-1456D01*
G03X1479920Y1610578I150J-132D01*
G01Y1608636D01*
G03X1479970Y1608504I200J0D01*
G02Y1605592I-1664J-1456D01*
G03X1479920Y1605460I150J-132D01*
G01Y1604838D01*
G02X1479717Y1604636I-203J1D01*
G01X1476897D01*
G02X1476694Y1604838I-1J202D01*
G01Y1605460D01*
G03X1476644Y1605592I-200J0D01*
G02Y1608504I1664J1456D01*
G03X1476694Y1608636I-150J132D01*
G01Y1610578D01*
G03X1476644Y1610710I-200J0D01*
G02Y1613622I1664J1456D01*
G03X1476694Y1613754I-150J132D01*
G01Y1614376D01*
G02X1476897Y1614578I203J-1D01*
G37*
G36*
G01X1650125D02*
X1652945D01*
G02X1653148Y1614376I1J-202D01*
G01Y1613754D01*
G03X1653198Y1613622I200J0D01*
G02Y1610710I-1664J-1456D01*
G03X1653148Y1610578I150J-132D01*
G01Y1608636D01*
G03X1653198Y1608504I200J0D01*
G02Y1605592I-1664J-1456D01*
G03X1653148Y1605460I150J-132D01*
G01Y1604838D01*
G02X1652945Y1604636I-203J1D01*
G01X1650125D01*
G02X1649922Y1604838I-1J202D01*
G01Y1605460D01*
G03X1649872Y1605592I-200J0D01*
G02Y1608504I1664J1456D01*
G03X1649922Y1608636I-150J132D01*
G01Y1610578D01*
G03X1649872Y1610710I-200J0D01*
G02Y1613622I1664J1456D01*
G03X1649922Y1613754I-150J132D01*
G01Y1614376D01*
G02X1650125Y1614578I203J-1D01*
G37*
G36*
G01X1684771D02*
X1687591D01*
G02X1687794Y1614376I1J-202D01*
G01Y1613754D01*
G03X1687844Y1613622I200J0D01*
G02Y1610710I-1664J-1456D01*
G03X1687794Y1610578I150J-132D01*
G01Y1608636D01*
G03X1687844Y1608504I200J0D01*
G02Y1605592I-1664J-1456D01*
G03X1687794Y1605460I150J-132D01*
G01Y1604838D01*
G02X1687591Y1604636I-203J1D01*
G01X1684771D01*
G02X1684568Y1604838I-1J202D01*
G01Y1605460D01*
G03X1684518Y1605592I-200J0D01*
G02Y1608504I1664J1456D01*
G03X1684568Y1608636I-150J132D01*
G01Y1610578D01*
G03X1684518Y1610710I-200J0D01*
G02Y1613622I1664J1456D01*
G03X1684568Y1613754I-150J132D01*
G01Y1614376D01*
G02X1684771Y1614578I203J-1D01*
G37*
G36*
G01X1702093D02*
X1704913D01*
G02X1705116Y1614376I1J-202D01*
G01Y1613754D01*
G03X1705166Y1613622I200J0D01*
G02Y1610710I-1664J-1456D01*
G03X1705116Y1610578I150J-132D01*
G01Y1608636D01*
G03X1705166Y1608504I200J0D01*
G02Y1605592I-1664J-1456D01*
G03X1705116Y1605460I150J-132D01*
G01Y1604838D01*
G02X1704913Y1604636I-203J1D01*
G01X1702093D01*
G02X1701890Y1604838I-1J202D01*
G01Y1605460D01*
G03X1701840Y1605592I-200J0D01*
G02Y1608504I1664J1456D01*
G03X1701890Y1608636I-150J132D01*
G01Y1610578D01*
G03X1701840Y1610710I-200J0D01*
G02Y1613622I1664J1456D01*
G03X1701890Y1613754I-150J132D01*
G01Y1614376D01*
G02X1702093Y1614578I203J-1D01*
G37*
G36*
G01X134456Y1618908D02*
X137276D01*
G02X137478Y1618706I0J-202D01*
G01Y1618086D01*
G03X137528Y1617954I200J0D01*
G02Y1615038I-1661J-1458D01*
G03X137478Y1614906I150J-132D01*
G01Y1612968D01*
G03X137528Y1612836I200J0D01*
G02Y1609920I-1661J-1458D01*
G03X137478Y1609788I150J-132D01*
G01Y1609168D01*
G02X137276Y1608966I-202J0D01*
G01X134456D01*
G02X134254Y1609168I0J202D01*
G01Y1609788D01*
G03X134204Y1609920I-200J0D01*
G02Y1612836I1661J1458D01*
G03X134254Y1612968I-150J132D01*
G01Y1614906D01*
G03X134204Y1615038I-200J0D01*
G02Y1617954I1661J1458D01*
G03X134254Y1618086I-150J132D01*
G01Y1618706D01*
G02X134456Y1618908I202J0D01*
G37*
G36*
G01X169102D02*
X171922D01*
G02X172124Y1618706I0J-202D01*
G01Y1618086D01*
G03X172174Y1617954I200J0D01*
G02Y1615038I-1661J-1458D01*
G03X172124Y1614906I150J-132D01*
G01Y1612968D01*
G03X172174Y1612836I200J0D01*
G02Y1609920I-1661J-1458D01*
G03X172124Y1609788I150J-132D01*
G01Y1609168D01*
G02X171922Y1608966I-202J0D01*
G01X169102D01*
G02X168900Y1609168I0J202D01*
G01Y1609788D01*
G03X168850Y1609920I-200J0D01*
G02Y1612836I1661J1458D01*
G03X168900Y1612968I-150J132D01*
G01Y1614906D01*
G03X168850Y1615038I-200J0D01*
G02Y1617954I1661J1458D01*
G03X168900Y1618086I-150J132D01*
G01Y1618706D01*
G02X169102Y1618908I202J0D01*
G37*
G36*
G01X307684D02*
X310504D01*
G02X310706Y1618706I0J-202D01*
G01Y1618086D01*
G03X310756Y1617954I200J0D01*
G02Y1615038I-1661J-1458D01*
G03X310706Y1614906I150J-132D01*
G01Y1612968D01*
G03X310756Y1612836I200J0D01*
G02Y1609920I-1661J-1458D01*
G03X310706Y1609788I150J-132D01*
G01Y1609168D01*
G02X310504Y1608966I-202J0D01*
G01X307684D01*
G02X307482Y1609168I0J202D01*
G01Y1609788D01*
G03X307432Y1609920I-200J0D01*
G02Y1612836I1661J1458D01*
G03X307482Y1612968I-150J132D01*
G01Y1614906D01*
G03X307432Y1615038I-200J0D01*
G02Y1617954I1661J1458D01*
G03X307482Y1618086I-150J132D01*
G01Y1618706D01*
G02X307684Y1618908I202J0D01*
G37*
G36*
G01X342330D02*
X345150D01*
G02X345352Y1618706I0J-202D01*
G01Y1618086D01*
G03X345402Y1617954I200J0D01*
G02Y1615038I-1661J-1458D01*
G03X345352Y1614906I150J-132D01*
G01Y1612968D01*
G03X345402Y1612836I200J0D01*
G02Y1609920I-1661J-1458D01*
G03X345352Y1609788I150J-132D01*
G01Y1609168D01*
G02X345150Y1608966I-202J0D01*
G01X342330D01*
G02X342128Y1609168I0J202D01*
G01Y1609788D01*
G03X342078Y1609920I-200J0D01*
G02Y1612836I1661J1458D01*
G03X342128Y1612968I-150J132D01*
G01Y1614906D01*
G03X342078Y1615038I-200J0D01*
G02Y1617954I1661J1458D01*
G03X342128Y1618086I-150J132D01*
G01Y1618706D01*
G02X342330Y1618908I202J0D01*
G37*
G36*
G01X636818D02*
X639638D01*
G02X639840Y1618706I0J-202D01*
G01Y1618086D01*
G03X639890Y1617954I200J0D01*
G02Y1615038I-1661J-1458D01*
G03X639840Y1614906I150J-132D01*
G01Y1612968D01*
G03X639890Y1612836I200J0D01*
G02Y1609920I-1661J-1458D01*
G03X639840Y1609788I150J-132D01*
G01Y1609168D01*
G02X639638Y1608966I-202J0D01*
G01X636818D01*
G02X636616Y1609168I0J202D01*
G01Y1609788D01*
G03X636566Y1609920I-200J0D01*
G02Y1612836I1661J1458D01*
G03X636616Y1612968I-150J132D01*
G01Y1614906D01*
G03X636566Y1615038I-200J0D01*
G02Y1617954I1661J1458D01*
G03X636616Y1618086I-150J132D01*
G01Y1618706D01*
G02X636818Y1618908I202J0D01*
G37*
G36*
G01X671464D02*
X674284D01*
G02X674486Y1618706I0J-202D01*
G01Y1618086D01*
G03X674536Y1617954I200J0D01*
G02Y1615038I-1661J-1458D01*
G03X674486Y1614906I150J-132D01*
G01Y1612968D01*
G03X674536Y1612836I200J0D01*
G02Y1609920I-1661J-1458D01*
G03X674486Y1609788I150J-132D01*
G01Y1609168D01*
G02X674284Y1608966I-202J0D01*
G01X671464D01*
G02X671262Y1609168I0J202D01*
G01Y1609788D01*
G03X671212Y1609920I-200J0D01*
G02Y1612836I1661J1458D01*
G03X671262Y1612968I-150J132D01*
G01Y1614906D01*
G03X671212Y1615038I-200J0D01*
G02Y1617954I1661J1458D01*
G03X671262Y1618086I-150J132D01*
G01Y1618706D01*
G02X671464Y1618908I202J0D01*
G37*
G36*
G01X1156424D02*
X1159244D01*
G02X1159446Y1618706I0J-202D01*
G01Y1618086D01*
G03X1159496Y1617954I200J0D01*
G02Y1615038I-1661J-1458D01*
G03X1159446Y1614906I150J-132D01*
G01Y1612968D01*
G03X1159496Y1612836I200J0D01*
G02Y1609920I-1661J-1458D01*
G03X1159446Y1609788I150J-132D01*
G01Y1609168D01*
G02X1159244Y1608966I-202J0D01*
G01X1156424D01*
G02X1156222Y1609168I0J202D01*
G01Y1609788D01*
G03X1156172Y1609920I-200J0D01*
G02Y1612836I1661J1458D01*
G03X1156222Y1612968I-150J132D01*
G01Y1614906D01*
G03X1156172Y1615038I-200J0D01*
G02Y1617954I1661J1458D01*
G03X1156222Y1618086I-150J132D01*
G01Y1618706D01*
G02X1156424Y1618908I202J0D01*
G37*
G36*
G01X1191070D02*
X1193890D01*
G02X1194092Y1618706I0J-202D01*
G01Y1618086D01*
G03X1194142Y1617954I200J0D01*
G02Y1615038I-1661J-1458D01*
G03X1194092Y1614906I150J-132D01*
G01Y1612968D01*
G03X1194142Y1612836I200J0D01*
G02Y1609920I-1661J-1458D01*
G03X1194092Y1609788I150J-132D01*
G01Y1609168D01*
G02X1193890Y1608966I-202J0D01*
G01X1191070D01*
G02X1190868Y1609168I0J202D01*
G01Y1609788D01*
G03X1190818Y1609920I-200J0D01*
G02Y1612836I1661J1458D01*
G03X1190868Y1612968I-150J132D01*
G01Y1614906D01*
G03X1190818Y1615038I-200J0D01*
G02Y1617954I1661J1458D01*
G03X1190868Y1618086I-150J132D01*
G01Y1618706D01*
G02X1191070Y1618908I202J0D01*
G37*
G36*
G01X1312330D02*
X1315150D01*
G02X1315352Y1618706I0J-202D01*
G01Y1618086D01*
G03X1315402Y1617954I200J0D01*
G02Y1615038I-1661J-1458D01*
G03X1315352Y1614906I150J-132D01*
G01Y1612968D01*
G03X1315402Y1612836I200J0D01*
G02Y1609920I-1661J-1458D01*
G03X1315352Y1609788I150J-132D01*
G01Y1609168D01*
G02X1315150Y1608966I-202J0D01*
G01X1312330D01*
G02X1312128Y1609168I0J202D01*
G01Y1609788D01*
G03X1312078Y1609920I-200J0D01*
G02Y1612836I1661J1458D01*
G03X1312128Y1612968I-150J132D01*
G01Y1614906D01*
G03X1312078Y1615038I-200J0D01*
G02Y1617954I1661J1458D01*
G03X1312128Y1618086I-150J132D01*
G01Y1618706D01*
G02X1312330Y1618908I202J0D01*
G37*
G36*
G01X1346976D02*
X1349796D01*
G02X1349998Y1618706I0J-202D01*
G01Y1618086D01*
G03X1350048Y1617954I200J0D01*
G02Y1615038I-1661J-1458D01*
G03X1349998Y1614906I150J-132D01*
G01Y1612968D01*
G03X1350048Y1612836I200J0D01*
G02Y1609920I-1661J-1458D01*
G03X1349998Y1609788I150J-132D01*
G01Y1609168D01*
G02X1349796Y1608966I-202J0D01*
G01X1346976D01*
G02X1346774Y1609168I0J202D01*
G01Y1609788D01*
G03X1346724Y1609920I-200J0D01*
G02Y1612836I1661J1458D01*
G03X1346774Y1612968I-150J132D01*
G01Y1614906D01*
G03X1346724Y1615038I-200J0D01*
G02Y1617954I1661J1458D01*
G03X1346774Y1618086I-150J132D01*
G01Y1618706D01*
G02X1346976Y1618908I202J0D01*
G37*
G36*
G01X1658786D02*
X1661606D01*
G02X1661808Y1618706I0J-202D01*
G01Y1618086D01*
G03X1661858Y1617954I200J0D01*
G02Y1615038I-1661J-1458D01*
G03X1661808Y1614906I150J-132D01*
G01Y1612968D01*
G03X1661858Y1612836I200J0D01*
G02Y1609920I-1661J-1458D01*
G03X1661808Y1609788I150J-132D01*
G01Y1609168D01*
G02X1661606Y1608966I-202J0D01*
G01X1658786D01*
G02X1658584Y1609168I0J202D01*
G01Y1609788D01*
G03X1658534Y1609920I-200J0D01*
G02Y1612836I1661J1458D01*
G03X1658584Y1612968I-150J132D01*
G01Y1614906D01*
G03X1658534Y1615038I-200J0D01*
G02Y1617954I1661J1458D01*
G03X1658584Y1618086I-150J132D01*
G01Y1618706D01*
G02X1658786Y1618908I202J0D01*
G37*
G36*
G01X1693432D02*
X1696252D01*
G02X1696454Y1618706I0J-202D01*
G01Y1618086D01*
G03X1696504Y1617954I200J0D01*
G02Y1615038I-1661J-1458D01*
G03X1696454Y1614906I150J-132D01*
G01Y1612968D01*
G03X1696504Y1612836I200J0D01*
G02Y1609920I-1661J-1458D01*
G03X1696454Y1609788I150J-132D01*
G01Y1609168D01*
G02X1696252Y1608966I-202J0D01*
G01X1693432D01*
G02X1693230Y1609168I0J202D01*
G01Y1609788D01*
G03X1693180Y1609920I-200J0D01*
G02Y1612836I1661J1458D01*
G03X1693230Y1612968I-150J132D01*
G01Y1614906D01*
G03X1693180Y1615038I-200J0D01*
G02Y1617954I1661J1458D01*
G03X1693230Y1618086I-150J132D01*
G01Y1618706D01*
G02X1693432Y1618908I202J0D01*
G37*
G36*
G01X117133D02*
X119953D01*
G02X120156Y1618706I1J-202D01*
G01Y1618084D01*
G03X120206Y1617952I200J0D01*
G02Y1615040I-1664J-1456D01*
G03X120156Y1614908I150J-132D01*
G01Y1612966D01*
G03X120206Y1612834I200J0D01*
G02Y1609922I-1664J-1456D01*
G03X120156Y1609790I150J-132D01*
G01Y1609168D01*
G02X119953Y1608966I-203J1D01*
G01X117133D01*
G02X116930Y1609168I-1J202D01*
G01Y1609790D01*
G03X116880Y1609922I-200J0D01*
G02Y1612834I1664J1456D01*
G03X116930Y1612966I-150J132D01*
G01Y1614908D01*
G03X116880Y1615040I-200J0D01*
G02Y1617952I1664J1456D01*
G03X116930Y1618084I-150J132D01*
G01Y1618706D01*
G02X117133Y1618908I203J-1D01*
G37*
G36*
G01X151779D02*
X154599D01*
G02X154802Y1618706I1J-202D01*
G01Y1618084D01*
G03X154852Y1617952I200J0D01*
G02Y1615040I-1664J-1456D01*
G03X154802Y1614908I150J-132D01*
G01Y1612966D01*
G03X154852Y1612834I200J0D01*
G02Y1609922I-1664J-1456D01*
G03X154802Y1609790I150J-132D01*
G01Y1609168D01*
G02X154599Y1608966I-203J1D01*
G01X151779D01*
G02X151576Y1609168I-1J202D01*
G01Y1609790D01*
G03X151526Y1609922I-200J0D01*
G02Y1612834I1664J1456D01*
G03X151576Y1612966I-150J132D01*
G01Y1614908D01*
G03X151526Y1615040I-200J0D01*
G02Y1617952I1664J1456D01*
G03X151576Y1618084I-150J132D01*
G01Y1618706D01*
G02X151779Y1618908I203J-1D01*
G37*
G36*
G01X186425D02*
X189245D01*
G02X189448Y1618706I1J-202D01*
G01Y1618084D01*
G03X189498Y1617952I200J0D01*
G02Y1615040I-1664J-1456D01*
G03X189448Y1614908I150J-132D01*
G01Y1612966D01*
G03X189498Y1612834I200J0D01*
G02Y1609922I-1664J-1456D01*
G03X189448Y1609790I150J-132D01*
G01Y1609168D01*
G02X189245Y1608966I-203J1D01*
G01X186425D01*
G02X186222Y1609168I-1J202D01*
G01Y1609790D01*
G03X186172Y1609922I-200J0D01*
G02Y1612834I1664J1456D01*
G03X186222Y1612966I-150J132D01*
G01Y1614908D01*
G03X186172Y1615040I-200J0D01*
G02Y1617952I1664J1456D01*
G03X186222Y1618084I-150J132D01*
G01Y1618706D01*
G02X186425Y1618908I203J-1D01*
G37*
G36*
G01X290361D02*
X293181D01*
G02X293384Y1618706I1J-202D01*
G01Y1618084D01*
G03X293434Y1617952I200J0D01*
G02Y1615040I-1664J-1456D01*
G03X293384Y1614908I150J-132D01*
G01Y1612966D01*
G03X293434Y1612834I200J0D01*
G02Y1609922I-1664J-1456D01*
G03X293384Y1609790I150J-132D01*
G01Y1609168D01*
G02X293181Y1608966I-203J1D01*
G01X290361D01*
G02X290158Y1609168I-1J202D01*
G01Y1609790D01*
G03X290108Y1609922I-200J0D01*
G02Y1612834I1664J1456D01*
G03X290158Y1612966I-150J132D01*
G01Y1614908D01*
G03X290108Y1615040I-200J0D01*
G02Y1617952I1664J1456D01*
G03X290158Y1618084I-150J132D01*
G01Y1618706D01*
G02X290361Y1618908I203J-1D01*
G37*
G36*
G01X325007D02*
X327827D01*
G02X328030Y1618706I1J-202D01*
G01Y1618084D01*
G03X328080Y1617952I200J0D01*
G02Y1615040I-1664J-1456D01*
G03X328030Y1614908I150J-132D01*
G01Y1612966D01*
G03X328080Y1612834I200J0D01*
G02Y1609922I-1664J-1456D01*
G03X328030Y1609790I150J-132D01*
G01Y1609168D01*
G02X327827Y1608966I-203J1D01*
G01X325007D01*
G02X324804Y1609168I-1J202D01*
G01Y1609790D01*
G03X324754Y1609922I-200J0D01*
G02Y1612834I1664J1456D01*
G03X324804Y1612966I-150J132D01*
G01Y1614908D01*
G03X324754Y1615040I-200J0D01*
G02Y1617952I1664J1456D01*
G03X324804Y1618084I-150J132D01*
G01Y1618706D01*
G02X325007Y1618908I203J-1D01*
G37*
G36*
G01X359653D02*
X362473D01*
G02X362676Y1618706I1J-202D01*
G01Y1618084D01*
G03X362726Y1617952I200J0D01*
G02Y1615040I-1664J-1456D01*
G03X362676Y1614908I150J-132D01*
G01Y1612966D01*
G03X362726Y1612834I200J0D01*
G02Y1609922I-1664J-1456D01*
G03X362676Y1609790I150J-132D01*
G01Y1609168D01*
G02X362473Y1608966I-203J1D01*
G01X359653D01*
G02X359450Y1609168I-1J202D01*
G01Y1609790D01*
G03X359400Y1609922I-200J0D01*
G02Y1612834I1664J1456D01*
G03X359450Y1612966I-150J132D01*
G01Y1614908D01*
G03X359400Y1615040I-200J0D01*
G02Y1617952I1664J1456D01*
G03X359450Y1618084I-150J132D01*
G01Y1618706D01*
G02X359653Y1618908I203J-1D01*
G37*
G36*
G01X515559D02*
X518379D01*
G02X518582Y1618706I1J-202D01*
G01Y1618084D01*
G03X518632Y1617952I200J0D01*
G02Y1615040I-1664J-1456D01*
G03X518582Y1614908I150J-132D01*
G01Y1612966D01*
G03X518632Y1612834I200J0D01*
G02Y1609922I-1664J-1456D01*
G03X518582Y1609790I150J-132D01*
G01Y1609168D01*
G02X518379Y1608966I-203J1D01*
G01X515559D01*
G02X515356Y1609168I-1J202D01*
G01Y1609790D01*
G03X515306Y1609922I-200J0D01*
G02Y1612834I1664J1456D01*
G03X515356Y1612966I-150J132D01*
G01Y1614908D01*
G03X515306Y1615040I-200J0D01*
G02Y1617952I1664J1456D01*
G03X515356Y1618084I-150J132D01*
G01Y1618706D01*
G02X515559Y1618908I203J-1D01*
G37*
G36*
G01X654141D02*
X656961D01*
G02X657164Y1618706I1J-202D01*
G01Y1618084D01*
G03X657214Y1617952I200J0D01*
G02Y1615040I-1664J-1456D01*
G03X657164Y1614908I150J-132D01*
G01Y1612966D01*
G03X657214Y1612834I200J0D01*
G02Y1609922I-1664J-1456D01*
G03X657164Y1609790I150J-132D01*
G01Y1609168D01*
G02X656961Y1608966I-203J1D01*
G01X654141D01*
G02X653938Y1609168I-1J202D01*
G01Y1609790D01*
G03X653888Y1609922I-200J0D01*
G02Y1612834I1664J1456D01*
G03X653938Y1612966I-150J132D01*
G01Y1614908D01*
G03X653888Y1615040I-200J0D01*
G02Y1617952I1664J1456D01*
G03X653938Y1618084I-150J132D01*
G01Y1618706D01*
G02X654141Y1618908I203J-1D01*
G37*
G36*
G01X688787D02*
X691607D01*
G02X691810Y1618706I1J-202D01*
G01Y1618084D01*
G03X691860Y1617952I200J0D01*
G02Y1615040I-1664J-1456D01*
G03X691810Y1614908I150J-132D01*
G01Y1612966D01*
G03X691860Y1612834I200J0D01*
G02Y1609922I-1664J-1456D01*
G03X691810Y1609790I150J-132D01*
G01Y1609168D01*
G02X691607Y1608966I-203J1D01*
G01X688787D01*
G02X688584Y1609168I-1J202D01*
G01Y1609790D01*
G03X688534Y1609922I-200J0D01*
G02Y1612834I1664J1456D01*
G03X688584Y1612966I-150J132D01*
G01Y1614908D01*
G03X688534Y1615040I-200J0D01*
G02Y1617952I1664J1456D01*
G03X688584Y1618084I-150J132D01*
G01Y1618706D01*
G02X688787Y1618908I203J-1D01*
G37*
G36*
G01X1139101D02*
X1141921D01*
G02X1142124Y1618706I1J-202D01*
G01Y1618084D01*
G03X1142174Y1617952I200J0D01*
G02Y1615040I-1664J-1456D01*
G03X1142124Y1614908I150J-132D01*
G01Y1612966D01*
G03X1142174Y1612834I200J0D01*
G02Y1609922I-1664J-1456D01*
G03X1142124Y1609790I150J-132D01*
G01Y1609168D01*
G02X1141921Y1608966I-203J1D01*
G01X1139101D01*
G02X1138898Y1609168I-1J202D01*
G01Y1609790D01*
G03X1138848Y1609922I-200J0D01*
G02Y1612834I1664J1456D01*
G03X1138898Y1612966I-150J132D01*
G01Y1614908D01*
G03X1138848Y1615040I-200J0D01*
G02Y1617952I1664J1456D01*
G03X1138898Y1618084I-150J132D01*
G01Y1618706D01*
G02X1139101Y1618908I203J-1D01*
G37*
G36*
G01X1173747D02*
X1176567D01*
G02X1176770Y1618706I1J-202D01*
G01Y1618084D01*
G03X1176820Y1617952I200J0D01*
G02Y1615040I-1664J-1456D01*
G03X1176770Y1614908I150J-132D01*
G01Y1612966D01*
G03X1176820Y1612834I200J0D01*
G02Y1609922I-1664J-1456D01*
G03X1176770Y1609790I150J-132D01*
G01Y1609168D01*
G02X1176567Y1608966I-203J1D01*
G01X1173747D01*
G02X1173544Y1609168I-1J202D01*
G01Y1609790D01*
G03X1173494Y1609922I-200J0D01*
G02Y1612834I1664J1456D01*
G03X1173544Y1612966I-150J132D01*
G01Y1614908D01*
G03X1173494Y1615040I-200J0D01*
G02Y1617952I1664J1456D01*
G03X1173544Y1618084I-150J132D01*
G01Y1618706D01*
G02X1173747Y1618908I203J-1D01*
G37*
G36*
G01X1329653D02*
X1332473D01*
G02X1332676Y1618706I1J-202D01*
G01Y1618084D01*
G03X1332726Y1617952I200J0D01*
G02Y1615040I-1664J-1456D01*
G03X1332676Y1614908I150J-132D01*
G01Y1612966D01*
G03X1332726Y1612834I200J0D01*
G02Y1609922I-1664J-1456D01*
G03X1332676Y1609790I150J-132D01*
G01Y1609168D01*
G02X1332473Y1608966I-203J1D01*
G01X1329653D01*
G02X1329450Y1609168I-1J202D01*
G01Y1609790D01*
G03X1329400Y1609922I-200J0D01*
G02Y1612834I1664J1456D01*
G03X1329450Y1612966I-150J132D01*
G01Y1614908D01*
G03X1329400Y1615040I-200J0D01*
G02Y1617952I1664J1456D01*
G03X1329450Y1618084I-150J132D01*
G01Y1618706D01*
G02X1329653Y1618908I203J-1D01*
G37*
G36*
G01X1364299D02*
X1367119D01*
G02X1367322Y1618706I1J-202D01*
G01Y1618084D01*
G03X1367372Y1617952I200J0D01*
G02Y1615040I-1664J-1456D01*
G03X1367322Y1614908I150J-132D01*
G01Y1612966D01*
G03X1367372Y1612834I200J0D01*
G02Y1609922I-1664J-1456D01*
G03X1367322Y1609790I150J-132D01*
G01Y1609168D01*
G02X1367119Y1608966I-203J1D01*
G01X1364299D01*
G02X1364096Y1609168I-1J202D01*
G01Y1609790D01*
G03X1364046Y1609922I-200J0D01*
G02Y1612834I1664J1456D01*
G03X1364096Y1612966I-150J132D01*
G01Y1614908D01*
G03X1364046Y1615040I-200J0D01*
G02Y1617952I1664J1456D01*
G03X1364096Y1618084I-150J132D01*
G01Y1618706D01*
G02X1364299Y1618908I203J-1D01*
G37*
G36*
G01X1676109D02*
X1678929D01*
G02X1679132Y1618706I1J-202D01*
G01Y1618084D01*
G03X1679182Y1617952I200J0D01*
G02Y1615040I-1664J-1456D01*
G03X1679132Y1614908I150J-132D01*
G01Y1612966D01*
G03X1679182Y1612834I200J0D01*
G02Y1609922I-1664J-1456D01*
G03X1679132Y1609790I150J-132D01*
G01Y1609168D01*
G02X1678929Y1608966I-203J1D01*
G01X1676109D01*
G02X1675906Y1609168I-1J202D01*
G01Y1609790D01*
G03X1675856Y1609922I-200J0D01*
G02Y1612834I1664J1456D01*
G03X1675906Y1612966I-150J132D01*
G01Y1614908D01*
G03X1675856Y1615040I-200J0D01*
G02Y1617952I1664J1456D01*
G03X1675906Y1618084I-150J132D01*
G01Y1618706D01*
G02X1676109Y1618908I203J-1D01*
G37*
G36*
G01X1710755D02*
X1713575D01*
G02X1713778Y1618706I1J-202D01*
G01Y1618084D01*
G03X1713828Y1617952I200J0D01*
G02Y1615040I-1664J-1456D01*
G03X1713778Y1614908I150J-132D01*
G01Y1612966D01*
G03X1713828Y1612834I200J0D01*
G02Y1609922I-1664J-1456D01*
G03X1713778Y1609790I150J-132D01*
G01Y1609168D01*
G02X1713575Y1608966I-203J1D01*
G01X1710755D01*
G02X1710552Y1609168I-1J202D01*
G01Y1609790D01*
G03X1710502Y1609922I-200J0D01*
G02Y1612834I1664J1456D01*
G03X1710552Y1612966I-150J132D01*
G01Y1614908D01*
G03X1710502Y1615040I-200J0D01*
G02Y1617952I1664J1456D01*
G03X1710552Y1618084I-150J132D01*
G01Y1618706D01*
G02X1710755Y1618908I203J-1D01*
G37*
G36*
G01X1522570Y1409998D02*
X1525970D01*
G02Y1406992I0J-1503D01*
G01X1522570D01*
G02Y1409998I0J1503D01*
G37*
G36*
G01X1559290Y1349690D02*
X1562690D01*
G02Y1346684I0J-1503D01*
G01X1559290D01*
G02Y1349690I0J1503D01*
G37*
G36*
G01X1522570Y1385800D02*
X1525970D01*
G02Y1382794I0J-1503D01*
G01X1522570D01*
G02Y1385800I0J1503D01*
G37*
G36*
G01Y1373888D02*
X1525970D01*
G02Y1370882I0J-1503D01*
G01X1522570D01*
G02Y1373888I0J1503D01*
G37*
G36*
G01Y1398086D02*
X1525970D01*
G02Y1395080I0J-1503D01*
G01X1522570D01*
G02Y1398086I0J1503D01*
G37*
G36*
G01X1510330Y1373888D02*
X1513730D01*
G02Y1370882I0J-1503D01*
G01X1510330D01*
G02Y1373888I0J1503D01*
G37*
G36*
G01X1547050Y1361602D02*
X1550450D01*
G02Y1358596I0J-1503D01*
G01X1547050D01*
G02Y1361602I0J1503D01*
G37*
G36*
G01X1534810D02*
X1538210D01*
G02Y1358596I0J-1503D01*
G01X1534810D01*
G02Y1361602I0J1503D01*
G37*
G36*
G01X1547050Y1349690D02*
X1550450D01*
G02Y1346684I0J-1503D01*
G01X1547050D01*
G02Y1349690I0J1503D01*
G37*
G36*
G01X1534810D02*
X1538210D01*
G02Y1346684I0J-1503D01*
G01X1534810D01*
G02Y1349690I0J1503D01*
G37*
G36*
G01X241623Y1373888D02*
X245023D01*
G02Y1370882I0J-1503D01*
G01X241623D01*
G02Y1373888I0J1503D01*
G37*
G36*
G01Y1361602D02*
X245023D01*
G02Y1358596I0J-1503D01*
G01X241623D01*
G02Y1361602I0J1503D01*
G37*
G36*
G01X1485850Y1409998D02*
X1489250D01*
G02Y1406992I0J-1503D01*
G01X1485850D01*
G02Y1409998I0J1503D01*
G37*
G36*
G01X1510330Y1349690D02*
X1513730D01*
G02Y1346684I0J-1503D01*
G01X1510330D01*
G02Y1349690I0J1503D01*
G37*
G36*
G01X364023Y1398086D02*
X367423D01*
G02Y1395080I0J-1503D01*
G01X364023D01*
G02Y1398086I0J1503D01*
G37*
G36*
G01X1485850Y1385800D02*
X1489250D01*
G02Y1382794I0J-1503D01*
G01X1485850D01*
G02Y1385800I0J1503D01*
G37*
G36*
G01X1473610D02*
X1477010D01*
G02Y1382794I0J-1503D01*
G01X1473610D01*
G02Y1385800I0J1503D01*
G37*
G36*
G01Y1361602D02*
X1477010D01*
G02Y1358596I0J-1503D01*
G01X1473610D01*
G02Y1361602I0J1503D01*
G37*
G36*
G01Y1349690D02*
X1477010D01*
G02Y1346684I0J-1503D01*
G01X1473610D01*
G02Y1349690I0J1503D01*
G37*
G36*
G01X1461370Y1385800D02*
X1464770D01*
G02Y1382794I0J-1503D01*
G01X1461370D01*
G02Y1385800I0J1503D01*
G37*
G36*
G01Y1373888D02*
X1464770D01*
G02Y1370882I0J-1503D01*
G01X1461370D01*
G02Y1373888I0J1503D01*
G37*
G36*
G01Y1361602D02*
X1464770D01*
G02Y1358596I0J-1503D01*
G01X1461370D01*
G02Y1361602I0J1503D01*
G37*
G36*
G01Y1349690D02*
X1464770D01*
G02Y1346684I0J-1503D01*
G01X1461370D01*
G02Y1349690I0J1503D01*
G37*
G36*
G01X1485850Y1373888D02*
X1489250D01*
G02Y1370882I0J-1503D01*
G01X1485850D01*
G02Y1373888I0J1503D01*
G37*
G36*
G01X1498090Y1361602D02*
X1501490D01*
G02Y1358596I0J-1503D01*
G01X1498090D01*
G02Y1361602I0J1503D01*
G37*
G36*
G01X1485850D02*
X1489250D01*
G02Y1358596I0J-1503D01*
G01X1485850D01*
G02Y1361602I0J1503D01*
G37*
G36*
G01X253863Y1409998D02*
X257263D01*
G02Y1406992I0J-1503D01*
G01X253863D01*
G02Y1409998I0J1503D01*
G37*
G36*
G01X266103Y1373888D02*
X269503D01*
G02Y1370882I0J-1503D01*
G01X266103D01*
G02Y1373888I0J1503D01*
G37*
G36*
G01X290583Y1361602D02*
X293983D01*
G02Y1358596I0J-1503D01*
G01X290583D01*
G02Y1361602I0J1503D01*
G37*
G36*
G01X327303Y1349690D02*
X330703D01*
G02Y1346684I0J-1503D01*
G01X327303D01*
G02Y1349690I0J1503D01*
G37*
G36*
G01X290583Y1385800D02*
X293983D01*
G02Y1382794I0J-1503D01*
G01X290583D01*
G02Y1385800I0J1503D01*
G37*
G36*
G01Y1409998D02*
X293983D01*
G02Y1406992I0J-1503D01*
G01X290583D01*
G02Y1409998I0J1503D01*
G37*
G36*
G01X253863Y1398086D02*
X257263D01*
G02Y1395080I0J-1503D01*
G01X253863D01*
G02Y1398086I0J1503D01*
G37*
G36*
G01X364023Y1361602D02*
X367423D01*
G02Y1358596I0J-1503D01*
G01X364023D01*
G02Y1361602I0J1503D01*
G37*
G36*
G01X339543Y1349690D02*
X342943D01*
G02Y1346684I0J-1503D01*
G01X339543D01*
G02Y1349690I0J1503D01*
G37*
G36*
G01X241623D02*
X245023D01*
G02Y1346684I0J-1503D01*
G01X241623D01*
G02Y1349690I0J1503D01*
G37*
G36*
G01X339543Y1361602D02*
X342943D01*
G02Y1358596I0J-1503D01*
G01X339543D01*
G02Y1361602I0J1503D01*
G37*
G36*
G01X302823Y1409998D02*
X306223D01*
G02Y1406992I0J-1503D01*
G01X302823D01*
G02Y1409998I0J1503D01*
G37*
G36*
G01X364023Y1385800D02*
X367423D01*
G02Y1382794I0J-1503D01*
G01X364023D01*
G02Y1385800I0J1503D01*
G37*
G36*
G01X290583Y1398086D02*
X293983D01*
G02Y1395080I0J-1503D01*
G01X290583D01*
G02Y1398086I0J1503D01*
G37*
G36*
G01X112832D02*
X116232D01*
G02Y1395080I0J-1503D01*
G01X112832D01*
G02Y1398086I0J1503D01*
G37*
G36*
G01X364023Y1373888D02*
X367423D01*
G02Y1370882I0J-1503D01*
G01X364023D01*
G02Y1373888I0J1503D01*
G37*
G36*
G01X302823Y1361602D02*
X306223D01*
G02Y1358596I0J-1503D01*
G01X302823D01*
G02Y1361602I0J1503D01*
G37*
G36*
G01X1534810Y1409998D02*
X1538210D01*
G02Y1406992I0J-1503D01*
G01X1534810D01*
G02Y1409998I0J1503D01*
G37*
G36*
G01X1510330Y1385800D02*
X1513730D01*
G02Y1382794I0J-1503D01*
G01X1510330D01*
G02Y1385800I0J1503D01*
G37*
G36*
G01X1534810Y1398086D02*
X1538210D01*
G02Y1395080I0J-1503D01*
G01X1534810D01*
G02Y1398086I0J1503D01*
G37*
G36*
G01X302823Y1349690D02*
X306223D01*
G02Y1346684I0J-1503D01*
G01X302823D01*
G02Y1349690I0J1503D01*
G37*
G36*
G01X88352Y1373888D02*
X91752D01*
G02Y1370882I0J-1503D01*
G01X88352D01*
G02Y1373888I0J1503D01*
G37*
G36*
G01X339543Y1385800D02*
X342943D01*
G02Y1382794I0J-1503D01*
G01X339543D01*
G02Y1385800I0J1503D01*
G37*
G36*
G01X327303Y1373888D02*
X330703D01*
G02Y1370882I0J-1503D01*
G01X327303D01*
G02Y1373888I0J1503D01*
G37*
G36*
G01Y1409998D02*
X330703D01*
G02Y1406992I0J-1503D01*
G01X327303D01*
G02Y1409998I0J1503D01*
G37*
G36*
G01X278343Y1398086D02*
X281743D01*
G02Y1395080I0J-1503D01*
G01X278343D01*
G02Y1398086I0J1503D01*
G37*
G36*
G01X351783Y1349690D02*
X355183D01*
G02Y1346684I0J-1503D01*
G01X351783D01*
G02Y1349690I0J1503D01*
G37*
G36*
G01X186272Y1385800D02*
X189672D01*
G02Y1382794I0J-1503D01*
G01X186272D01*
G02Y1385800I0J1503D01*
G37*
G36*
G01Y1373888D02*
X189672D01*
G02Y1370882I0J-1503D01*
G01X186272D01*
G02Y1373888I0J1503D01*
G37*
G36*
G01X315063Y1361602D02*
X318463D01*
G02Y1358596I0J-1503D01*
G01X315063D01*
G02Y1361602I0J1503D01*
G37*
G36*
G01X327303D02*
X330703D01*
G02Y1358596I0J-1503D01*
G01X327303D01*
G02Y1361602I0J1503D01*
G37*
G36*
G01X315063Y1349690D02*
X318463D01*
G02Y1346684I0J-1503D01*
G01X315063D01*
G02Y1349690I0J1503D01*
G37*
G36*
G01X174032Y1398086D02*
X177432D01*
G02Y1395080I0J-1503D01*
G01X174032D01*
G02Y1398086I0J1503D01*
G37*
G36*
G01X266103Y1349690D02*
X269503D01*
G02Y1346684I0J-1503D01*
G01X266103D01*
G02Y1349690I0J1503D01*
G37*
G36*
G01X1054713Y1361602D02*
X1058113D01*
G02Y1358596I0J-1503D01*
G01X1054713D01*
G02Y1361602I0J1503D01*
G37*
G36*
G01Y1349690D02*
X1058113D01*
G02Y1346684I0J-1503D01*
G01X1054713D01*
G02Y1349690I0J1503D01*
G37*
G36*
G01Y1385800D02*
X1058113D01*
G02Y1382794I0J-1503D01*
G01X1054713D01*
G02Y1385800I0J1503D01*
G37*
G36*
G01Y1373888D02*
X1058113D01*
G02Y1370882I0J-1503D01*
G01X1054713D01*
G02Y1373888I0J1503D01*
G37*
G36*
G01X1177113Y1409998D02*
X1180513D01*
G02Y1406992I0J-1503D01*
G01X1177113D01*
G02Y1409998I0J1503D01*
G37*
G36*
G01Y1398086D02*
X1180513D01*
G02Y1395080I0J-1503D01*
G01X1177113D01*
G02Y1398086I0J1503D01*
G37*
G36*
G01Y1373888D02*
X1180513D01*
G02Y1370882I0J-1503D01*
G01X1177113D01*
G02Y1373888I0J1503D01*
G37*
G36*
G01Y1385800D02*
X1180513D01*
G02Y1382794I0J-1503D01*
G01X1177113D01*
G02Y1385800I0J1503D01*
G37*
G36*
G01Y1361602D02*
X1180513D01*
G02Y1358596I0J-1503D01*
G01X1177113D01*
G02Y1361602I0J1503D01*
G37*
G36*
G01Y1349690D02*
X1180513D01*
G02Y1346684I0J-1503D01*
G01X1177113D01*
G02Y1349690I0J1503D01*
G37*
G36*
G01X1164873Y1409998D02*
X1168273D01*
G02Y1406992I0J-1503D01*
G01X1164873D01*
G02Y1409998I0J1503D01*
G37*
G36*
G01Y1398086D02*
X1168273D01*
G02Y1395080I0J-1503D01*
G01X1164873D01*
G02Y1398086I0J1503D01*
G37*
G36*
G01Y1385800D02*
X1168273D01*
G02Y1382794I0J-1503D01*
G01X1164873D01*
G02Y1385800I0J1503D01*
G37*
G36*
G01Y1373888D02*
X1168273D01*
G02Y1370882I0J-1503D01*
G01X1164873D01*
G02Y1373888I0J1503D01*
G37*
G36*
G01Y1361602D02*
X1168273D01*
G02Y1358596I0J-1503D01*
G01X1164873D01*
G02Y1361602I0J1503D01*
G37*
G36*
G01Y1349690D02*
X1168273D01*
G02Y1346684I0J-1503D01*
G01X1164873D01*
G02Y1349690I0J1503D01*
G37*
G36*
G01X1152633Y1409998D02*
X1156033D01*
G02Y1406992I0J-1503D01*
G01X1152633D01*
G02Y1409998I0J1503D01*
G37*
G36*
G01Y1398086D02*
X1156033D01*
G02Y1395080I0J-1503D01*
G01X1152633D01*
G02Y1398086I0J1503D01*
G37*
G36*
G01Y1373888D02*
X1156033D01*
G02Y1370882I0J-1503D01*
G01X1152633D01*
G02Y1373888I0J1503D01*
G37*
G36*
G01Y1385800D02*
X1156033D01*
G02Y1382794I0J-1503D01*
G01X1152633D01*
G02Y1385800I0J1503D01*
G37*
G36*
G01Y1361602D02*
X1156033D01*
G02Y1358596I0J-1503D01*
G01X1152633D01*
G02Y1361602I0J1503D01*
G37*
G36*
G01Y1349690D02*
X1156033D01*
G02Y1346684I0J-1503D01*
G01X1152633D01*
G02Y1349690I0J1503D01*
G37*
G36*
G01X1128153Y1409998D02*
X1131553D01*
G02Y1406992I0J-1503D01*
G01X1128153D01*
G02Y1409998I0J1503D01*
G37*
G36*
G01X1140393D02*
X1143793D01*
G02Y1406992I0J-1503D01*
G01X1140393D01*
G02Y1409998I0J1503D01*
G37*
G36*
G01X1128153Y1398086D02*
X1131553D01*
G02Y1395080I0J-1503D01*
G01X1128153D01*
G02Y1398086I0J1503D01*
G37*
G36*
G01X1140393D02*
X1143793D01*
G02Y1395080I0J-1503D01*
G01X1140393D01*
G02Y1398086I0J1503D01*
G37*
G36*
G01X1128153Y1373888D02*
X1131553D01*
G02Y1370882I0J-1503D01*
G01X1128153D01*
G02Y1373888I0J1503D01*
G37*
G36*
G01Y1385800D02*
X1131553D01*
G02Y1382794I0J-1503D01*
G01X1128153D01*
G02Y1385800I0J1503D01*
G37*
G36*
G01X1140393D02*
X1143793D01*
G02Y1382794I0J-1503D01*
G01X1140393D01*
G02Y1385800I0J1503D01*
G37*
G36*
G01Y1373888D02*
X1143793D01*
G02Y1370882I0J-1503D01*
G01X1140393D01*
G02Y1373888I0J1503D01*
G37*
G36*
G01X1128153Y1361602D02*
X1131553D01*
G02Y1358596I0J-1503D01*
G01X1128153D01*
G02Y1361602I0J1503D01*
G37*
G36*
G01X1140393D02*
X1143793D01*
G02Y1358596I0J-1503D01*
G01X1140393D01*
G02Y1361602I0J1503D01*
G37*
G36*
G01X1128153Y1349690D02*
X1131553D01*
G02Y1346684I0J-1503D01*
G01X1128153D01*
G02Y1349690I0J1503D01*
G37*
G36*
G01X1140393D02*
X1143793D01*
G02Y1346684I0J-1503D01*
G01X1140393D01*
G02Y1349690I0J1503D01*
G37*
G36*
G01X1115913Y1409998D02*
X1119313D01*
G02Y1406992I0J-1503D01*
G01X1115913D01*
G02Y1409998I0J1503D01*
G37*
G36*
G01Y1398086D02*
X1119313D01*
G02Y1395080I0J-1503D01*
G01X1115913D01*
G02Y1398086I0J1503D01*
G37*
G36*
G01Y1373888D02*
X1119313D01*
G02Y1370882I0J-1503D01*
G01X1115913D01*
G02Y1373888I0J1503D01*
G37*
G36*
G01Y1385800D02*
X1119313D01*
G02Y1382794I0J-1503D01*
G01X1115913D01*
G02Y1385800I0J1503D01*
G37*
G36*
G01Y1361602D02*
X1119313D01*
G02Y1358596I0J-1503D01*
G01X1115913D01*
G02Y1361602I0J1503D01*
G37*
G36*
G01Y1349690D02*
X1119313D01*
G02Y1346684I0J-1503D01*
G01X1115913D01*
G02Y1349690I0J1503D01*
G37*
G36*
G01X1103673Y1409998D02*
X1107073D01*
G02Y1406992I0J-1503D01*
G01X1103673D01*
G02Y1409998I0J1503D01*
G37*
G36*
G01Y1398086D02*
X1107073D01*
G02Y1395080I0J-1503D01*
G01X1103673D01*
G02Y1398086I0J1503D01*
G37*
G36*
G01Y1385800D02*
X1107073D01*
G02Y1382794I0J-1503D01*
G01X1103673D01*
G02Y1385800I0J1503D01*
G37*
G36*
G01Y1373888D02*
X1107073D01*
G02Y1370882I0J-1503D01*
G01X1103673D01*
G02Y1373888I0J1503D01*
G37*
G36*
G01Y1361602D02*
X1107073D01*
G02Y1358596I0J-1503D01*
G01X1103673D01*
G02Y1361602I0J1503D01*
G37*
G36*
G01Y1349690D02*
X1107073D01*
G02Y1346684I0J-1503D01*
G01X1103673D01*
G02Y1349690I0J1503D01*
G37*
G36*
G01X1079193Y1409998D02*
X1082593D01*
G02Y1406992I0J-1503D01*
G01X1079193D01*
G02Y1409998I0J1503D01*
G37*
G36*
G01X1091433D02*
X1094833D01*
G02Y1406992I0J-1503D01*
G01X1091433D01*
G02Y1409998I0J1503D01*
G37*
G36*
G01X1079193Y1398086D02*
X1082593D01*
G02Y1395080I0J-1503D01*
G01X1079193D01*
G02Y1398086I0J1503D01*
G37*
G36*
G01X1091433D02*
X1094833D01*
G02Y1395080I0J-1503D01*
G01X1091433D01*
G02Y1398086I0J1503D01*
G37*
G36*
G01X1079193Y1385800D02*
X1082593D01*
G02Y1382794I0J-1503D01*
G01X1079193D01*
G02Y1385800I0J1503D01*
G37*
G36*
G01Y1373888D02*
X1082593D01*
G02Y1370882I0J-1503D01*
G01X1079193D01*
G02Y1373888I0J1503D01*
G37*
G36*
G01X1091433Y1385800D02*
X1094833D01*
G02Y1382794I0J-1503D01*
G01X1091433D01*
G02Y1385800I0J1503D01*
G37*
G36*
G01Y1373888D02*
X1094833D01*
G02Y1370882I0J-1503D01*
G01X1091433D01*
G02Y1373888I0J1503D01*
G37*
G36*
G01X1079193Y1361602D02*
X1082593D01*
G02Y1358596I0J-1503D01*
G01X1079193D01*
G02Y1361602I0J1503D01*
G37*
G36*
G01X1091433D02*
X1094833D01*
G02Y1358596I0J-1503D01*
G01X1091433D01*
G02Y1361602I0J1503D01*
G37*
G36*
G01X1079193Y1349690D02*
X1082593D01*
G02Y1346684I0J-1503D01*
G01X1079193D01*
G02Y1349690I0J1503D01*
G37*
G36*
G01X1091433D02*
X1094833D01*
G02Y1346684I0J-1503D01*
G01X1091433D01*
G02Y1349690I0J1503D01*
G37*
G36*
G01X1066953Y1409998D02*
X1070353D01*
G02Y1406992I0J-1503D01*
G01X1066953D01*
G02Y1409998I0J1503D01*
G37*
G36*
G01Y1398086D02*
X1070353D01*
G02Y1395080I0J-1503D01*
G01X1066953D01*
G02Y1398086I0J1503D01*
G37*
G36*
G01X290583Y1349690D02*
X293983D01*
G02Y1346684I0J-1503D01*
G01X290583D01*
G02Y1349690I0J1503D01*
G37*
G36*
G01X241623Y1385800D02*
X245023D01*
G02Y1382794I0J-1503D01*
G01X241623D01*
G02Y1385800I0J1503D01*
G37*
G36*
G01X253863Y1361602D02*
X257263D01*
G02Y1358596I0J-1503D01*
G01X253863D01*
G02Y1361602I0J1503D01*
G37*
G36*
G01Y1349690D02*
X257263D01*
G02Y1346684I0J-1503D01*
G01X253863D01*
G02Y1349690I0J1503D01*
G37*
G36*
G01X1547050Y1409998D02*
X1550450D01*
G02Y1406992I0J-1503D01*
G01X1547050D01*
G02Y1409998I0J1503D01*
G37*
G36*
G01X1559290Y1385800D02*
X1562690D01*
G02Y1382794I0J-1503D01*
G01X1559290D01*
G02Y1385800I0J1503D01*
G37*
G36*
G01X1230326Y1349690D02*
X1233726D01*
G02Y1346684I0J-1503D01*
G01X1230326D01*
G02Y1349690I0J1503D01*
G37*
G36*
G01Y1361602D02*
X1233726D01*
G02Y1358596I0J-1503D01*
G01X1230326D01*
G02Y1361602I0J1503D01*
G37*
G36*
G01Y1373888D02*
X1233726D01*
G02Y1370882I0J-1503D01*
G01X1230326D01*
G02Y1373888I0J1503D01*
G37*
G36*
G01Y1385800D02*
X1233726D01*
G02Y1382794I0J-1503D01*
G01X1230326D01*
G02Y1385800I0J1503D01*
G37*
G36*
G01X1242566Y1349690D02*
X1245966D01*
G02Y1346684I0J-1503D01*
G01X1242566D01*
G02Y1349690I0J1503D01*
G37*
G36*
G01Y1361602D02*
X1245966D01*
G02Y1358596I0J-1503D01*
G01X1242566D01*
G02Y1361602I0J1503D01*
G37*
G36*
G01Y1385800D02*
X1245966D01*
G02Y1382794I0J-1503D01*
G01X1242566D01*
G02Y1385800I0J1503D01*
G37*
G36*
G01Y1373888D02*
X1245966D01*
G02Y1370882I0J-1503D01*
G01X1242566D01*
G02Y1373888I0J1503D01*
G37*
G36*
G01Y1398086D02*
X1245966D01*
G02Y1395080I0J-1503D01*
G01X1242566D01*
G02Y1398086I0J1503D01*
G37*
G36*
G01Y1409998D02*
X1245966D01*
G02Y1406992I0J-1503D01*
G01X1242566D01*
G02Y1409998I0J1503D01*
G37*
G36*
G01X1267046Y1349690D02*
X1270446D01*
G02Y1346684I0J-1503D01*
G01X1267046D01*
G02Y1349690I0J1503D01*
G37*
G36*
G01X1254806D02*
X1258206D01*
G02Y1346684I0J-1503D01*
G01X1254806D01*
G02Y1349690I0J1503D01*
G37*
G36*
G01X1267046Y1361602D02*
X1270446D01*
G02Y1358596I0J-1503D01*
G01X1267046D01*
G02Y1361602I0J1503D01*
G37*
G36*
G01X1254806D02*
X1258206D01*
G02Y1358596I0J-1503D01*
G01X1254806D01*
G02Y1361602I0J1503D01*
G37*
G36*
G01X1267046Y1385800D02*
X1270446D01*
G02Y1382794I0J-1503D01*
G01X1267046D01*
G02Y1385800I0J1503D01*
G37*
G36*
G01Y1373888D02*
X1270446D01*
G02Y1370882I0J-1503D01*
G01X1267046D01*
G02Y1373888I0J1503D01*
G37*
G36*
G01X1254806D02*
X1258206D01*
G02Y1370882I0J-1503D01*
G01X1254806D01*
G02Y1373888I0J1503D01*
G37*
G36*
G01Y1385800D02*
X1258206D01*
G02Y1382794I0J-1503D01*
G01X1254806D01*
G02Y1385800I0J1503D01*
G37*
G36*
G01X1267046Y1398086D02*
X1270446D01*
G02Y1395080I0J-1503D01*
G01X1267046D01*
G02Y1398086I0J1503D01*
G37*
G36*
G01X1254806D02*
X1258206D01*
G02Y1395080I0J-1503D01*
G01X1254806D01*
G02Y1398086I0J1503D01*
G37*
G36*
G01X1267046Y1409998D02*
X1270446D01*
G02Y1406992I0J-1503D01*
G01X1267046D01*
G02Y1409998I0J1503D01*
G37*
G36*
G01X1254806D02*
X1258206D01*
G02Y1406992I0J-1503D01*
G01X1254806D01*
G02Y1409998I0J1503D01*
G37*
G36*
G01X1279286Y1349690D02*
X1282686D01*
G02Y1346684I0J-1503D01*
G01X1279286D01*
G02Y1349690I0J1503D01*
G37*
G36*
G01Y1361602D02*
X1282686D01*
G02Y1358596I0J-1503D01*
G01X1279286D01*
G02Y1361602I0J1503D01*
G37*
G36*
G01X1510330D02*
X1513730D01*
G02Y1358596I0J-1503D01*
G01X1510330D01*
G02Y1361602I0J1503D01*
G37*
G36*
G01X1279286Y1373888D02*
X1282686D01*
G02Y1370882I0J-1503D01*
G01X1279286D01*
G02Y1373888I0J1503D01*
G37*
G36*
G01Y1385800D02*
X1282686D01*
G02Y1382794I0J-1503D01*
G01X1279286D01*
G02Y1385800I0J1503D01*
G37*
G36*
G01X1648118Y1409998D02*
X1651518D01*
G02Y1406992I0J-1503D01*
G01X1648118D01*
G02Y1409998I0J1503D01*
G37*
G36*
G01X1279286Y1398086D02*
X1282686D01*
G02Y1395080I0J-1503D01*
G01X1279286D01*
G02Y1398086I0J1503D01*
G37*
G36*
G01Y1409998D02*
X1282686D01*
G02Y1406992I0J-1503D01*
G01X1279286D01*
G02Y1409998I0J1503D01*
G37*
G36*
G01X1291526Y1349690D02*
X1294926D01*
G02Y1346684I0J-1503D01*
G01X1291526D01*
G02Y1349690I0J1503D01*
G37*
G36*
G01X1559290Y1398086D02*
X1562690D01*
G02Y1395080I0J-1503D01*
G01X1559290D01*
G02Y1398086I0J1503D01*
G37*
G36*
G01X161792Y1409998D02*
X165192D01*
G02Y1406992I0J-1503D01*
G01X161792D01*
G02Y1409998I0J1503D01*
G37*
G36*
G01X186272Y1349690D02*
X189672D01*
G02Y1346684I0J-1503D01*
G01X186272D01*
G02Y1349690I0J1503D01*
G37*
G36*
G01X315063Y1409998D02*
X318463D01*
G02Y1406992I0J-1503D01*
G01X315063D01*
G02Y1409998I0J1503D01*
G37*
G36*
G01X1534810Y1373888D02*
X1538210D01*
G02Y1370882I0J-1503D01*
G01X1534810D01*
G02Y1373888I0J1503D01*
G37*
G36*
G01X1559290Y1409998D02*
X1562690D01*
G02Y1406992I0J-1503D01*
G01X1559290D01*
G02Y1409998I0J1503D01*
G37*
G36*
G01X351783Y1361602D02*
X355183D01*
G02Y1358596I0J-1503D01*
G01X351783D01*
G02Y1361602I0J1503D01*
G37*
G36*
G01X198512Y1385800D02*
X201912D01*
G02Y1382794I0J-1503D01*
G01X198512D01*
G02Y1385800I0J1503D01*
G37*
G36*
G01X1291526Y1361602D02*
X1294926D01*
G02Y1358596I0J-1503D01*
G01X1291526D01*
G02Y1361602I0J1503D01*
G37*
G36*
G01X1635878Y1349690D02*
X1639278D01*
G02Y1346684I0J-1503D01*
G01X1635878D01*
G02Y1349690I0J1503D01*
G37*
G36*
G01Y1361602D02*
X1639278D01*
G02Y1358596I0J-1503D01*
G01X1635878D01*
G02Y1361602I0J1503D01*
G37*
G36*
G01X1291526Y1385800D02*
X1294926D01*
G02Y1382794I0J-1503D01*
G01X1291526D01*
G02Y1385800I0J1503D01*
G37*
G36*
G01Y1373888D02*
X1294926D01*
G02Y1370882I0J-1503D01*
G01X1291526D01*
G02Y1373888I0J1503D01*
G37*
G36*
G01X1635878Y1385800D02*
X1639278D01*
G02Y1382794I0J-1503D01*
G01X1635878D01*
G02Y1385800I0J1503D01*
G37*
G36*
G01Y1373888D02*
X1639278D01*
G02Y1370882I0J-1503D01*
G01X1635878D01*
G02Y1373888I0J1503D01*
G37*
G36*
G01Y1398086D02*
X1639278D01*
G02Y1395080I0J-1503D01*
G01X1635878D01*
G02Y1398086I0J1503D01*
G37*
G36*
G01X1623638Y1349690D02*
X1627038D01*
G02Y1346684I0J-1503D01*
G01X1623638D01*
G02Y1349690I0J1503D01*
G37*
G36*
G01X1611398D02*
X1614798D01*
G02Y1346684I0J-1503D01*
G01X1611398D01*
G02Y1349690I0J1503D01*
G37*
G36*
G01X1623638Y1361602D02*
X1627038D01*
G02Y1358596I0J-1503D01*
G01X1623638D01*
G02Y1361602I0J1503D01*
G37*
G36*
G01X1291526Y1398086D02*
X1294926D01*
G02Y1395080I0J-1503D01*
G01X1291526D01*
G02Y1398086I0J1503D01*
G37*
G36*
G01Y1409998D02*
X1294926D01*
G02Y1406992I0J-1503D01*
G01X1291526D01*
G02Y1409998I0J1503D01*
G37*
G36*
G01X1316006Y1349690D02*
X1319406D01*
G02Y1346684I0J-1503D01*
G01X1316006D01*
G02Y1349690I0J1503D01*
G37*
G36*
G01X1303766D02*
X1307166D01*
G02Y1346684I0J-1503D01*
G01X1303766D01*
G02Y1349690I0J1503D01*
G37*
G36*
G01X1316006Y1361602D02*
X1319406D01*
G02Y1358596I0J-1503D01*
G01X1316006D01*
G02Y1361602I0J1503D01*
G37*
G36*
G01X1303766D02*
X1307166D01*
G02Y1358596I0J-1503D01*
G01X1303766D01*
G02Y1361602I0J1503D01*
G37*
G36*
G01X1316006Y1385800D02*
X1319406D01*
G02Y1382794I0J-1503D01*
G01X1316006D01*
G02Y1385800I0J1503D01*
G37*
G36*
G01X1611398Y1373888D02*
X1614798D01*
G02Y1370882I0J-1503D01*
G01X1611398D01*
G02Y1373888I0J1503D01*
G37*
G36*
G01Y1385800D02*
X1614798D01*
G02Y1382794I0J-1503D01*
G01X1611398D01*
G02Y1385800I0J1503D01*
G37*
G36*
G01X1623638Y1398086D02*
X1627038D01*
G02Y1395080I0J-1503D01*
G01X1623638D01*
G02Y1398086I0J1503D01*
G37*
G36*
G01X1316006Y1373888D02*
X1319406D01*
G02Y1370882I0J-1503D01*
G01X1316006D01*
G02Y1373888I0J1503D01*
G37*
G36*
G01X1303766D02*
X1307166D01*
G02Y1370882I0J-1503D01*
G01X1303766D01*
G02Y1373888I0J1503D01*
G37*
G36*
G01Y1385800D02*
X1307166D01*
G02Y1382794I0J-1503D01*
G01X1303766D01*
G02Y1385800I0J1503D01*
G37*
G36*
G01X1316006Y1398086D02*
X1319406D01*
G02Y1395080I0J-1503D01*
G01X1316006D01*
G02Y1398086I0J1503D01*
G37*
G36*
G01X1303766D02*
X1307166D01*
G02Y1395080I0J-1503D01*
G01X1303766D01*
G02Y1398086I0J1503D01*
G37*
G36*
G01X1316006Y1409998D02*
X1319406D01*
G02Y1406992I0J-1503D01*
G01X1316006D01*
G02Y1409998I0J1503D01*
G37*
G36*
G01X1303766D02*
X1307166D01*
G02Y1406992I0J-1503D01*
G01X1303766D01*
G02Y1409998I0J1503D01*
G37*
G36*
G01X1623638D02*
X1627038D01*
G02Y1406992I0J-1503D01*
G01X1623638D01*
G02Y1409998I0J1503D01*
G37*
G36*
G01X1328246Y1349690D02*
X1331646D01*
G02Y1346684I0J-1503D01*
G01X1328246D01*
G02Y1349690I0J1503D01*
G37*
G36*
G01Y1361602D02*
X1331646D01*
G02Y1358596I0J-1503D01*
G01X1328246D01*
G02Y1361602I0J1503D01*
G37*
G36*
G01X1648118Y1398086D02*
X1651518D01*
G02Y1395080I0J-1503D01*
G01X1648118D01*
G02Y1398086I0J1503D01*
G37*
G36*
G01Y1373888D02*
X1651518D01*
G02Y1370882I0J-1503D01*
G01X1648118D01*
G02Y1373888I0J1503D01*
G37*
G36*
G01Y1385800D02*
X1651518D01*
G02Y1382794I0J-1503D01*
G01X1648118D01*
G02Y1385800I0J1503D01*
G37*
G36*
G01X1328246Y1373888D02*
X1331646D01*
G02Y1370882I0J-1503D01*
G01X1328246D01*
G02Y1373888I0J1503D01*
G37*
G36*
G01X1648118Y1361602D02*
X1651518D01*
G02Y1358596I0J-1503D01*
G01X1648118D01*
G02Y1361602I0J1503D01*
G37*
G36*
G01Y1349690D02*
X1651518D01*
G02Y1346684I0J-1503D01*
G01X1648118D01*
G02Y1349690I0J1503D01*
G37*
G36*
G01X1635878Y1409998D02*
X1639278D01*
G02Y1406992I0J-1503D01*
G01X1635878D01*
G02Y1409998I0J1503D01*
G37*
G36*
G01X1660358D02*
X1663758D01*
G02Y1406992I0J-1503D01*
G01X1660358D01*
G02Y1409998I0J1503D01*
G37*
G36*
G01X1672598D02*
X1675998D01*
G02Y1406992I0J-1503D01*
G01X1672598D01*
G02Y1409998I0J1503D01*
G37*
G36*
G01X1660358Y1398086D02*
X1663758D01*
G02Y1395080I0J-1503D01*
G01X1660358D01*
G02Y1398086I0J1503D01*
G37*
G36*
G01X1672598D02*
X1675998D01*
G02Y1395080I0J-1503D01*
G01X1672598D01*
G02Y1398086I0J1503D01*
G37*
G36*
G01X1660358Y1373888D02*
X1663758D01*
G02Y1370882I0J-1503D01*
G01X1660358D01*
G02Y1373888I0J1503D01*
G37*
G36*
G01Y1385800D02*
X1663758D01*
G02Y1382794I0J-1503D01*
G01X1660358D01*
G02Y1385800I0J1503D01*
G37*
G36*
G01X1672598Y1373888D02*
X1675998D01*
G02Y1370882I0J-1503D01*
G01X1672598D01*
G02Y1373888I0J1503D01*
G37*
G36*
G01X1328246Y1385800D02*
X1331646D01*
G02Y1382794I0J-1503D01*
G01X1328246D01*
G02Y1385800I0J1503D01*
G37*
G36*
G01X1672598D02*
X1675998D01*
G02Y1382794I0J-1503D01*
G01X1672598D01*
G02Y1385800I0J1503D01*
G37*
G36*
G01X174032Y1409998D02*
X177432D01*
G02Y1406992I0J-1503D01*
G01X174032D01*
G02Y1409998I0J1503D01*
G37*
G36*
G01X266103Y1385800D02*
X269503D01*
G02Y1382794I0J-1503D01*
G01X266103D01*
G02Y1385800I0J1503D01*
G37*
G36*
G01X315063D02*
X318463D01*
G02Y1382794I0J-1503D01*
G01X315063D01*
G02Y1385800I0J1503D01*
G37*
G36*
G01X278343Y1409998D02*
X281743D01*
G02Y1406992I0J-1503D01*
G01X278343D01*
G02Y1409998I0J1503D01*
G37*
G36*
G01X1328246Y1398086D02*
X1331646D01*
G02Y1395080I0J-1503D01*
G01X1328246D01*
G02Y1398086I0J1503D01*
G37*
G36*
G01X364023Y1409998D02*
X367423D01*
G02Y1406992I0J-1503D01*
G01X364023D01*
G02Y1409998I0J1503D01*
G37*
G36*
G01X266103D02*
X269503D01*
G02Y1406992I0J-1503D01*
G01X266103D01*
G02Y1409998I0J1503D01*
G37*
G36*
G01X1733798Y1385800D02*
X1737198D01*
G02Y1382794I0J-1503D01*
G01X1733798D01*
G02Y1385800I0J1503D01*
G37*
G36*
G01Y1373888D02*
X1737198D01*
G02Y1370882I0J-1503D01*
G01X1733798D01*
G02Y1373888I0J1503D01*
G37*
G36*
G01Y1398086D02*
X1737198D01*
G02Y1395080I0J-1503D01*
G01X1733798D01*
G02Y1398086I0J1503D01*
G37*
G36*
G01X1721558Y1373888D02*
X1724958D01*
G02Y1370882I0J-1503D01*
G01X1721558D01*
G02Y1373888I0J1503D01*
G37*
G36*
G01X290583D02*
X293983D01*
G02Y1370882I0J-1503D01*
G01X290583D01*
G02Y1373888I0J1503D01*
G37*
G36*
G01X1328246Y1409998D02*
X1331646D01*
G02Y1406992I0J-1503D01*
G01X1328246D01*
G02Y1409998I0J1503D01*
G37*
G36*
G01X1340486Y1349690D02*
X1343886D01*
G02Y1346684I0J-1503D01*
G01X1340486D01*
G02Y1349690I0J1503D01*
G37*
G36*
G01X1583770Y1373888D02*
X1587170D01*
G02Y1370882I0J-1503D01*
G01X1583770D01*
G02Y1373888I0J1503D01*
G37*
G36*
G01X1485850Y1349690D02*
X1489250D01*
G02Y1346684I0J-1503D01*
G01X1485850D01*
G02Y1349690I0J1503D01*
G37*
G36*
G01X1340486Y1361602D02*
X1343886D01*
G02Y1358596I0J-1503D01*
G01X1340486D01*
G02Y1361602I0J1503D01*
G37*
G36*
G01X1733798Y1409998D02*
X1737198D01*
G02Y1406992I0J-1503D01*
G01X1733798D01*
G02Y1409998I0J1503D01*
G37*
G36*
G01X278343Y1373888D02*
X281743D01*
G02Y1370882I0J-1503D01*
G01X278343D01*
G02Y1373888I0J1503D01*
G37*
G36*
G01X266103Y1398086D02*
X269503D01*
G02Y1395080I0J-1503D01*
G01X266103D01*
G02Y1398086I0J1503D01*
G37*
G36*
G01X1733798Y1349690D02*
X1737198D01*
G02Y1346684I0J-1503D01*
G01X1733798D01*
G02Y1349690I0J1503D01*
G37*
G36*
G01X137312Y1385800D02*
X140712D01*
G02Y1382794I0J-1503D01*
G01X137312D01*
G02Y1385800I0J1503D01*
G37*
G36*
G01X1721558Y1398086D02*
X1724958D01*
G02Y1395080I0J-1503D01*
G01X1721558D01*
G02Y1398086I0J1503D01*
G37*
G36*
G01X1340486Y1385800D02*
X1343886D01*
G02Y1382794I0J-1503D01*
G01X1340486D01*
G02Y1385800I0J1503D01*
G37*
G36*
G01Y1373888D02*
X1343886D01*
G02Y1370882I0J-1503D01*
G01X1340486D01*
G02Y1373888I0J1503D01*
G37*
G36*
G01X1721558Y1385800D02*
X1724958D01*
G02Y1382794I0J-1503D01*
G01X1721558D01*
G02Y1385800I0J1503D01*
G37*
G36*
G01X339543Y1398086D02*
X342943D01*
G02Y1395080I0J-1503D01*
G01X339543D01*
G02Y1398086I0J1503D01*
G37*
G36*
G01X327303Y1385800D02*
X330703D01*
G02Y1382794I0J-1503D01*
G01X327303D01*
G02Y1385800I0J1503D01*
G37*
G36*
G01X315063Y1373888D02*
X318463D01*
G02Y1370882I0J-1503D01*
G01X315063D01*
G02Y1373888I0J1503D01*
G37*
G36*
G01X339543D02*
X342943D01*
G02Y1370882I0J-1503D01*
G01X339543D01*
G02Y1373888I0J1503D01*
G37*
G36*
G01X351783Y1385800D02*
X355183D01*
G02Y1382794I0J-1503D01*
G01X351783D01*
G02Y1385800I0J1503D01*
G37*
G36*
G01Y1373888D02*
X355183D01*
G02Y1370882I0J-1503D01*
G01X351783D01*
G02Y1373888I0J1503D01*
G37*
G36*
G01Y1398086D02*
X355183D01*
G02Y1395080I0J-1503D01*
G01X351783D01*
G02Y1398086I0J1503D01*
G37*
G36*
G01Y1409998D02*
X355183D01*
G02Y1406992I0J-1503D01*
G01X351783D01*
G02Y1409998I0J1503D01*
G37*
G36*
G01X315063Y1398086D02*
X318463D01*
G02Y1395080I0J-1503D01*
G01X315063D01*
G02Y1398086I0J1503D01*
G37*
G36*
G01X278343Y1361602D02*
X281743D01*
G02Y1358596I0J-1503D01*
G01X278343D01*
G02Y1361602I0J1503D01*
G37*
G36*
G01X1498090Y1349690D02*
X1501490D01*
G02Y1346684I0J-1503D01*
G01X1498090D01*
G02Y1349690I0J1503D01*
G37*
G36*
G01X266103Y1361602D02*
X269503D01*
G02Y1358596I0J-1503D01*
G01X266103D01*
G02Y1361602I0J1503D01*
G37*
G36*
G01X35825Y1466648D02*
X39225D01*
G02Y1463044I0J-1802D01*
G01X35825D01*
G02Y1466648I0J1802D01*
G37*
G36*
G01X942699Y344560D02*
X939299D01*
G02Y348166I0J1803D01*
G01X942699D01*
G02Y344560I0J-1803D01*
G37*
G36*
G01X942730Y322242D02*
X939330D01*
G02Y325846I0J1802D01*
G01X942730D01*
G02Y322242I0J-1802D01*
G37*
G36*
G01X927963Y342238D02*
X924563D01*
G02Y345844I0J1803D01*
G01X927963D01*
G02Y342238I0J-1803D01*
G37*
G36*
G01X919353Y342348D02*
X915953D01*
G02Y345952I0J1802D01*
G01X919353D01*
G02Y342348I0J-1802D01*
G37*
G36*
G01X302823Y1398086D02*
X306223D01*
G02Y1395080I0J-1503D01*
G01X302823D01*
G02Y1398086I0J1503D01*
G37*
G36*
G01X389015Y794228D02*
X392415D01*
G02Y791222I0J-1503D01*
G01X389015D01*
G02Y794228I0J1503D01*
G37*
G36*
G01X302823Y1373888D02*
X306223D01*
G02Y1370882I0J-1503D01*
G01X302823D01*
G02Y1373888I0J1503D01*
G37*
G36*
G01X1534810Y1385800D02*
X1538210D01*
G02Y1382794I0J-1503D01*
G01X1534810D01*
G02Y1385800I0J1503D01*
G37*
G36*
G01X327303Y1398086D02*
X330703D01*
G02Y1395080I0J-1503D01*
G01X327303D01*
G02Y1398086I0J1503D01*
G37*
G36*
G01X339543Y1409998D02*
X342943D01*
G02Y1406992I0J-1503D01*
G01X339543D01*
G02Y1409998I0J1503D01*
G37*
G36*
G01X302823Y1385800D02*
X306223D01*
G02Y1382794I0J-1503D01*
G01X302823D01*
G02Y1385800I0J1503D01*
G37*
G36*
G01X278343D02*
X281743D01*
G02Y1382794I0J-1503D01*
G01X278343D01*
G02Y1385800I0J1503D01*
G37*
G36*
G01X1340486Y1398086D02*
X1343886D01*
G02Y1395080I0J-1503D01*
G01X1340486D01*
G02Y1398086I0J1503D01*
G37*
G36*
G01Y1409998D02*
X1343886D01*
G02Y1406992I0J-1503D01*
G01X1340486D01*
G02Y1409998I0J1503D01*
G37*
G36*
G01X1583770Y1385800D02*
X1587170D01*
G02Y1382794I0J-1503D01*
G01X1583770D01*
G02Y1385800I0J1503D01*
G37*
G36*
G01X1571530Y1349690D02*
X1574930D01*
G02Y1346684I0J-1503D01*
G01X1571530D01*
G02Y1349690I0J1503D01*
G37*
G36*
G01Y1373888D02*
X1574930D01*
G02Y1370882I0J-1503D01*
G01X1571530D01*
G02Y1373888I0J1503D01*
G37*
G36*
G01Y1385800D02*
X1574930D01*
G02Y1382794I0J-1503D01*
G01X1571530D01*
G02Y1385800I0J1503D01*
G37*
G36*
G01X1473610Y1398086D02*
X1477010D01*
G02Y1395080I0J-1503D01*
G01X1473610D01*
G02Y1398086I0J1503D01*
G37*
G36*
G01Y1409998D02*
X1477010D01*
G02Y1406992I0J-1503D01*
G01X1473610D01*
G02Y1409998I0J1503D01*
G37*
G36*
G01X1583770Y1398086D02*
X1587170D01*
G02Y1395080I0J-1503D01*
G01X1583770D01*
G02Y1398086I0J1503D01*
G37*
G36*
G01Y1409998D02*
X1587170D01*
G02Y1406992I0J-1503D01*
G01X1583770D01*
G02Y1409998I0J1503D01*
G37*
G36*
G01X1485850Y1398086D02*
X1489250D01*
G02Y1395080I0J-1503D01*
G01X1485850D01*
G02Y1398086I0J1503D01*
G37*
G36*
G01X1498090Y1373888D02*
X1501490D01*
G02Y1370882I0J-1503D01*
G01X1498090D01*
G02Y1373888I0J1503D01*
G37*
G36*
G01X1522570Y1361602D02*
X1525970D01*
G02Y1358596I0J-1503D01*
G01X1522570D01*
G02Y1361602I0J1503D01*
G37*
G36*
G01X1498090Y1409998D02*
X1501490D01*
G02Y1406992I0J-1503D01*
G01X1498090D01*
G02Y1409998I0J1503D01*
G37*
G36*
G01X1352726Y1349690D02*
X1356126D01*
G02Y1346684I0J-1503D01*
G01X1352726D01*
G02Y1349690I0J1503D01*
G37*
G36*
G01X1510330Y1398086D02*
X1513730D01*
G02Y1395080I0J-1503D01*
G01X1510330D01*
G02Y1398086I0J1503D01*
G37*
G36*
G01X1611398Y1361602D02*
X1614798D01*
G02Y1358596I0J-1503D01*
G01X1611398D01*
G02Y1361602I0J1503D01*
G37*
G36*
G01X1623638Y1373888D02*
X1627038D01*
G02Y1370882I0J-1503D01*
G01X1623638D01*
G02Y1373888I0J1503D01*
G37*
G36*
G01X1547050D02*
X1550450D01*
G02Y1370882I0J-1503D01*
G01X1547050D01*
G02Y1373888I0J1503D01*
G37*
G36*
G01X1352726Y1361602D02*
X1356126D01*
G02Y1358596I0J-1503D01*
G01X1352726D01*
G02Y1361602I0J1503D01*
G37*
G36*
G01Y1385800D02*
X1356126D01*
G02Y1382794I0J-1503D01*
G01X1352726D01*
G02Y1385800I0J1503D01*
G37*
G36*
G01Y1373888D02*
X1356126D01*
G02Y1370882I0J-1503D01*
G01X1352726D01*
G02Y1373888I0J1503D01*
G37*
G36*
G01X1684838Y1409998D02*
X1688238D01*
G02Y1406992I0J-1503D01*
G01X1684838D01*
G02Y1409998I0J1503D01*
G37*
G36*
G01X1709318Y1373888D02*
X1712718D01*
G02Y1370882I0J-1503D01*
G01X1709318D01*
G02Y1373888I0J1503D01*
G37*
G36*
G01Y1385800D02*
X1712718D01*
G02Y1382794I0J-1503D01*
G01X1709318D01*
G02Y1385800I0J1503D01*
G37*
G36*
G01X1733798Y1361602D02*
X1737198D01*
G02Y1358596I0J-1503D01*
G01X1733798D01*
G02Y1361602I0J1503D01*
G37*
G36*
G01X1697078Y1373888D02*
X1700478D01*
G02Y1370882I0J-1503D01*
G01X1697078D01*
G02Y1373888I0J1503D01*
G37*
G36*
G01X1709318Y1409998D02*
X1712718D01*
G02Y1406992I0J-1503D01*
G01X1709318D01*
G02Y1409998I0J1503D01*
G37*
G36*
G01X1697078Y1398086D02*
X1700478D01*
G02Y1395080I0J-1503D01*
G01X1697078D01*
G02Y1398086I0J1503D01*
G37*
G36*
G01X1709318D02*
X1712718D01*
G02Y1395080I0J-1503D01*
G01X1709318D01*
G02Y1398086I0J1503D01*
G37*
G36*
G01X1721558Y1349690D02*
X1724958D01*
G02Y1346684I0J-1503D01*
G01X1721558D01*
G02Y1349690I0J1503D01*
G37*
G36*
G01Y1361602D02*
X1724958D01*
G02Y1358596I0J-1503D01*
G01X1721558D01*
G02Y1361602I0J1503D01*
G37*
G36*
G01Y1409998D02*
X1724958D01*
G02Y1406992I0J-1503D01*
G01X1721558D01*
G02Y1409998I0J1503D01*
G37*
G36*
G01X1352726Y1398086D02*
X1356126D01*
G02Y1395080I0J-1503D01*
G01X1352726D01*
G02Y1398086I0J1503D01*
G37*
G36*
G01X174032Y1361602D02*
X177432D01*
G02Y1358596I0J-1503D01*
G01X174032D01*
G02Y1361602I0J1503D01*
G37*
G36*
G01X198512Y1349690D02*
X201912D01*
G02Y1346684I0J-1503D01*
G01X198512D01*
G02Y1349690I0J1503D01*
G37*
G36*
G01Y1398086D02*
X201912D01*
G02Y1395080I0J-1503D01*
G01X198512D01*
G02Y1398086I0J1503D01*
G37*
G36*
G01X186272D02*
X189672D01*
G02Y1395080I0J-1503D01*
G01X186272D01*
G02Y1398086I0J1503D01*
G37*
G36*
G01X161792Y1349690D02*
X165192D01*
G02Y1346684I0J-1503D01*
G01X161792D01*
G02Y1349690I0J1503D01*
G37*
G36*
G01X186272Y1361602D02*
X189672D01*
G02Y1358596I0J-1503D01*
G01X186272D01*
G02Y1361602I0J1503D01*
G37*
G36*
G01X100592Y1349690D02*
X103992D01*
G02Y1346684I0J-1503D01*
G01X100592D01*
G02Y1349690I0J1503D01*
G37*
G36*
G01X112832D02*
X116232D01*
G02Y1346684I0J-1503D01*
G01X112832D01*
G02Y1349690I0J1503D01*
G37*
G36*
G01X149552Y1398086D02*
X152952D01*
G02Y1395080I0J-1503D01*
G01X149552D01*
G02Y1398086I0J1503D01*
G37*
G36*
G01X161792D02*
X165192D01*
G02Y1395080I0J-1503D01*
G01X161792D01*
G02Y1398086I0J1503D01*
G37*
G36*
G01Y1373888D02*
X165192D01*
G02Y1370882I0J-1503D01*
G01X161792D01*
G02Y1373888I0J1503D01*
G37*
G36*
G01Y1385800D02*
X165192D01*
G02Y1382794I0J-1503D01*
G01X161792D01*
G02Y1385800I0J1503D01*
G37*
G36*
G01X198512Y1361602D02*
X201912D01*
G02Y1358596I0J-1503D01*
G01X198512D01*
G02Y1361602I0J1503D01*
G37*
G36*
G01X137312D02*
X140712D01*
G02Y1358596I0J-1503D01*
G01X137312D01*
G02Y1361602I0J1503D01*
G37*
G36*
G01X161792D02*
X165192D01*
G02Y1358596I0J-1503D01*
G01X161792D01*
G02Y1361602I0J1503D01*
G37*
G36*
G01X149552Y1349690D02*
X152952D01*
G02Y1346684I0J-1503D01*
G01X149552D01*
G02Y1349690I0J1503D01*
G37*
G36*
G01X137312D02*
X140712D01*
G02Y1346684I0J-1503D01*
G01X137312D01*
G02Y1349690I0J1503D01*
G37*
G36*
G01X76112Y1361602D02*
X79512D01*
G02Y1358596I0J-1503D01*
G01X76112D01*
G02Y1361602I0J1503D01*
G37*
G36*
G01X174032Y1385800D02*
X177432D01*
G02Y1382794I0J-1503D01*
G01X174032D01*
G02Y1385800I0J1503D01*
G37*
G36*
G01X125072Y1409998D02*
X128472D01*
G02Y1406992I0J-1503D01*
G01X125072D01*
G02Y1409998I0J1503D01*
G37*
G36*
G01Y1398086D02*
X128472D01*
G02Y1395080I0J-1503D01*
G01X125072D01*
G02Y1398086I0J1503D01*
G37*
G36*
G01Y1373888D02*
X128472D01*
G02Y1370882I0J-1503D01*
G01X125072D01*
G02Y1373888I0J1503D01*
G37*
G36*
G01Y1385800D02*
X128472D01*
G02Y1382794I0J-1503D01*
G01X125072D01*
G02Y1385800I0J1503D01*
G37*
G36*
G01X1571530Y1361602D02*
X1574930D01*
G02Y1358596I0J-1503D01*
G01X1571530D01*
G02Y1361602I0J1503D01*
G37*
G36*
G01X100592Y1385800D02*
X103992D01*
G02Y1382794I0J-1503D01*
G01X100592D01*
G02Y1385800I0J1503D01*
G37*
G36*
G01X76112Y1373888D02*
X79512D01*
G02Y1370882I0J-1503D01*
G01X76112D01*
G02Y1373888I0J1503D01*
G37*
G36*
G01X88352Y1409998D02*
X91752D01*
G02Y1406992I0J-1503D01*
G01X88352D01*
G02Y1409998I0J1503D01*
G37*
G36*
G01X149552D02*
X152952D01*
G02Y1406992I0J-1503D01*
G01X149552D01*
G02Y1409998I0J1503D01*
G37*
G36*
G01X137312Y1373888D02*
X140712D01*
G02Y1370882I0J-1503D01*
G01X137312D01*
G02Y1373888I0J1503D01*
G37*
G36*
G01X253863Y1385800D02*
X257263D01*
G02Y1382794I0J-1503D01*
G01X253863D01*
G02Y1385800I0J1503D01*
G37*
G36*
G01X186272Y1409998D02*
X189672D01*
G02Y1406992I0J-1503D01*
G01X186272D01*
G02Y1409998I0J1503D01*
G37*
G36*
G01X125072Y1361602D02*
X128472D01*
G02Y1358596I0J-1503D01*
G01X125072D01*
G02Y1361602I0J1503D01*
G37*
G36*
G01Y1349690D02*
X128472D01*
G02Y1346684I0J-1503D01*
G01X125072D01*
G02Y1349690I0J1503D01*
G37*
G36*
G01X149552Y1373888D02*
X152952D01*
G02Y1370882I0J-1503D01*
G01X149552D01*
G02Y1373888I0J1503D01*
G37*
G36*
G01X174032Y1349690D02*
X177432D01*
G02Y1346684I0J-1503D01*
G01X174032D01*
G02Y1349690I0J1503D01*
G37*
G36*
G01Y1373888D02*
X177432D01*
G02Y1370882I0J-1503D01*
G01X174032D01*
G02Y1373888I0J1503D01*
G37*
G36*
G01X76112Y1385800D02*
X79512D01*
G02Y1382794I0J-1503D01*
G01X76112D01*
G02Y1385800I0J1503D01*
G37*
G36*
G01X1583770Y1349690D02*
X1587170D01*
G02Y1346684I0J-1503D01*
G01X1583770D01*
G02Y1349690I0J1503D01*
G37*
G36*
G01X1697078Y1385800D02*
X1700478D01*
G02Y1382794I0J-1503D01*
G01X1697078D01*
G02Y1385800I0J1503D01*
G37*
G36*
G01X88352Y1361602D02*
X91752D01*
G02Y1358596I0J-1503D01*
G01X88352D01*
G02Y1361602I0J1503D01*
G37*
G36*
G01Y1349690D02*
X91752D01*
G02Y1346684I0J-1503D01*
G01X88352D01*
G02Y1349690I0J1503D01*
G37*
G36*
G01X1697078Y1409998D02*
X1700478D01*
G02Y1406992I0J-1503D01*
G01X1697078D01*
G02Y1409998I0J1503D01*
G37*
G36*
G01X112832Y1373888D02*
X116232D01*
G02Y1370882I0J-1503D01*
G01X112832D01*
G02Y1373888I0J1503D01*
G37*
G36*
G01Y1409998D02*
X116232D01*
G02Y1406992I0J-1503D01*
G01X112832D01*
G02Y1409998I0J1503D01*
G37*
G36*
G01X100592D02*
X103992D01*
G02Y1406992I0J-1503D01*
G01X100592D01*
G02Y1409998I0J1503D01*
G37*
G36*
G01X724208Y1385800D02*
X727608D01*
G02Y1382794I0J-1503D01*
G01X724208D01*
G02Y1385800I0J1503D01*
G37*
G36*
G01X88352D02*
X91752D01*
G02Y1382794I0J-1503D01*
G01X88352D01*
G02Y1385800I0J1503D01*
G37*
G36*
G01X760928Y1361602D02*
X764328D01*
G02Y1358596I0J-1503D01*
G01X760928D01*
G02Y1361602I0J1503D01*
G37*
G36*
G01X100592Y1373888D02*
X103992D01*
G02Y1370882I0J-1503D01*
G01X100592D01*
G02Y1373888I0J1503D01*
G37*
G36*
G01X137312Y1398086D02*
X140712D01*
G02Y1395080I0J-1503D01*
G01X137312D01*
G02Y1398086I0J1503D01*
G37*
G36*
G01Y1409998D02*
X140712D01*
G02Y1406992I0J-1503D01*
G01X137312D01*
G02Y1409998I0J1503D01*
G37*
G36*
G01X112832Y1385800D02*
X116232D01*
G02Y1382794I0J-1503D01*
G01X112832D01*
G02Y1385800I0J1503D01*
G37*
G36*
G01X663008Y1361602D02*
X666408D01*
G02Y1358596I0J-1503D01*
G01X663008D01*
G02Y1361602I0J1503D01*
G37*
G36*
G01X100592Y1398086D02*
X103992D01*
G02Y1395080I0J-1503D01*
G01X100592D01*
G02Y1398086I0J1503D01*
G37*
G36*
G01X748688Y1385800D02*
X752088D01*
G02Y1382794I0J-1503D01*
G01X748688D01*
G02Y1385800I0J1503D01*
G37*
G36*
G01X1352726Y1409998D02*
X1356126D01*
G02Y1406992I0J-1503D01*
G01X1352726D01*
G02Y1409998I0J1503D01*
G37*
G36*
G01X100592Y1361602D02*
X103992D01*
G02Y1358596I0J-1503D01*
G01X100592D01*
G02Y1361602I0J1503D01*
G37*
G36*
G01X112832D02*
X116232D01*
G02Y1358596I0J-1503D01*
G01X112832D01*
G02Y1361602I0J1503D01*
G37*
G36*
G01X88352Y1398086D02*
X91752D01*
G02Y1395080I0J-1503D01*
G01X88352D01*
G02Y1398086I0J1503D01*
G37*
G36*
G01X1660358Y1361602D02*
X1663758D01*
G02Y1358596I0J-1503D01*
G01X1660358D01*
G02Y1361602I0J1503D01*
G37*
G36*
G01X1066953Y1349690D02*
X1070353D01*
G02Y1346684I0J-1503D01*
G01X1066953D01*
G02Y1349690I0J1503D01*
G37*
G36*
G01X663008D02*
X666408D01*
G02Y1346684I0J-1503D01*
G01X663008D01*
G02Y1349690I0J1503D01*
G37*
G36*
G01X1583770Y1361602D02*
X1587170D01*
G02Y1358596I0J-1503D01*
G01X1583770D01*
G02Y1361602I0J1503D01*
G37*
G36*
G01X1571530Y1398086D02*
X1574930D01*
G02Y1395080I0J-1503D01*
G01X1571530D01*
G02Y1398086I0J1503D01*
G37*
G36*
G01X1559290Y1361602D02*
X1562690D01*
G02Y1358596I0J-1503D01*
G01X1559290D01*
G02Y1361602I0J1503D01*
G37*
G36*
G01Y1373888D02*
X1562690D01*
G02Y1370882I0J-1503D01*
G01X1559290D01*
G02Y1373888I0J1503D01*
G37*
G36*
G01X1623638Y1385800D02*
X1627038D01*
G02Y1382794I0J-1503D01*
G01X1623638D01*
G02Y1385800I0J1503D01*
G37*
G36*
G01X76112Y1349690D02*
X79512D01*
G02Y1346684I0J-1503D01*
G01X76112D01*
G02Y1349690I0J1503D01*
G37*
G36*
G01X1066953Y1361602D02*
X1070353D01*
G02Y1358596I0J-1503D01*
G01X1066953D01*
G02Y1361602I0J1503D01*
G37*
G36*
G01X1547050Y1385800D02*
X1550450D01*
G02Y1382794I0J-1503D01*
G01X1547050D01*
G02Y1385800I0J1503D01*
G37*
G36*
G01X1672598Y1349690D02*
X1675998D01*
G02Y1346684I0J-1503D01*
G01X1672598D01*
G02Y1349690I0J1503D01*
G37*
G36*
G01X1660358D02*
X1663758D01*
G02Y1346684I0J-1503D01*
G01X1660358D01*
G02Y1349690I0J1503D01*
G37*
G36*
G01X1672598Y1361602D02*
X1675998D01*
G02Y1358596I0J-1503D01*
G01X1672598D01*
G02Y1361602I0J1503D01*
G37*
G36*
G01X1709318Y1349690D02*
X1712718D01*
G02Y1346684I0J-1503D01*
G01X1709318D01*
G02Y1349690I0J1503D01*
G37*
G36*
G01X1697078D02*
X1700478D01*
G02Y1346684I0J-1503D01*
G01X1697078D01*
G02Y1349690I0J1503D01*
G37*
G36*
G01X1684838Y1385800D02*
X1688238D01*
G02Y1382794I0J-1503D01*
G01X1684838D01*
G02Y1385800I0J1503D01*
G37*
G36*
G01X1709318Y1361602D02*
X1712718D01*
G02Y1358596I0J-1503D01*
G01X1709318D01*
G02Y1361602I0J1503D01*
G37*
G36*
G01X1697078D02*
X1700478D01*
G02Y1358596I0J-1503D01*
G01X1697078D01*
G02Y1361602I0J1503D01*
G37*
G36*
G01X1684838D02*
X1688238D01*
G02Y1358596I0J-1503D01*
G01X1684838D01*
G02Y1361602I0J1503D01*
G37*
G36*
G01Y1373888D02*
X1688238D01*
G02Y1370882I0J-1503D01*
G01X1684838D01*
G02Y1373888I0J1503D01*
G37*
G36*
G01Y1398086D02*
X1688238D01*
G02Y1395080I0J-1503D01*
G01X1684838D01*
G02Y1398086I0J1503D01*
G37*
G36*
G01X1066953Y1373888D02*
X1070353D01*
G02Y1370882I0J-1503D01*
G01X1066953D01*
G02Y1373888I0J1503D01*
G37*
G36*
G01Y1385800D02*
X1070353D01*
G02Y1382794I0J-1503D01*
G01X1066953D01*
G02Y1385800I0J1503D01*
G37*
G36*
G01X1547050Y1398086D02*
X1550450D01*
G02Y1395080I0J-1503D01*
G01X1547050D01*
G02Y1398086I0J1503D01*
G37*
G36*
G01X549168Y783102D02*
G02Y780098I0J-1502D01*
G01X545813D01*
X545808D01*
G02X545944Y783092I-38J1502D01*
G01X545956Y783090D01*
X548978D01*
X548990Y783092D01*
G02X549168Y783102I173J-1492D01*
G37*
G36*
G01X278343Y1349690D02*
X281743D01*
G02Y1346684I0J-1503D01*
G01X278343D01*
G02Y1349690I0J1503D01*
G37*
G36*
G01X945982Y888540D02*
X949382D01*
G02Y884936I0J-1802D01*
G01X945982D01*
G02Y888540I0J1802D01*
G37*
G36*
G01X1684838Y1349690D02*
X1688238D01*
G02Y1346684I0J-1503D01*
G01X1684838D01*
G02Y1349690I0J1503D01*
G37*
G36*
G01X1571530Y1409998D02*
X1574930D01*
G02Y1406992I0J-1503D01*
G01X1571530D01*
G02Y1409998I0J1503D01*
G37*
G36*
G01X1473610Y1373888D02*
X1477010D01*
G02Y1370882I0J-1503D01*
G01X1473610D01*
G02Y1373888I0J1503D01*
G37*
G36*
G01X1498090Y1398086D02*
X1501490D01*
G02Y1395080I0J-1503D01*
G01X1498090D01*
G02Y1398086I0J1503D01*
G37*
G36*
G01Y1385800D02*
X1501490D01*
G02Y1382794I0J-1503D01*
G01X1498090D01*
G02Y1385800I0J1503D01*
G37*
G36*
G01X1510330Y1409998D02*
X1513730D01*
G02Y1406992I0J-1503D01*
G01X1510330D01*
G02Y1409998I0J1503D01*
G37*
G36*
G01X1522570Y1349690D02*
X1525970D01*
G02Y1346684I0J-1503D01*
G01X1522570D01*
G02Y1349690I0J1503D01*
G37*
G36*
G01X146948Y1135604D02*
X143208D01*
G02Y1138210I0J1303D01*
G01X146948D01*
G02Y1135604I0J-1303D01*
G37*
G36*
G01X165649Y1131864D02*
X161909D01*
G02Y1134470I0J1303D01*
G01X165649D01*
G02Y1131864I0J-1303D01*
G37*
G36*
G01X154429D02*
X150689D01*
G02Y1134470I0J1303D01*
G01X154429D01*
G02Y1131864I0J-1303D01*
G37*
G36*
G01X173129Y1135604D02*
X169389D01*
G02Y1138210I0J1303D01*
G01X173129D01*
G02Y1135604I0J-1303D01*
G37*
G36*
G01X440402Y1361602D02*
X443802D01*
G02Y1358596I0J-1503D01*
G01X440402D01*
G02Y1361602I0J1503D01*
G37*
G36*
G01Y1349690D02*
X443802D01*
G02Y1346684I0J-1503D01*
G01X440402D01*
G02Y1349690I0J1503D01*
G37*
G36*
G01X452642Y1361602D02*
X456042D01*
G02Y1358596I0J-1503D01*
G01X452642D01*
G02Y1361602I0J1503D01*
G37*
G36*
G01Y1349690D02*
X456042D01*
G02Y1346684I0J-1503D01*
G01X452642D01*
G02Y1349690I0J1503D01*
G37*
G36*
G01X501602Y1385800D02*
X505002D01*
G02Y1382794I0J-1503D01*
G01X501602D01*
G02Y1385800I0J1503D01*
G37*
G36*
G01X513842D02*
X517242D01*
G02Y1382794I0J-1503D01*
G01X513842D01*
G02Y1385800I0J1503D01*
G37*
G36*
G01Y1373888D02*
X517242D01*
G02Y1370882I0J-1503D01*
G01X513842D01*
G02Y1373888I0J1503D01*
G37*
G36*
G01X501602D02*
X505002D01*
G02Y1370882I0J-1503D01*
G01X501602D01*
G02Y1373888I0J1503D01*
G37*
G36*
G01X464882Y1349690D02*
X468282D01*
G02Y1346684I0J-1503D01*
G01X464882D01*
G02Y1349690I0J1503D01*
G37*
G36*
G01X477122D02*
X480522D01*
G02Y1346684I0J-1503D01*
G01X477122D01*
G02Y1349690I0J1503D01*
G37*
G36*
G01X526082Y1385800D02*
X529482D01*
G02Y1382794I0J-1503D01*
G01X526082D01*
G02Y1385800I0J1503D01*
G37*
G36*
G01X538322D02*
X541722D01*
G02Y1382794I0J-1503D01*
G01X538322D01*
G02Y1385800I0J1503D01*
G37*
G36*
G01X526082Y1373888D02*
X529482D01*
G02Y1370882I0J-1503D01*
G01X526082D01*
G02Y1373888I0J1503D01*
G37*
G36*
G01X538322D02*
X541722D01*
G02Y1370882I0J-1503D01*
G01X538322D01*
G02Y1373888I0J1503D01*
G37*
G36*
G01X464882Y1361602D02*
X468282D01*
G02Y1358596I0J-1503D01*
G01X464882D01*
G02Y1361602I0J1503D01*
G37*
G36*
G01X477122D02*
X480522D01*
G02Y1358596I0J-1503D01*
G01X477122D01*
G02Y1361602I0J1503D01*
G37*
G36*
G01X489362Y1349690D02*
X492762D01*
G02Y1346684I0J-1503D01*
G01X489362D01*
G02Y1349690I0J1503D01*
G37*
G36*
G01X440402Y1373888D02*
X443802D01*
G02Y1370882I0J-1503D01*
G01X440402D01*
G02Y1373888I0J1503D01*
G37*
G36*
G01X550562Y1385800D02*
X553962D01*
G02Y1382794I0J-1503D01*
G01X550562D01*
G02Y1385800I0J1503D01*
G37*
G36*
G01Y1373888D02*
X553962D01*
G02Y1370882I0J-1503D01*
G01X550562D01*
G02Y1373888I0J1503D01*
G37*
G36*
G01X489362Y1361602D02*
X492762D01*
G02Y1358596I0J-1503D01*
G01X489362D01*
G02Y1361602I0J1503D01*
G37*
G36*
G01X440402Y1385800D02*
X443802D01*
G02Y1382794I0J-1503D01*
G01X440402D01*
G02Y1385800I0J1503D01*
G37*
G36*
G01X452642Y1373888D02*
X456042D01*
G02Y1370882I0J-1503D01*
G01X452642D01*
G02Y1373888I0J1503D01*
G37*
G36*
G01X562802Y1385800D02*
X566202D01*
G02Y1382794I0J-1503D01*
G01X562802D01*
G02Y1385800I0J1503D01*
G37*
G36*
G01X452642Y1409998D02*
X456042D01*
G02Y1406992I0J-1503D01*
G01X452642D01*
G02Y1409998I0J1503D01*
G37*
G36*
G01Y1398086D02*
X456042D01*
G02Y1395080I0J-1503D01*
G01X452642D01*
G02Y1398086I0J1503D01*
G37*
G36*
G01X562802Y1373888D02*
X566202D01*
G02Y1370882I0J-1503D01*
G01X562802D01*
G02Y1373888I0J1503D01*
G37*
G36*
G01X452642Y1385800D02*
X456042D01*
G02Y1382794I0J-1503D01*
G01X452642D01*
G02Y1385800I0J1503D01*
G37*
G36*
G01X464882Y1409998D02*
X468282D01*
G02Y1406992I0J-1503D01*
G01X464882D01*
G02Y1409998I0J1503D01*
G37*
G36*
G01Y1398086D02*
X468282D01*
G02Y1395080I0J-1503D01*
G01X464882D01*
G02Y1398086I0J1503D01*
G37*
G36*
G01Y1385800D02*
X468282D01*
G02Y1382794I0J-1503D01*
G01X464882D01*
G02Y1385800I0J1503D01*
G37*
G36*
G01X477122D02*
X480522D01*
G02Y1382794I0J-1503D01*
G01X477122D01*
G02Y1385800I0J1503D01*
G37*
G36*
G01Y1373888D02*
X480522D01*
G02Y1370882I0J-1503D01*
G01X477122D01*
G02Y1373888I0J1503D01*
G37*
G36*
G01X464882D02*
X468282D01*
G02Y1370882I0J-1503D01*
G01X464882D01*
G02Y1373888I0J1503D01*
G37*
G36*
G01X489362D02*
X492762D01*
G02Y1370882I0J-1503D01*
G01X489362D01*
G02Y1373888I0J1503D01*
G37*
G36*
G01Y1409998D02*
X492762D01*
G02Y1406992I0J-1503D01*
G01X489362D01*
G02Y1409998I0J1503D01*
G37*
G36*
G01Y1398086D02*
X492762D01*
G02Y1395080I0J-1503D01*
G01X489362D01*
G02Y1398086I0J1503D01*
G37*
G36*
G01X477122Y1409998D02*
X480522D01*
G02Y1406992I0J-1503D01*
G01X477122D01*
G02Y1409998I0J1503D01*
G37*
G36*
G01Y1398086D02*
X480522D01*
G02Y1395080I0J-1503D01*
G01X477122D01*
G02Y1398086I0J1503D01*
G37*
G36*
G01X489362Y1385800D02*
X492762D01*
G02Y1382794I0J-1503D01*
G01X489362D01*
G02Y1385800I0J1503D01*
G37*
G36*
G01X501602Y1361602D02*
X505002D01*
G02Y1358596I0J-1503D01*
G01X501602D01*
G02Y1361602I0J1503D01*
G37*
G36*
G01X513842D02*
X517242D01*
G02Y1358596I0J-1503D01*
G01X513842D01*
G02Y1361602I0J1503D01*
G37*
G36*
G01X501602Y1349690D02*
X505002D01*
G02Y1346684I0J-1503D01*
G01X501602D01*
G02Y1349690I0J1503D01*
G37*
G36*
G01X513842D02*
X517242D01*
G02Y1346684I0J-1503D01*
G01X513842D01*
G02Y1349690I0J1503D01*
G37*
G36*
G01X501602Y1398086D02*
X505002D01*
G02Y1395080I0J-1503D01*
G01X501602D01*
G02Y1398086I0J1503D01*
G37*
G36*
G01Y1409998D02*
X505002D01*
G02Y1406992I0J-1503D01*
G01X501602D01*
G02Y1409998I0J1503D01*
G37*
G36*
G01X526082Y1361602D02*
X529482D01*
G02Y1358596I0J-1503D01*
G01X526082D01*
G02Y1361602I0J1503D01*
G37*
G36*
G01Y1349690D02*
X529482D01*
G02Y1346684I0J-1503D01*
G01X526082D01*
G02Y1349690I0J1503D01*
G37*
G36*
G01X513842Y1398086D02*
X517242D01*
G02Y1395080I0J-1503D01*
G01X513842D01*
G02Y1398086I0J1503D01*
G37*
G36*
G01X526082Y1409998D02*
X529482D01*
G02Y1406992I0J-1503D01*
G01X526082D01*
G02Y1409998I0J1503D01*
G37*
G36*
G01X513842D02*
X517242D01*
G02Y1406992I0J-1503D01*
G01X513842D01*
G02Y1409998I0J1503D01*
G37*
G36*
G01X526082Y1398086D02*
X529482D01*
G02Y1395080I0J-1503D01*
G01X526082D01*
G02Y1398086I0J1503D01*
G37*
G36*
G01X538322Y1361602D02*
X541722D01*
G02Y1358596I0J-1503D01*
G01X538322D01*
G02Y1361602I0J1503D01*
G37*
G36*
G01X550562D02*
X553962D01*
G02Y1358596I0J-1503D01*
G01X550562D01*
G02Y1361602I0J1503D01*
G37*
G36*
G01X538322Y1349690D02*
X541722D01*
G02Y1346684I0J-1503D01*
G01X538322D01*
G02Y1349690I0J1503D01*
G37*
G36*
G01X550562D02*
X553962D01*
G02Y1346684I0J-1503D01*
G01X550562D01*
G02Y1349690I0J1503D01*
G37*
G36*
G01X538322Y1398086D02*
X541722D01*
G02Y1395080I0J-1503D01*
G01X538322D01*
G02Y1398086I0J1503D01*
G37*
G36*
G01Y1409998D02*
X541722D01*
G02Y1406992I0J-1503D01*
G01X538322D01*
G02Y1409998I0J1503D01*
G37*
G36*
G01X562802Y1361602D02*
X566202D01*
G02Y1358596I0J-1503D01*
G01X562802D01*
G02Y1361602I0J1503D01*
G37*
G36*
G01Y1349690D02*
X566202D01*
G02Y1346684I0J-1503D01*
G01X562802D01*
G02Y1349690I0J1503D01*
G37*
G36*
G01X550562Y1398086D02*
X553962D01*
G02Y1395080I0J-1503D01*
G01X550562D01*
G02Y1398086I0J1503D01*
G37*
G36*
G01X562802D02*
X566202D01*
G02Y1395080I0J-1503D01*
G01X562802D01*
G02Y1398086I0J1503D01*
G37*
G36*
G01X550562Y1409998D02*
X553962D01*
G02Y1406992I0J-1503D01*
G01X550562D01*
G02Y1409998I0J1503D01*
G37*
G36*
G01X562802D02*
X566202D01*
G02Y1406992I0J-1503D01*
G01X562802D01*
G02Y1409998I0J1503D01*
G37*
G36*
G01X650768Y1361602D02*
X654168D01*
G02Y1358596I0J-1503D01*
G01X650768D01*
G02Y1361602I0J1503D01*
G37*
G36*
G01Y1349690D02*
X654168D01*
G02Y1346684I0J-1503D01*
G01X650768D01*
G02Y1349690I0J1503D01*
G37*
G36*
G01X626288Y1409998D02*
X629688D01*
G02Y1406992I0J-1503D01*
G01X626288D01*
G02Y1409998I0J1503D01*
G37*
G36*
G01X638528Y1385800D02*
X641928D01*
G02Y1382794I0J-1503D01*
G01X638528D01*
G02Y1385800I0J1503D01*
G37*
G36*
G01Y1373888D02*
X641928D01*
G02Y1370882I0J-1503D01*
G01X638528D01*
G02Y1373888I0J1503D01*
G37*
G36*
G01X626288Y1398086D02*
X629688D01*
G02Y1395080I0J-1503D01*
G01X626288D01*
G02Y1398086I0J1503D01*
G37*
G36*
G01X675248Y1361602D02*
X678648D01*
G02Y1358596I0J-1503D01*
G01X675248D01*
G02Y1361602I0J1503D01*
G37*
G36*
G01X650768Y1385800D02*
X654168D01*
G02Y1382794I0J-1503D01*
G01X650768D01*
G02Y1385800I0J1503D01*
G37*
G36*
G01X675248Y1349690D02*
X678648D01*
G02Y1346684I0J-1503D01*
G01X675248D01*
G02Y1349690I0J1503D01*
G37*
G36*
G01X650768Y1373888D02*
X654168D01*
G02Y1370882I0J-1503D01*
G01X650768D01*
G02Y1373888I0J1503D01*
G37*
G36*
G01X638528Y1409998D02*
X641928D01*
G02Y1406992I0J-1503D01*
G01X638528D01*
G02Y1409998I0J1503D01*
G37*
G36*
G01Y1398086D02*
X641928D01*
G02Y1395080I0J-1503D01*
G01X638528D01*
G02Y1398086I0J1503D01*
G37*
G36*
G01X687488Y1361602D02*
X690888D01*
G02Y1358596I0J-1503D01*
G01X687488D01*
G02Y1361602I0J1503D01*
G37*
G36*
G01Y1349690D02*
X690888D01*
G02Y1346684I0J-1503D01*
G01X687488D01*
G02Y1349690I0J1503D01*
G37*
G36*
G01X663008Y1385800D02*
X666408D01*
G02Y1382794I0J-1503D01*
G01X663008D01*
G02Y1385800I0J1503D01*
G37*
G36*
G01X650768Y1409998D02*
X654168D01*
G02Y1406992I0J-1503D01*
G01X650768D01*
G02Y1409998I0J1503D01*
G37*
G36*
G01X663008Y1373888D02*
X666408D01*
G02Y1370882I0J-1503D01*
G01X663008D01*
G02Y1373888I0J1503D01*
G37*
G36*
G01X650768Y1398086D02*
X654168D01*
G02Y1395080I0J-1503D01*
G01X650768D01*
G02Y1398086I0J1503D01*
G37*
G36*
G01X699728Y1361602D02*
X703128D01*
G02Y1358596I0J-1503D01*
G01X699728D01*
G02Y1361602I0J1503D01*
G37*
G36*
G01X687488Y1385800D02*
X690888D01*
G02Y1382794I0J-1503D01*
G01X687488D01*
G02Y1385800I0J1503D01*
G37*
G36*
G01X699728Y1349690D02*
X703128D01*
G02Y1346684I0J-1503D01*
G01X699728D01*
G02Y1349690I0J1503D01*
G37*
G36*
G01X687488Y1373888D02*
X690888D01*
G02Y1370882I0J-1503D01*
G01X687488D01*
G02Y1373888I0J1503D01*
G37*
G36*
G01X675248Y1385800D02*
X678648D01*
G02Y1382794I0J-1503D01*
G01X675248D01*
G02Y1385800I0J1503D01*
G37*
G36*
G01Y1373888D02*
X678648D01*
G02Y1370882I0J-1503D01*
G01X675248D01*
G02Y1373888I0J1503D01*
G37*
G36*
G01X711968Y1349690D02*
X715368D01*
G02Y1346684I0J-1503D01*
G01X711968D01*
G02Y1349690I0J1503D01*
G37*
G36*
G01Y1361602D02*
X715368D01*
G02Y1358596I0J-1503D01*
G01X711968D01*
G02Y1361602I0J1503D01*
G37*
G36*
G01X663008Y1409998D02*
X666408D01*
G02Y1406992I0J-1503D01*
G01X663008D01*
G02Y1409998I0J1503D01*
G37*
G36*
G01X699728Y1385800D02*
X703128D01*
G02Y1382794I0J-1503D01*
G01X699728D01*
G02Y1385800I0J1503D01*
G37*
G36*
G01Y1373888D02*
X703128D01*
G02Y1370882I0J-1503D01*
G01X699728D01*
G02Y1373888I0J1503D01*
G37*
G36*
G01X663008Y1398086D02*
X666408D01*
G02Y1395080I0J-1503D01*
G01X663008D01*
G02Y1398086I0J1503D01*
G37*
G36*
G01X724208Y1397992D02*
X727608D01*
G02Y1394986I0J-1503D01*
G01X724208D01*
G02Y1397992I0J1503D01*
G37*
G36*
G01Y1349690D02*
X727608D01*
G02Y1346684I0J-1503D01*
G01X724208D01*
G02Y1349690I0J1503D01*
G37*
G36*
G01X675248Y1409998D02*
X678648D01*
G02Y1406992I0J-1503D01*
G01X675248D01*
G02Y1409998I0J1503D01*
G37*
G36*
G01Y1398086D02*
X678648D01*
G02Y1395080I0J-1503D01*
G01X675248D01*
G02Y1398086I0J1503D01*
G37*
G36*
G01X724208Y1361602D02*
X727608D01*
G02Y1358596I0J-1503D01*
G01X724208D01*
G02Y1361602I0J1503D01*
G37*
G36*
G01Y1409904D02*
X727608D01*
G02Y1406898I0J-1503D01*
G01X724208D01*
G02Y1409904I0J1503D01*
G37*
G36*
G01X736448Y1349690D02*
X739848D01*
G02Y1346684I0J-1503D01*
G01X736448D01*
G02Y1349690I0J1503D01*
G37*
G36*
G01X711968Y1373888D02*
X715368D01*
G02Y1370882I0J-1503D01*
G01X711968D01*
G02Y1373888I0J1503D01*
G37*
G36*
G01X736448Y1361602D02*
X739848D01*
G02Y1358596I0J-1503D01*
G01X736448D01*
G02Y1361602I0J1503D01*
G37*
G36*
G01X711968Y1385800D02*
X715368D01*
G02Y1382794I0J-1503D01*
G01X711968D01*
G02Y1385800I0J1503D01*
G37*
G36*
G01X687488Y1409998D02*
X690888D01*
G02Y1406992I0J-1503D01*
G01X687488D01*
G02Y1409998I0J1503D01*
G37*
G36*
G01Y1398086D02*
X690888D01*
G02Y1395080I0J-1503D01*
G01X687488D01*
G02Y1398086I0J1503D01*
G37*
G36*
G01X736448Y1373888D02*
X739848D01*
G02Y1370882I0J-1503D01*
G01X736448D01*
G02Y1373888I0J1503D01*
G37*
G36*
G01X748688Y1349690D02*
X752088D01*
G02Y1346684I0J-1503D01*
G01X748688D01*
G02Y1349690I0J1503D01*
G37*
G36*
G01X724208Y1373888D02*
X727608D01*
G02Y1370882I0J-1503D01*
G01X724208D01*
G02Y1373888I0J1503D01*
G37*
G36*
G01X736448Y1385800D02*
X739848D01*
G02Y1382794I0J-1503D01*
G01X736448D01*
G02Y1385800I0J1503D01*
G37*
G36*
G01X748688Y1361602D02*
X752088D01*
G02Y1358596I0J-1503D01*
G01X748688D01*
G02Y1361602I0J1503D01*
G37*
G36*
G01X736448Y1409904D02*
X739848D01*
G02Y1406898I0J-1503D01*
G01X736448D01*
G02Y1409904I0J1503D01*
G37*
G36*
G01Y1397992D02*
X739848D01*
G02Y1394986I0J-1503D01*
G01X736448D01*
G02Y1397992I0J1503D01*
G37*
G36*
G01X699728Y1409998D02*
X703128D01*
G02Y1406992I0J-1503D01*
G01X699728D01*
G02Y1409998I0J1503D01*
G37*
G36*
G01Y1398086D02*
X703128D01*
G02Y1395080I0J-1503D01*
G01X699728D01*
G02Y1398086I0J1503D01*
G37*
G36*
G01X748688Y1373888D02*
X752088D01*
G02Y1370882I0J-1503D01*
G01X748688D01*
G02Y1373888I0J1503D01*
G37*
G36*
G01X773168Y1349690D02*
X776568D01*
G02Y1346684I0J-1503D01*
G01X773168D01*
G02Y1349690I0J1503D01*
G37*
G36*
G01X760928D02*
X764328D01*
G02Y1346684I0J-1503D01*
G01X760928D01*
G02Y1349690I0J1503D01*
G37*
G36*
G01X711968Y1409998D02*
X715368D01*
G02Y1406992I0J-1503D01*
G01X711968D01*
G02Y1409998I0J1503D01*
G37*
G36*
G01Y1398086D02*
X715368D01*
G02Y1395080I0J-1503D01*
G01X711968D01*
G02Y1398086I0J1503D01*
G37*
G36*
G01X773168Y1361602D02*
X776568D01*
G02Y1358596I0J-1503D01*
G01X773168D01*
G02Y1361602I0J1503D01*
G37*
G36*
G01X760928Y1373888D02*
X764328D01*
G02Y1370882I0J-1503D01*
G01X760928D01*
G02Y1373888I0J1503D01*
G37*
G36*
G01Y1385800D02*
X764328D01*
G02Y1382794I0J-1503D01*
G01X760928D01*
G02Y1385800I0J1503D01*
G37*
G36*
G01X149552D02*
X152952D01*
G02Y1382794I0J-1503D01*
G01X149552D01*
G02Y1385800I0J1503D01*
G37*
G36*
G01Y1361602D02*
X152952D01*
G02Y1358596I0J-1503D01*
G01X149552D01*
G02Y1361602I0J1503D01*
G37*
G36*
G01X253863Y1373888D02*
X257263D01*
G02Y1370882I0J-1503D01*
G01X253863D01*
G02Y1373888I0J1503D01*
G37*
G36*
G01X198512D02*
X201912D01*
G02Y1370882I0J-1503D01*
G01X198512D01*
G02Y1373888I0J1503D01*
G37*
G36*
G01Y1409998D02*
X201912D01*
G02Y1406992I0J-1503D01*
G01X198512D01*
G02Y1409998I0J1503D01*
G37*
G36*
G01X364023Y1349690D02*
X367423D01*
G02Y1346684I0J-1503D01*
G01X364023D01*
G02Y1349690I0J1503D01*
G37*
G54D74*
X978614Y1210568D03*
Y1214838D03*
X914637Y1210568D03*
Y1214838D03*
X70947Y1201565D03*
Y1205835D03*
X1822594Y1211054D03*
Y1215324D03*
G54D80*
X665748Y1101376D03*
X748030Y1086417D03*
X751771Y1078936D03*
X658268Y1101376D03*
X740550Y1086416D03*
X744290Y1097637D03*
X748031Y1105117D03*
X688189Y1086417D03*
Y1082677D03*
X766731Y1075196D03*
X740550Y1082676D03*
X748030Y1082677D03*
X744290Y1078936D03*
Y1093897D03*
X740551Y1101376D03*
X751771Y1097637D03*
Y1093897D03*
X748031Y1101376D03*
X740551Y1105117D03*
X320866Y1221062D03*
X313385Y1209842D03*
X320866Y1213582D03*
X324606Y1221062D03*
X313385Y1217322D03*
X317125Y1236023D03*
X313385Y1224803D03*
X324606Y1228543D03*
X317125Y1232283D03*
X313385Y1228543D03*
X320866D03*
X324606Y1239763D03*
X313385Y1247243D03*
X320866D03*
X317125Y1250984D03*
X320866Y1239763D03*
X313385Y1243503D03*
X324606Y1247243D03*
X317125Y1254724D03*
X320866Y1198621D03*
X313385Y1202362D03*
X324606Y1198621D03*
X317125Y1202362D03*
X320866Y1206102D03*
X324606D03*
X317125Y1217322D03*
Y1209842D03*
X324606Y1213582D03*
X313385Y1120078D03*
X324606Y1123818D03*
X317125Y1112598D03*
X324606Y1116338D03*
X313385Y1112598D03*
X317125Y1120078D03*
X320866Y1116338D03*
Y1123818D03*
X313385Y1127558D03*
X317125Y1135039D03*
X313385D03*
X324606Y1131299D03*
X317125Y1127558D03*
X320866Y1131299D03*
Y1090157D03*
X317125Y1093897D03*
X324606Y1090157D03*
Y1082676D03*
X317124Y1078936D03*
X313384Y1082677D03*
Y1086417D03*
X320866Y1082676D03*
X313385Y1101377D03*
X320866D03*
X324606D03*
X317125Y1097637D03*
X324606Y1108858D03*
X320866D03*
X317124Y1075196D03*
X305905Y1224803D03*
X302165Y1236023D03*
X294685Y1250984D03*
X298425Y1247243D03*
X309645Y1250984D03*
X298425Y1243503D03*
X305905D03*
Y1247243D03*
X302165Y1250984D03*
X294685Y1254724D03*
X309645D03*
X302165D03*
X298425Y1213582D03*
X305905Y1209842D03*
Y1217322D03*
X302165Y1209842D03*
X298425Y1206102D03*
X302165Y1217322D03*
Y1232283D03*
X309645D03*
X294685Y1236023D03*
X298425Y1224803D03*
X294685Y1232283D03*
X298425Y1228543D03*
X309645Y1236023D03*
X305905Y1228543D03*
Y1127559D03*
Y1135039D03*
X302165D03*
Y1127559D03*
X298425Y1123818D03*
Y1131299D03*
Y1198621D03*
X305905Y1202362D03*
X302165D03*
X298425Y1105117D03*
Y1101376D03*
X309644Y1097637D03*
X302164D03*
X305905Y1105117D03*
X294684Y1097637D03*
X313385Y1105117D03*
X305905Y1101376D03*
X302165Y1120078D03*
X305905Y1112598D03*
X298425Y1116338D03*
X305905Y1120078D03*
X302165Y1112598D03*
X294684Y1093897D03*
X309644D03*
X302164D03*
X305904Y1082677D03*
X302164Y1078936D03*
X305904Y1086417D03*
X294684Y1078936D03*
X309644D03*
X298424Y1086416D03*
Y1082676D03*
X294684Y1075196D03*
X302164D03*
X309644D03*
X283464Y1243503D03*
X279724Y1250984D03*
X283464Y1247243D03*
X287204Y1250984D03*
X290944Y1247243D03*
Y1243503D03*
X287204Y1254724D03*
X279724D03*
X294685Y1213582D03*
Y1206102D03*
X279724Y1232283D03*
Y1236023D03*
X287204Y1232283D03*
X283464Y1224803D03*
Y1228543D03*
X287204Y1236023D03*
X290944Y1224803D03*
Y1228543D03*
X294684Y1123818D03*
Y1131299D03*
X294685Y1198621D03*
X287203Y1093897D03*
X279723D03*
X290943Y1086417D03*
X287203Y1078936D03*
X290943Y1082677D03*
X283463Y1082676D03*
X279723Y1078936D03*
X283463Y1086416D03*
X283464Y1101376D03*
Y1105117D03*
X290944Y1101376D03*
X279723Y1097637D03*
X290944Y1105117D03*
X287203Y1097637D03*
X294684Y1116338D03*
X287203Y1075196D03*
X279723D03*
X268503Y1228543D03*
X264763Y1236023D03*
Y1250984D03*
X268503Y1243503D03*
Y1247243D03*
X272244Y1250984D03*
X275984Y1243503D03*
Y1247243D03*
X264763Y1254724D03*
X272244D03*
X264763Y1232283D03*
X268503Y1224803D03*
X275984D03*
X272244Y1236023D03*
X275984Y1228543D03*
X272244Y1232283D03*
X264762Y1097637D03*
X268503Y1105117D03*
X272243Y1097637D03*
X275984Y1105117D03*
X268503Y1101376D03*
X275984D03*
X264762Y1075196D03*
X272243D03*
Y1093897D03*
X264762D03*
X275982Y1082677D03*
Y1086417D03*
X268502Y1082676D03*
X272243Y1078936D03*
X268502Y1086416D03*
X264762Y1078936D03*
X261023Y1243503D03*
X246062D03*
X249803Y1250984D03*
X261023Y1247243D03*
X246062D03*
X257283Y1250984D03*
X253543Y1247243D03*
Y1243503D03*
X257283Y1254724D03*
X249803D03*
X261023Y1224803D03*
X253543Y1228543D03*
X249803Y1232283D03*
X246062Y1228543D03*
X257283Y1232283D03*
Y1236023D03*
X246062Y1224803D03*
X261023Y1228543D03*
X253543Y1224803D03*
X249803Y1236023D03*
X249802Y1097637D03*
X257282D03*
X253543Y1105117D03*
Y1101376D03*
X261023Y1105117D03*
Y1101376D03*
X249802Y1075196D03*
X257282D03*
X249802Y1093897D03*
X257282D03*
X249802Y1078936D03*
X261022Y1086417D03*
X253542Y1082676D03*
X257282Y1078936D03*
X246061Y1082677D03*
Y1086417D03*
X253542Y1086416D03*
X261022Y1082677D03*
X234842Y1254724D03*
X242322D03*
X238582Y1224803D03*
Y1228543D03*
X242322Y1236023D03*
Y1232283D03*
X234842D03*
Y1236023D03*
X238582Y1247243D03*
X242322Y1250984D03*
X234842D03*
X238582Y1243503D03*
X246062Y1105117D03*
X242321Y1097637D03*
X234841D03*
X238582Y1101376D03*
X246062D03*
X238582Y1105117D03*
X234841Y1075195D03*
X242321Y1075196D03*
X234841Y1093897D03*
X242321D03*
Y1078936D03*
X238581Y1082676D03*
X234841Y1078935D03*
X238581Y1086416D03*
X219881Y1254724D03*
X227362D03*
X231102Y1228543D03*
Y1224803D03*
X219881Y1232283D03*
Y1236023D03*
X223622Y1224803D03*
X227362Y1232283D03*
X223622Y1228543D03*
X227362Y1236023D03*
X231102Y1243503D03*
Y1247243D03*
X223622Y1243503D03*
Y1247243D03*
X219881Y1250984D03*
X227362D03*
Y1093897D03*
X219881D03*
Y1078936D03*
X231102Y1082677D03*
Y1086417D03*
X223622Y1082677D03*
X227362Y1078936D03*
X223622Y1086417D03*
X231102Y1101376D03*
X219881Y1097637D03*
X223621Y1101376D03*
Y1105117D03*
X227362Y1097637D03*
X231102Y1105117D03*
X227362Y1075196D03*
X219881D03*
X216141Y1247243D03*
X208661Y1243503D03*
X216141D03*
X204921Y1250984D03*
X208661Y1247243D03*
X201181Y1243503D03*
X212401Y1250984D03*
X201181Y1247243D03*
X212401Y1254724D03*
X204921D03*
Y1232283D03*
X201181Y1224803D03*
X212401Y1232283D03*
X208661Y1228543D03*
X212401Y1236023D03*
X216141Y1224803D03*
X208661D03*
X201181Y1228543D03*
X216141D03*
X204921Y1236023D03*
X208661Y1082677D03*
X216141Y1086417D03*
X201181Y1082677D03*
X216141D03*
X201181Y1086417D03*
X208661D03*
X204921Y1078936D03*
Y1097637D03*
X216141Y1101376D03*
X208661D03*
X212401Y1097637D03*
X208661Y1105117D03*
X216141D03*
X201181Y1101376D03*
Y1105117D03*
X204921Y1075196D03*
X212401D03*
Y1093897D03*
X204921D03*
X212401Y1078936D03*
X197440Y1250984D03*
X193700Y1247243D03*
Y1243503D03*
X189960Y1250984D03*
X186220Y1247243D03*
Y1243503D03*
X197440Y1254724D03*
X189960D03*
X197440Y1236023D03*
X186220Y1224803D03*
X193700Y1228543D03*
X197440Y1232283D03*
X189960Y1236023D03*
X186220Y1228543D03*
X193700Y1224803D03*
X189960Y1232283D03*
X197440Y1093897D03*
X189960D03*
X186220Y1082677D03*
Y1086417D03*
X189960Y1078936D03*
X193700Y1086417D03*
Y1082677D03*
X197440Y1078936D03*
X193700Y1105117D03*
X189960Y1097637D03*
X186220Y1105117D03*
X197440Y1097637D03*
X193700Y1101376D03*
X186220D03*
X189960Y1075196D03*
X197440D03*
X178740Y1247243D03*
X182480Y1250984D03*
X171259Y1247243D03*
X174999Y1250984D03*
X171259Y1243503D03*
X178740D03*
X182480Y1254724D03*
X174999D03*
X171259Y1198621D03*
X174999Y1206102D03*
X171259Y1213582D03*
X174999D03*
X178740Y1228543D03*
X171259Y1224803D03*
X182480Y1236023D03*
Y1232283D03*
X174999D03*
X171259Y1228543D03*
X178740Y1224803D03*
X174999Y1236023D03*
Y1191141D03*
X171259D03*
X174999Y1198621D03*
X171259Y1206102D03*
X174999Y1093897D03*
X182480D03*
X174999Y1078936D03*
X182480D03*
X178740Y1082677D03*
Y1086417D03*
X182480Y1097637D03*
X174999D03*
X178740Y1101376D03*
Y1105117D03*
X174999Y1075196D03*
X182480D03*
X152559Y1250984D03*
X156299Y1243503D03*
Y1247243D03*
X163779Y1243503D03*
X160039Y1250984D03*
X163779Y1247243D03*
X167519Y1250984D03*
X152559Y1254724D03*
X167519D03*
X160039D03*
X167519Y1209842D03*
X163779D03*
Y1217322D03*
X167519D03*
X152559D03*
X160039Y1236023D03*
X163779Y1224803D03*
X156299D03*
X167519Y1232283D03*
X156299Y1228543D03*
X163779D03*
X167519Y1236023D03*
X160039Y1232283D03*
X152559Y1236023D03*
Y1232283D03*
X156299Y1202362D03*
Y1194881D03*
X152559Y1202362D03*
Y1194881D03*
X163779D03*
Y1202362D03*
X167519Y1194881D03*
Y1202362D03*
X156299Y1217322D03*
Y1209842D03*
X152559D03*
X156299Y1187401D03*
X163779D03*
X152559D03*
X167519D03*
X148818Y1239763D03*
X145078D03*
Y1198621D03*
X148818D03*
X145078Y1206102D03*
X148818D03*
X145078Y1221062D03*
X148818D03*
Y1213582D03*
X145078D03*
Y1228543D03*
X148818D03*
Y1247243D03*
X145078D03*
Y1191141D03*
X148818D03*
X1643503Y1078936D03*
X1647242Y1082677D03*
X1636022Y1075196D03*
X1643503D03*
X1639762Y1086416D03*
Y1082676D03*
X1658463Y1097637D03*
X1636022Y1078936D03*
X1647242Y1086417D03*
X1617322Y1101376D03*
X1639763D03*
X1636022Y1097637D03*
Y1093897D03*
X1662204Y1101376D03*
X1658463Y1075196D03*
X1650983D03*
X1658463Y1078936D03*
X1654723Y1086416D03*
Y1082676D03*
X1662203Y1082677D03*
Y1086417D03*
X1621062Y1093897D03*
X1658463D03*
X1628542Y1097637D03*
X1643503D03*
Y1093897D03*
X1647244Y1101376D03*
X1650983Y1078936D03*
X662008D03*
X1621062Y1097637D03*
X1632283Y1101376D03*
X1624803D03*
X1654724D03*
X699408Y1093897D03*
X736810D03*
Y1097637D03*
X658268Y1082677D03*
X1059251Y1239763D03*
X759251Y1075196D03*
X751771D03*
X1059251Y1247243D03*
X658268Y1086417D03*
X669488Y1093897D03*
X639567D03*
X635827Y1101376D03*
Y1105117D03*
X639567Y1097637D03*
X632086D03*
Y1075196D03*
X639567D03*
X774212Y1093897D03*
X729330Y1097637D03*
X721849Y1093897D03*
X781693Y1101377D03*
X669488Y1097637D03*
X1628542Y1093897D03*
X650787Y1082677D03*
Y1101376D03*
X647047Y1097637D03*
X762992Y1120078D03*
X635827Y1082677D03*
X777953Y1101377D03*
X770472D03*
X647047Y1075196D03*
X654527D03*
X770472Y1105117D03*
X669488Y1075196D03*
X774212Y1097637D03*
X643307Y1101376D03*
Y1105117D03*
X647047Y1078936D03*
X654527D03*
X643307Y1082677D03*
Y1086417D03*
X774211Y1078936D03*
X770471Y1086417D03*
Y1082677D03*
X777953Y1082676D03*
X781693D03*
Y1090157D03*
X777953D03*
X650787Y1105117D03*
X762992Y1112598D03*
X650787Y1086417D03*
X639567Y1078936D03*
X635827Y1086417D03*
X762992Y1135039D03*
Y1127559D03*
X1647244Y1105116D03*
X662008Y1093897D03*
X755511Y1082676D03*
X662008Y1097637D03*
X658268Y1105117D03*
X774211Y1075196D03*
X755511Y1086416D03*
X676968Y1075196D03*
X632086Y1093897D03*
Y1078936D03*
X1624803Y1105116D03*
X1650983Y1097637D03*
Y1093897D03*
X1673424Y1075196D03*
X1680904D03*
X1665944D03*
X1669684Y1082676D03*
Y1086416D03*
X1673424Y1078936D03*
X1680904D03*
X1677164Y1086417D03*
Y1082677D03*
X1665944Y1078936D03*
X1677165Y1101376D03*
X1669685D03*
X1680904Y1093897D03*
Y1097637D03*
X1673424Y1093897D03*
Y1097637D03*
X1665944D03*
Y1093897D03*
X1688384Y1075196D03*
Y1078936D03*
X1684644Y1086417D03*
Y1082677D03*
X1692126Y1082676D03*
X1695866D03*
Y1090157D03*
X1692126D03*
X1688385Y1097637D03*
Y1093897D03*
X1684645Y1101377D03*
X1695866D03*
X1692126D03*
X1550000Y1105116D03*
X1564960D03*
X1557480D03*
X1572441D03*
X1579921D03*
X1594881D03*
X1587401D03*
X1609842D03*
X1602362D03*
X1516338Y1191141D03*
Y1198621D03*
Y1206102D03*
Y1213582D03*
X1535039Y1187401D03*
X1527559D03*
X1523819D03*
X1535039Y1194881D03*
Y1202362D03*
X1523819Y1194881D03*
X1527559D03*
X1523819Y1202362D03*
X1527559D03*
X1520078Y1191141D03*
Y1198621D03*
Y1206102D03*
X1535039Y1217322D03*
Y1209842D03*
X1527559D03*
X1523819D03*
Y1217322D03*
X1527559D03*
X1520078Y1213582D03*
X1538779Y1187401D03*
Y1194881D03*
Y1202362D03*
Y1217322D03*
Y1209842D03*
X1546259Y1191141D03*
X1542519D03*
Y1198621D03*
X1546259D03*
X1542519Y1206102D03*
X1546259D03*
X762991Y1082677D03*
X602165Y1228543D03*
X613386Y1243503D03*
Y1247243D03*
X609646Y1250984D03*
Y1254724D03*
X617126D03*
Y1250984D03*
X620866Y1247243D03*
Y1243503D03*
X665748Y1105117D03*
X613386Y1202362D03*
X609646D03*
X613386Y1194881D03*
X609646D03*
X613386Y1217322D03*
X609646D03*
Y1209842D03*
X613386D03*
X620866Y1187401D03*
Y1202362D03*
Y1194881D03*
Y1209842D03*
X624606Y1187401D03*
X632086Y1206102D03*
X628346D03*
X632086Y1198621D03*
X628346D03*
X624606Y1202362D03*
Y1194881D03*
X628346Y1191141D03*
X632086D03*
Y1213582D03*
X628346D03*
X624606Y1209842D03*
X620866Y1217322D03*
X624606D03*
X762992Y1105117D03*
X684449Y1075196D03*
X755512Y1101376D03*
X766731Y1097637D03*
X759251Y1078936D03*
X755512Y1105117D03*
X766731Y1093897D03*
Y1078936D03*
X762991Y1086417D03*
X759251Y1097637D03*
X762992Y1101376D03*
X759251Y1093897D03*
X1516338Y1221062D03*
Y1228543D03*
X662008Y1075196D03*
X647047Y1093897D03*
X654527Y1097637D03*
Y1093897D03*
X669488Y1078936D03*
X602165Y1239763D03*
X736810Y1078936D03*
X744290Y1075196D03*
X721849Y1078936D03*
X725589Y1086416D03*
Y1082676D03*
X729330Y1078936D03*
X733069Y1086417D03*
Y1082677D03*
X729330Y1075196D03*
X718110Y1101376D03*
X1617321Y1082677D03*
X714369Y1093897D03*
X1617321Y1086417D03*
X714369Y1097637D03*
X706889Y1093897D03*
Y1097637D03*
Y1078936D03*
X710629Y1086416D03*
Y1082676D03*
X714369Y1078936D03*
X718109Y1082677D03*
Y1086417D03*
X684449Y1078936D03*
X680709Y1086417D03*
Y1082677D03*
X676968Y1078936D03*
X673228Y1082677D03*
Y1086417D03*
X703149Y1105117D03*
X699408Y1097637D03*
X691928Y1093897D03*
Y1078935D03*
X695668Y1086416D03*
Y1082676D03*
X699408Y1078936D03*
X703148Y1086417D03*
Y1082677D03*
X691928Y1075195D03*
X699408Y1075196D03*
X691928Y1097637D03*
X695669Y1101376D03*
Y1105117D03*
X703149Y1101376D03*
X714369Y1075196D03*
X706889D03*
X710630Y1105117D03*
Y1101376D03*
X718110Y1105117D03*
X736810Y1075196D03*
X721849D03*
X684449Y1097637D03*
Y1093897D03*
X1527559Y1224803D03*
X676968Y1097637D03*
Y1093897D03*
X688189Y1105117D03*
Y1101376D03*
X1520078Y1221062D03*
X680708Y1105117D03*
Y1101376D03*
X673228Y1105117D03*
Y1101376D03*
X725590Y1105117D03*
X733071Y1101376D03*
Y1105117D03*
X725590Y1101376D03*
X665748Y1082677D03*
Y1086417D03*
X721849Y1097637D03*
X729330Y1093897D03*
X1516338Y1239763D03*
X770472Y1224803D03*
Y1228543D03*
X777953D03*
X781693D03*
X774212Y1232283D03*
Y1236023D03*
X781693Y1213582D03*
X777953D03*
X781693Y1221062D03*
X777953D03*
X774212Y1217322D03*
X770472D03*
Y1209842D03*
X774212D03*
X781693Y1198621D03*
X777953D03*
X774212Y1202362D03*
X770472D03*
X777953Y1206102D03*
X781693D03*
X762992Y1243503D03*
Y1247243D03*
X766732Y1250984D03*
Y1254724D03*
X759252D03*
Y1250984D03*
X755512Y1247243D03*
Y1243503D03*
Y1224803D03*
Y1228543D03*
X762992Y1224803D03*
Y1228543D03*
X759252Y1232283D03*
Y1236023D03*
X766732D03*
Y1232283D03*
X762992Y1217322D03*
X759252D03*
X755512Y1213582D03*
X759252Y1209842D03*
X762992D03*
Y1202362D03*
X759252D03*
X755512Y1206102D03*
Y1198621D03*
X751772Y1250984D03*
Y1254724D03*
Y1236023D03*
Y1232283D03*
Y1213582D03*
Y1206102D03*
Y1198621D03*
X759252Y1127559D03*
Y1135039D03*
X755512Y1131299D03*
X759252Y1112598D03*
Y1120078D03*
X755512Y1116338D03*
Y1123818D03*
X751771Y1131299D03*
Y1116338D03*
Y1123818D03*
X770472Y1135039D03*
X774212D03*
X777953Y1131299D03*
X781693D03*
X774212Y1127558D03*
X770472D03*
X777953Y1123818D03*
X781693D03*
X774212Y1120078D03*
X770472D03*
X777953Y1116338D03*
X781693D03*
X774212Y1112598D03*
X777953Y1108858D03*
X781693D03*
X1632283Y1105116D03*
X1617322D03*
X1639763D03*
X1662204D03*
X1654724D03*
X1677165D03*
X1669685D03*
X1684645Y1105117D03*
X1673425Y1112598D03*
Y1120078D03*
X1669685Y1116338D03*
Y1123818D03*
X1665945Y1116338D03*
Y1123818D03*
X1677165Y1112598D03*
Y1120078D03*
X1673425Y1127559D03*
X1669685Y1131299D03*
X1665945D03*
X1677165Y1127559D03*
X1692126Y1123818D03*
X1695866D03*
X1688385Y1120078D03*
X1684645D03*
X1692126Y1116338D03*
X1695866D03*
X1684645Y1112598D03*
X1688385D03*
X1692126Y1108858D03*
X1695866D03*
X1692126Y1131299D03*
X1695866D03*
X1688385Y1127558D03*
X1684645D03*
X1673425Y1135039D03*
X1677165D03*
X1684645D03*
X1688385D03*
X1059251Y1191141D03*
Y1198621D03*
Y1206102D03*
Y1213582D03*
X1077952Y1187401D03*
X1070472D03*
X1066732D03*
X1077952Y1194881D03*
Y1202362D03*
X1066732Y1194881D03*
X1070472D03*
X1066732Y1202362D03*
X1070472D03*
X1062991Y1191141D03*
Y1198621D03*
Y1206102D03*
X1077952Y1217322D03*
Y1209842D03*
X1070472D03*
X1066732D03*
Y1217322D03*
X1070472D03*
X1062991Y1213582D03*
X1081692Y1187401D03*
Y1194881D03*
Y1202362D03*
Y1217322D03*
Y1209842D03*
X1089172Y1191141D03*
X1085432D03*
Y1198621D03*
X1089172D03*
X1085432Y1206102D03*
X1089172D03*
X1059251Y1221062D03*
Y1228543D03*
X1062991Y1221062D03*
X1070472Y1224803D03*
Y1228543D03*
X1077952Y1224803D03*
Y1228543D03*
X1066732Y1232283D03*
Y1236023D03*
X1074212D03*
Y1232283D03*
X1062991Y1228543D03*
X1077952Y1243503D03*
Y1247243D03*
X1074212Y1250984D03*
Y1254724D03*
X1066732D03*
Y1250984D03*
X1070472Y1247243D03*
Y1243503D03*
X1062991Y1247243D03*
Y1239763D03*
X1085432Y1213582D03*
X1089172D03*
X1081692Y1232283D03*
Y1236023D03*
X1085432Y1224803D03*
Y1228543D03*
X1089172Y1232283D03*
Y1236023D03*
Y1250984D03*
Y1254724D03*
X1081692D03*
Y1250984D03*
X1085432Y1247243D03*
Y1243503D03*
X1092913Y1224803D03*
Y1228543D03*
Y1243503D03*
Y1247243D03*
X1100393Y1224803D03*
Y1228543D03*
X1104133Y1236023D03*
Y1232283D03*
X1107873Y1228543D03*
Y1224803D03*
X1096653Y1232283D03*
Y1236023D03*
X1100393Y1243503D03*
Y1247243D03*
X1104133Y1254724D03*
Y1250984D03*
X1107873Y1247243D03*
Y1243503D03*
X1096653Y1250984D03*
Y1254724D03*
X1115354Y1224803D03*
Y1228543D03*
X1119094Y1236023D03*
Y1232283D03*
X1122834Y1228543D03*
Y1224803D03*
X1126574Y1232283D03*
Y1236023D03*
X1111613Y1232283D03*
Y1236023D03*
X1115354Y1243503D03*
Y1247243D03*
X1119094Y1254724D03*
Y1250984D03*
X1122834Y1247243D03*
Y1243503D03*
X1126574Y1250984D03*
Y1254724D03*
X1111613Y1250984D03*
Y1254724D03*
X1130314Y1224803D03*
Y1228543D03*
X1141535Y1236023D03*
Y1232283D03*
X1134054Y1236023D03*
Y1232283D03*
X1137795Y1228543D03*
Y1224803D03*
X1130314Y1243503D03*
Y1247243D03*
X1134054Y1254724D03*
Y1250984D03*
X1137795Y1247243D03*
Y1243503D03*
X1141535Y1250984D03*
Y1254724D03*
X1149015Y1236023D03*
Y1232283D03*
X1152755Y1224803D03*
X1156495Y1232283D03*
Y1236023D03*
X1152755Y1228543D03*
X1145275Y1224803D03*
Y1228543D03*
X1149015Y1254724D03*
Y1250984D03*
X1152755Y1247243D03*
Y1243503D03*
X1156495Y1250984D03*
Y1254724D03*
X1145275Y1243503D03*
Y1247243D03*
X1163976Y1236023D03*
Y1232283D03*
X1167716Y1228543D03*
Y1224803D03*
X1175196D03*
Y1228543D03*
X1171456Y1232283D03*
Y1236023D03*
X1160235Y1224803D03*
Y1228543D03*
X1163976Y1254724D03*
Y1250984D03*
X1167716Y1243503D03*
Y1247243D03*
X1171456Y1250984D03*
Y1254724D03*
X1175196Y1247243D03*
Y1243503D03*
X1160235Y1247243D03*
Y1243503D03*
X1178936Y1236023D03*
Y1232283D03*
X1182676Y1224803D03*
Y1228543D03*
X1186417Y1236023D03*
Y1232283D03*
X1190157Y1228543D03*
Y1224803D03*
X1178936Y1254724D03*
Y1250984D03*
X1182676Y1243503D03*
Y1247243D03*
X1186417Y1250984D03*
Y1254724D03*
X1190157Y1247243D03*
Y1243503D03*
X1197637Y1224803D03*
Y1228543D03*
X1201377Y1232283D03*
Y1236023D03*
X1205117Y1228543D03*
Y1224803D03*
X1193897Y1236023D03*
Y1232283D03*
X1197637Y1247243D03*
X1205117Y1243503D03*
Y1247243D03*
X1201377Y1254724D03*
Y1250984D03*
X1197637Y1243503D03*
X1193897Y1254724D03*
Y1250984D03*
X1212598Y1224803D03*
Y1228543D03*
X1220078Y1224803D03*
Y1228543D03*
X1216338Y1232283D03*
Y1236023D03*
X1223818D03*
Y1232283D03*
X1208858Y1236023D03*
Y1232283D03*
X1220078Y1243503D03*
Y1247243D03*
X1223818Y1250984D03*
Y1254724D03*
X1216338D03*
Y1250984D03*
X1212598Y1247243D03*
Y1243503D03*
X1208858Y1250984D03*
Y1254724D03*
X1227558Y1224803D03*
Y1228543D03*
X1235039D03*
X1238779D03*
X1231298Y1232283D03*
Y1236023D03*
X1238779Y1239763D03*
X1235039D03*
X1238779Y1247243D03*
X1235039D03*
X1231298Y1250984D03*
Y1254724D03*
X1227558Y1247243D03*
Y1243503D03*
X1220078Y1202362D03*
X1216338D03*
X1212598Y1206102D03*
Y1198621D03*
X1208858Y1206102D03*
Y1198621D03*
X1220078Y1217322D03*
X1216338D03*
X1212598Y1213582D03*
X1216338Y1209842D03*
X1220078D03*
X1208858Y1213582D03*
X1238779Y1198621D03*
X1235039D03*
X1231298Y1202362D03*
X1227558D03*
X1235039Y1206102D03*
X1238779D03*
Y1213582D03*
X1235039D03*
X1238779Y1221062D03*
X1235039D03*
X1231298Y1217322D03*
X1227558D03*
Y1209842D03*
X1231298D03*
X1089172Y1075196D03*
Y1078936D03*
X1092913Y1086417D03*
Y1082677D03*
X1089172Y1097637D03*
Y1093897D03*
X1092913Y1101376D03*
X1104133Y1075196D03*
X1096653D03*
X1104133Y1078936D03*
X1107873Y1082677D03*
Y1086417D03*
X1100393D03*
Y1082677D03*
X1096653Y1078936D03*
X1104133Y1093897D03*
Y1097637D03*
X1107873Y1101376D03*
X1100393D03*
X1096653Y1097637D03*
Y1093897D03*
X1126574Y1075196D03*
X1119094D03*
X1111613D03*
X1126574Y1078936D03*
X1122834Y1086417D03*
Y1082677D03*
X1119094Y1078936D03*
X1115354Y1086417D03*
Y1082677D03*
X1111613Y1078936D03*
X1126574Y1093897D03*
Y1097637D03*
X1119094Y1093897D03*
Y1097637D03*
X1115354Y1101376D03*
X1122834D03*
X1111613Y1097637D03*
Y1093897D03*
X1141535Y1075196D03*
X1134054D03*
X1141535Y1078936D03*
X1137795Y1086417D03*
Y1082677D03*
X1134054Y1078936D03*
X1130314Y1082677D03*
Y1086417D03*
X1141535Y1097637D03*
Y1093897D03*
X1134054Y1097637D03*
Y1093897D03*
X1137794Y1101376D03*
X1130314D03*
X1149014Y1075195D03*
X1156494Y1075196D03*
X1149014Y1078935D03*
X1152754Y1086416D03*
Y1082676D03*
X1156494Y1078936D03*
X1145275Y1086417D03*
Y1082677D03*
X1152755Y1101376D03*
X1156494Y1093897D03*
Y1097637D03*
X1149014D03*
Y1093897D03*
X1145275Y1101376D03*
X1163975Y1075196D03*
X1171455D03*
X1163975Y1078936D03*
X1167715Y1086416D03*
Y1082676D03*
X1171455Y1078936D03*
X1175195Y1082677D03*
Y1086417D03*
X1160234D03*
Y1082677D03*
X1175196Y1101376D03*
X1167716D03*
X1171455Y1093897D03*
Y1097637D03*
X1163975Y1093897D03*
Y1097637D03*
X1160235Y1101376D03*
X1178935Y1075196D03*
X1186416D03*
X1178935Y1078936D03*
X1182675Y1086416D03*
Y1082676D03*
X1186416Y1078936D03*
X1190155Y1086417D03*
Y1082677D03*
X1190157Y1101376D03*
X1182676D03*
X1186416Y1093897D03*
Y1097637D03*
X1178935Y1093897D03*
Y1097637D03*
X1201376Y1075196D03*
X1193896D03*
X1201376Y1078936D03*
X1197636Y1086416D03*
Y1082676D03*
X1205116Y1082677D03*
Y1086417D03*
X1193896Y1078936D03*
X1205117Y1101376D03*
X1197637D03*
X1201376Y1097637D03*
Y1093897D03*
X1193896Y1097637D03*
Y1093897D03*
X1216337Y1075196D03*
X1223817D03*
X1208857D03*
X1212597Y1082676D03*
Y1086416D03*
X1216337Y1078936D03*
X1223817D03*
X1220077Y1086417D03*
Y1082677D03*
X1208857Y1078936D03*
X1220078Y1101376D03*
X1212598D03*
X1223817Y1093897D03*
Y1097637D03*
X1216337Y1093897D03*
Y1097637D03*
X1208857D03*
Y1093897D03*
X1231297Y1075196D03*
Y1078936D03*
X1227557Y1086417D03*
Y1082677D03*
X1235039Y1082676D03*
X1238779D03*
Y1090157D03*
X1235039D03*
X1231298Y1097637D03*
Y1093897D03*
X1227558Y1101377D03*
X1238779D03*
X1235039D03*
X1092913Y1105116D03*
X1107873D03*
X1100393D03*
X1115354D03*
X1122834D03*
X1137794D03*
X1130314D03*
X1152755D03*
X1145275D03*
X1175196D03*
X1167716D03*
X1160235D03*
X1190157D03*
X1182676D03*
X1205117D03*
X1197637D03*
X1220078D03*
X1212598D03*
X1227558Y1105117D03*
X1216338Y1112598D03*
Y1120078D03*
X1212598Y1116338D03*
Y1123818D03*
X1208858Y1116338D03*
Y1123818D03*
X1220078Y1112598D03*
Y1120078D03*
X1216338Y1127559D03*
X1212598Y1131299D03*
X1208858D03*
X1220078Y1127559D03*
X1235039Y1123818D03*
X1238779D03*
X1231298Y1120078D03*
X1227558D03*
X1235039Y1116338D03*
X1238779D03*
X1227558Y1112598D03*
X1231298D03*
X1235039Y1108858D03*
X1238779D03*
X1235039Y1131299D03*
X1238779D03*
X1231298Y1127558D03*
X1227558D03*
X1216338Y1135039D03*
X1220078D03*
X1227558D03*
X1231298D03*
X1557480Y1086417D03*
Y1082677D03*
X1553740Y1078936D03*
X1561220Y1093897D03*
Y1097637D03*
X1564960Y1101376D03*
X1557480D03*
X1553740Y1097637D03*
Y1093897D03*
X1583661Y1075196D03*
X1576181D03*
X1568700D03*
X1583661Y1078936D03*
X1579921Y1086417D03*
Y1082677D03*
X1576181Y1078936D03*
X1572441Y1086417D03*
Y1082677D03*
X1568700Y1078936D03*
X1583661Y1093897D03*
Y1097637D03*
X1576181Y1093897D03*
Y1097637D03*
X1572441Y1101376D03*
X1579921D03*
X1568700Y1097637D03*
Y1093897D03*
X1598622Y1075196D03*
X1591141D03*
X1598622Y1078936D03*
X1594882Y1086417D03*
Y1082677D03*
X1591141Y1078936D03*
X1587401Y1082677D03*
Y1086417D03*
X1598622Y1097637D03*
Y1093897D03*
X1591141Y1097637D03*
Y1093897D03*
X1594881Y1101376D03*
X1587401D03*
X1606101Y1075195D03*
X1613581Y1075196D03*
X1606101Y1078935D03*
X1609841Y1086416D03*
Y1082676D03*
X1613581Y1078936D03*
X1602362Y1086417D03*
Y1082677D03*
X1609842Y1101376D03*
X1613581Y1093897D03*
Y1097637D03*
X1606101D03*
Y1093897D03*
X1602362Y1101376D03*
X1621062Y1075196D03*
X1628542D03*
X1621062Y1078936D03*
X1624802Y1086416D03*
Y1082676D03*
X1628542Y1078936D03*
X1632282Y1082677D03*
Y1086417D03*
X1546259Y1078936D03*
X1550000Y1086417D03*
Y1082677D03*
X1546259Y1097637D03*
Y1093897D03*
X1550000Y1101376D03*
X1561220Y1075196D03*
X1553740D03*
X1561220Y1078936D03*
X1564960Y1082677D03*
Y1086417D03*
X1695866Y1213582D03*
X1692126D03*
X1695866Y1221062D03*
X1692126D03*
X1688385Y1217322D03*
X1684645D03*
Y1209842D03*
X1688385D03*
X1546259Y1075196D03*
X609646Y1187401D03*
X613386D03*
X1665945Y1198621D03*
X1677165Y1217322D03*
X1673425D03*
X1669685Y1213582D03*
X1673425Y1209842D03*
X1677165D03*
X1665945Y1213582D03*
X1695866Y1198621D03*
X1692126D03*
X1688385Y1202362D03*
X1684645D03*
X1692126Y1206102D03*
X1695866D03*
X1665945D03*
X1695866Y1239763D03*
X1692126D03*
X1695866Y1247243D03*
X1692126D03*
X1688385Y1250984D03*
Y1254724D03*
X1684645Y1247243D03*
Y1243503D03*
X1677165Y1202362D03*
X1673425D03*
X1669685Y1206102D03*
Y1198621D03*
X1665945Y1250984D03*
Y1254724D03*
X1684645Y1224803D03*
Y1228543D03*
X1692126D03*
X1695866D03*
X1688385Y1232283D03*
Y1236023D03*
X1527559Y1228543D03*
X1535039Y1224803D03*
Y1228543D03*
X1523819Y1232283D03*
Y1236023D03*
X1531299D03*
Y1232283D03*
X1520078Y1228543D03*
X1535039Y1243503D03*
Y1247243D03*
X1531299Y1250984D03*
Y1254724D03*
X1523819D03*
Y1250984D03*
X1527559Y1247243D03*
Y1243503D03*
X1520078Y1247243D03*
Y1239763D03*
X1542519Y1213582D03*
X1546259D03*
X1538779Y1232283D03*
Y1236023D03*
X1542519Y1224803D03*
Y1228543D03*
X1546259Y1232283D03*
Y1236023D03*
Y1250984D03*
Y1254724D03*
X1538779D03*
Y1250984D03*
X1542519Y1247243D03*
Y1243503D03*
X1550000Y1224803D03*
Y1228543D03*
Y1243503D03*
Y1247243D03*
X1557480Y1224803D03*
Y1228543D03*
X1561220Y1236023D03*
Y1232283D03*
X1564960Y1228543D03*
Y1224803D03*
X1553740Y1232283D03*
Y1236023D03*
X1557480Y1243503D03*
Y1247243D03*
X1561220Y1254724D03*
Y1250984D03*
X1564960Y1247243D03*
Y1243503D03*
X1553740Y1250984D03*
Y1254724D03*
X1572441Y1224803D03*
Y1228543D03*
X1576181Y1236023D03*
Y1232283D03*
X1579921Y1228543D03*
Y1224803D03*
X1583661Y1232283D03*
Y1236023D03*
X1568700Y1232283D03*
Y1236023D03*
X1572441Y1243503D03*
Y1247243D03*
X1576181Y1254724D03*
Y1250984D03*
X1579921Y1247243D03*
Y1243503D03*
X1583661Y1250984D03*
Y1254724D03*
X1568700Y1250984D03*
Y1254724D03*
X1587401Y1224803D03*
Y1228543D03*
X1598622Y1236023D03*
Y1232283D03*
X1591141Y1236023D03*
Y1232283D03*
X1594882Y1228543D03*
Y1224803D03*
X1587401Y1243503D03*
Y1247243D03*
X1591141Y1254724D03*
Y1250984D03*
X1594882Y1247243D03*
Y1243503D03*
X1598622Y1250984D03*
Y1254724D03*
X1606102Y1236023D03*
Y1232283D03*
X1609842Y1224803D03*
X1613582Y1232283D03*
Y1236023D03*
X1609842Y1228543D03*
X1602362Y1224803D03*
Y1228543D03*
X1606102Y1254724D03*
Y1250984D03*
X1609842Y1247243D03*
Y1243503D03*
X1613582Y1250984D03*
Y1254724D03*
X1602362Y1243503D03*
Y1247243D03*
X1621063Y1236023D03*
Y1232283D03*
X1624803Y1228543D03*
Y1224803D03*
X1632283D03*
Y1228543D03*
X1628543Y1232283D03*
Y1236023D03*
X1617322Y1224803D03*
Y1228543D03*
X1621063Y1254724D03*
Y1250984D03*
X1624803Y1243503D03*
Y1247243D03*
X1628543Y1250984D03*
Y1254724D03*
X1632283Y1247243D03*
Y1243503D03*
X1617322Y1247243D03*
Y1243503D03*
X1636023Y1236023D03*
Y1232283D03*
X1639763Y1224803D03*
Y1228543D03*
X1643504Y1236023D03*
Y1232283D03*
X1647244Y1228543D03*
Y1224803D03*
X1636023Y1254724D03*
Y1250984D03*
X1639763Y1243503D03*
Y1247243D03*
X1643504Y1250984D03*
Y1254724D03*
X1647244Y1247243D03*
Y1243503D03*
X1654724Y1224803D03*
Y1228543D03*
X1658464Y1232283D03*
Y1236023D03*
X1662204Y1228543D03*
Y1224803D03*
X1650984Y1236023D03*
Y1232283D03*
X1654724Y1247243D03*
X1662204Y1243503D03*
Y1247243D03*
X1658464Y1254724D03*
Y1250984D03*
X1654724Y1243503D03*
X1650984Y1254724D03*
Y1250984D03*
X1669685Y1224803D03*
Y1228543D03*
X1677165Y1224803D03*
Y1228543D03*
X1673425Y1232283D03*
Y1236023D03*
X1680905D03*
Y1232283D03*
X1665945Y1236023D03*
Y1232283D03*
X1677165Y1243503D03*
Y1247243D03*
X1680905Y1250984D03*
Y1254724D03*
X1673425D03*
Y1250984D03*
X1669685Y1247243D03*
Y1243503D03*
X770472D03*
Y1247243D03*
X774212Y1254724D03*
Y1250984D03*
X777953Y1247243D03*
X781693D03*
X777953Y1239763D03*
X781693D03*
X605905Y1228543D03*
Y1239763D03*
Y1247243D03*
X617126Y1232283D03*
Y1236023D03*
X609646D03*
Y1232283D03*
X620866Y1228543D03*
Y1224803D03*
X613386Y1228543D03*
Y1224803D03*
X770472Y1112598D03*
X639567Y1236023D03*
Y1232283D03*
X632086Y1236023D03*
Y1232283D03*
X635827Y1228543D03*
Y1224803D03*
X628346Y1228543D03*
Y1224803D03*
X624606Y1236023D03*
Y1232283D03*
X639567Y1254724D03*
Y1250984D03*
X628346Y1243503D03*
Y1247243D03*
X624606Y1250984D03*
Y1254724D03*
X632086D03*
Y1250984D03*
X635827Y1247243D03*
Y1243503D03*
X654527Y1236023D03*
Y1232283D03*
X650787Y1224803D03*
Y1228543D03*
X647047Y1232283D03*
Y1236023D03*
X643307Y1228543D03*
Y1224803D03*
X654527Y1254724D03*
Y1250984D03*
X650787Y1243503D03*
Y1247243D03*
X647047Y1250984D03*
Y1254724D03*
X643307Y1247243D03*
Y1243503D03*
X669488Y1236023D03*
Y1232283D03*
X665748Y1224803D03*
Y1228543D03*
X662008Y1232283D03*
Y1236023D03*
X658268Y1228543D03*
Y1224803D03*
X669488Y1254724D03*
Y1250984D03*
X665748Y1243503D03*
Y1247243D03*
X662008Y1250984D03*
Y1254724D03*
X658268Y1247243D03*
Y1243503D03*
X688189Y1228543D03*
Y1224803D03*
X680709D03*
Y1228543D03*
X676968Y1232283D03*
Y1236023D03*
X684449Y1232283D03*
Y1236023D03*
X673228Y1228543D03*
Y1224803D03*
X684449Y1254724D03*
Y1250984D03*
X688189Y1247243D03*
Y1243503D03*
X680709D03*
Y1247243D03*
X676968Y1250984D03*
Y1254724D03*
X673228Y1247243D03*
Y1243503D03*
X695669Y1228543D03*
X699409Y1236023D03*
Y1232283D03*
X703149Y1228543D03*
Y1224803D03*
X695669D03*
X691929Y1232283D03*
Y1236023D03*
X703149Y1243503D03*
Y1247243D03*
X699409Y1254724D03*
Y1250984D03*
X695669Y1243503D03*
Y1247243D03*
X691929Y1250984D03*
Y1254724D03*
X714370Y1236023D03*
Y1232283D03*
X718110Y1228543D03*
Y1224803D03*
X710630D03*
Y1228543D03*
X706890Y1232283D03*
Y1236023D03*
X718110Y1243503D03*
Y1247243D03*
X714370Y1254724D03*
Y1250984D03*
X710630Y1247243D03*
Y1243503D03*
X706890Y1250984D03*
Y1254724D03*
X733071Y1224803D03*
Y1228543D03*
X736811Y1232283D03*
Y1236023D03*
X729331Y1232283D03*
Y1236023D03*
X725590Y1228543D03*
Y1224803D03*
X721850Y1232283D03*
Y1236023D03*
X733071Y1243503D03*
Y1247243D03*
X736811Y1250984D03*
Y1254724D03*
X729331D03*
Y1250984D03*
X725590Y1247243D03*
Y1243503D03*
X721850Y1250984D03*
Y1254724D03*
X748031Y1224803D03*
Y1228543D03*
X744291Y1236023D03*
Y1232283D03*
X740551Y1228543D03*
Y1224803D03*
Y1243503D03*
X744291Y1250984D03*
Y1254724D03*
X748031Y1247243D03*
Y1243503D03*
X740551Y1247243D03*
X602165Y1206102D03*
X605905D03*
X602165Y1198621D03*
X605905D03*
X602165Y1191141D03*
X605905D03*
X602165Y1221062D03*
X605905D03*
Y1213582D03*
X602165D03*
X1516338Y1247243D03*
X602165D03*
G54D78*
X970071Y1409152D03*
Y1365652D03*
G54D71*
X743337Y374862D03*
G54D64*
X1819042Y-27188D03*
Y-37188D03*
Y-47188D03*
X1753686Y-85978D03*
Y-75978D03*
Y-65978D03*
X1564906Y-27086D03*
Y-47086D03*
Y-37086D03*
X1574906Y-66006D03*
Y-86006D03*
Y-76006D03*
X1534542Y-27058D03*
Y-37058D03*
Y-47058D03*
X1499186Y-65978D03*
Y-75978D03*
Y-85978D03*
X1280406Y-26956D03*
Y-46956D03*
Y-36956D03*
X1320406Y-86006D03*
Y-66006D03*
Y-76006D03*
X1248042Y-26928D03*
X1242686Y-65978D03*
Y-75978D03*
Y-85978D03*
X993906Y-26826D03*
Y-46826D03*
Y-36826D03*
X1063906Y-66006D03*
Y-86006D03*
Y-76006D03*
X964542Y-26798D03*
Y-36798D03*
X939542D03*
Y-26798D03*
X989386Y-65978D03*
Y-75978D03*
X964386D03*
Y-65978D03*
X710406Y-26826D03*
Y-36826D03*
X735406D03*
Y-26826D03*
X830406Y-66006D03*
Y-76006D03*
X855406D03*
Y-66006D03*
X1248042Y-36928D03*
Y-46928D03*
X1018906Y-36826D03*
Y-46826D03*
X1217686Y-65978D03*
Y-75978D03*
X1305406Y-36956D03*
Y-46956D03*
Y-26956D03*
X1018906Y-26826D03*
X1217686Y-85978D03*
X1223042Y-26928D03*
Y-36928D03*
X1088906Y-76006D03*
Y-86006D03*
X1345406D03*
Y-76006D03*
Y-66006D03*
X1088906D03*
X1223042Y-46928D03*
X1474186Y-65978D03*
Y-75978D03*
Y-85978D03*
X1509542Y-27058D03*
Y-37058D03*
Y-47058D03*
X1794042Y-27188D03*
Y-37188D03*
Y-47188D03*
X1728686Y-65978D03*
Y-75978D03*
Y-85978D03*
X1589906Y-37086D03*
Y-47086D03*
Y-27086D03*
X1599906Y-76006D03*
Y-86006D03*
Y-66006D03*
G54D77*
X909360Y230906D03*
Y274606D03*
G54D72*
X1729390Y144095D03*
X1627028D03*
X1169941D03*
X1067579D03*
X965217D03*
X815217D03*
G54D70*
X640522Y630650D03*
X1657510Y374862D03*
X1554695Y630650D03*
X1200423Y374862D03*
X1097608Y630650D03*
X286250Y374862D03*
X183435Y630650D03*
G54D76*
X51043Y144095D03*
X57933Y66811D03*
X153405Y144095D03*
X160295Y66811D03*
X255767Y144095D03*
X262657Y66811D03*
X358129Y144095D03*
X365019Y66811D03*
X508130Y144095D03*
X515020Y66811D03*
X610492Y144095D03*
X617382Y66811D03*
X712854Y144095D03*
X719744Y66811D03*
X822106D03*
X972106D03*
X1074468D03*
X1176830D03*
X1272302Y144095D03*
X1279192Y66811D03*
X1422303Y144095D03*
X1429193Y66811D03*
X1524665Y144095D03*
X1531555Y66811D03*
X1633917D03*
X1736279D03*
G54D69*
X736447Y630650D03*
X1650620D03*
X1561585Y374862D03*
X1193533Y630650D03*
X1104498Y374862D03*
X279360Y630650D03*
X190325Y374862D03*
G54D68*
X1817323Y56693D03*
G54D67*
X924650Y1326119D03*
X370202Y1313064D03*
X559070Y686509D03*
X561570Y694509D03*
X559070Y702509D03*
X561570Y710509D03*
X559070Y718509D03*
X460950Y326485D03*
X463950Y334359D03*
X460950Y342233D03*
X463950Y350107D03*
X937000Y313983D03*
X66856Y105949D03*
X169218D03*
X271580D03*
X373942D03*
X893284Y235040D03*
X899352Y310261D03*
X1079748Y321042D03*
X1209184Y461917D03*
X1302896Y342096D03*
X1438116Y105949D03*
X1540478D03*
X1642840D03*
X1745202D03*
X1089096Y543562D03*
X1754906Y822634D03*
X917882Y326517D03*
X212980Y485254D03*
X205680Y478168D03*
X138290Y485260D03*
X148692Y478199D03*
X788482Y476118D03*
X778080Y483179D03*
X721092Y483210D03*
X713792Y476124D03*
X1245568Y476118D03*
X1235166Y483179D03*
X1178178Y483210D03*
X1170878Y476124D03*
X1584240Y485254D03*
X1576940Y478168D03*
X1519952Y478199D03*
X1509550Y485260D03*
X35688Y127128D03*
X28388Y120042D03*
Y134215D03*
X35688Y112955D03*
X130750Y120042D03*
Y134215D03*
X148692Y421047D03*
X138290Y413987D03*
X140690Y399813D03*
X148692Y406874D03*
Y392701D03*
X138050Y127128D03*
Y112955D03*
X138290Y471087D03*
Y442333D03*
Y428160D03*
X148692Y435221D03*
X205680Y399782D03*
X212980Y406868D03*
Y392695D03*
Y471081D03*
Y435215D03*
X205680Y442302D03*
Y428128D03*
Y413955D03*
X212980Y421041D03*
X233112Y134215D03*
Y120042D03*
X240412Y127128D03*
Y112955D03*
X342774Y127128D03*
X335474Y134215D03*
Y120042D03*
X342774Y112955D03*
X533092Y127096D03*
Y112923D03*
X543494Y134209D03*
Y120035D03*
X635454Y127096D03*
Y112923D03*
X645856Y134209D03*
Y120035D03*
X748218Y134209D03*
X737816Y127096D03*
X748218Y120035D03*
X737816Y112923D03*
X721092Y469037D03*
X778080Y469006D03*
X840178Y127096D03*
Y112923D03*
X850580Y134209D03*
Y120035D03*
X990178Y127096D03*
Y112923D03*
X1000580Y134209D03*
Y120035D03*
X1092540Y127096D03*
Y112923D03*
X1102942Y134209D03*
Y120035D03*
X1178178Y469037D03*
X1205304Y134209D03*
X1194902Y127096D03*
X1205304Y120035D03*
X1194902Y112923D03*
X1235166Y469006D03*
X1297264Y127096D03*
Y112923D03*
X1307666Y134209D03*
Y120035D03*
X1399648Y120042D03*
Y134215D03*
X1406948Y127128D03*
Y112955D03*
X1509310D03*
X1509550Y428160D03*
Y413987D03*
X1511950Y399813D03*
X1502010Y134215D03*
X1509310Y127128D03*
X1502010Y120042D03*
X1519952Y421047D03*
Y406874D03*
Y392701D03*
X1509550Y471087D03*
Y442333D03*
X1519952Y435221D03*
X1576940Y442302D03*
Y428128D03*
Y413955D03*
Y399782D03*
X1584240Y421041D03*
Y406868D03*
Y392695D03*
X1604372Y134215D03*
X1611672Y127128D03*
X1604372Y120042D03*
X1611672Y112955D03*
X1584240Y471081D03*
Y435215D03*
X1706734Y134215D03*
Y120042D03*
X1714034Y127128D03*
Y112955D03*
X148692Y536506D03*
Y522333D03*
X138290Y515221D03*
X148692Y492373D03*
X138290Y529394D03*
X205680Y492341D03*
Y536475D03*
X212980Y529388D03*
Y515215D03*
X205680Y522302D03*
X713792Y612817D03*
Y598644D03*
Y584471D03*
Y570297D03*
Y534431D03*
Y520258D03*
Y490297D03*
X721092Y591557D03*
Y577384D03*
Y563210D03*
Y527344D03*
Y513171D03*
Y605730D03*
X778080Y563179D03*
Y527313D03*
Y513139D03*
Y591525D03*
Y605699D03*
Y577352D03*
X788482Y570291D03*
Y534425D03*
Y520252D03*
Y490291D03*
Y612811D03*
Y598638D03*
Y584465D03*
X1170878Y612817D03*
Y598644D03*
Y584471D03*
Y570297D03*
Y534431D03*
Y520258D03*
Y490297D03*
X1178178Y563210D03*
Y527344D03*
Y513171D03*
Y605730D03*
Y591557D03*
Y577384D03*
X1235166Y527313D03*
Y513139D03*
Y605699D03*
Y591525D03*
Y577352D03*
Y563179D03*
X1245568Y570291D03*
Y534425D03*
Y520252D03*
Y490291D03*
Y612811D03*
Y598638D03*
Y584465D03*
X1509550Y529394D03*
Y515221D03*
X1519952Y536506D03*
Y522333D03*
Y492373D03*
X1576940Y536475D03*
Y522302D03*
Y492341D03*
X1584240Y529388D03*
Y515215D03*
X7982Y1527335D03*
G54D65*
X1592187Y-71006D03*
Y-81006D03*
X1582187Y-32086D03*
Y-42086D03*
X1736405Y-80978D03*
Y-70978D03*
X1801761Y-42188D03*
Y-32188D03*
X1517261Y-42058D03*
Y-32058D03*
X1481905Y-80978D03*
Y-70978D03*
X1230761Y-41928D03*
X1081187Y-71006D03*
X1337687D03*
Y-81006D03*
X1081187D03*
X1230761Y-31928D03*
X1225405Y-80978D03*
X1011187Y-31826D03*
X1297687Y-31956D03*
Y-41956D03*
X1225405Y-70978D03*
X1011187Y-41826D03*
X213969Y1460153D03*
Y1449153D03*
X227249Y1460153D03*
Y1449153D03*
G54D79*
X1817323Y1567323D03*
G54D66*
X1009333Y1344993D03*
X1015659Y681354D03*
X933725Y587636D03*
X933741Y596387D03*
X486837Y703006D03*
X394883Y340077D03*
X217907Y1428752D03*
X415203Y1497818D03*
X397267Y1516347D03*
X295011Y461917D03*
X523943Y105949D03*
X626305D03*
X728667D03*
X752097Y461917D03*
X831029Y105949D03*
X981029D03*
X1083391D03*
X1080351Y329955D03*
X1185753Y105949D03*
X1288115D03*
X1366535Y353200D03*
Y337452D03*
X1363535Y345326D03*
Y329578D03*
X1666271Y461919D03*
X174923Y543562D03*
X632009D03*
X1546183Y543564D03*
X385091Y1299153D03*
X454385Y1303545D03*
X940997Y333613D03*
X256705Y476124D03*
X264005Y483210D03*
X605779Y478199D03*
X595377Y485260D03*
X331395Y476118D03*
X320993Y483179D03*
X670067Y485254D03*
X662767Y478168D03*
X1127153Y485254D03*
X1119853Y478168D03*
X1062865Y478199D03*
X1052463Y485260D03*
X1702655Y476118D03*
X1692253Y483179D03*
X1635265Y483210D03*
X1627965Y476124D03*
X76005Y127096D03*
Y112923D03*
X86407Y120035D03*
Y134209D03*
X178367Y127096D03*
Y112923D03*
X188769Y134209D03*
Y120035D03*
X264005Y469037D03*
X291131Y134209D03*
Y120035D03*
X280729Y127096D03*
Y112923D03*
X320993Y469005D03*
X393493Y134209D03*
X383091Y127096D03*
X393493Y120035D03*
X383091Y112923D03*
X485475Y134215D03*
Y120042D03*
X492775Y127128D03*
Y112955D03*
X587837Y134215D03*
Y120042D03*
X597777Y399813D03*
X595137Y127128D03*
Y112955D03*
X595377Y471087D03*
Y442333D03*
Y428160D03*
Y413987D03*
X605779Y435221D03*
Y421047D03*
Y406874D03*
Y392701D03*
X670067Y435215D03*
X662767Y442302D03*
Y428128D03*
Y413955D03*
X670067Y421041D03*
X662767Y399782D03*
X670067Y406868D03*
Y392695D03*
Y471081D03*
X690199Y120042D03*
X697499Y127128D03*
X690199Y134215D03*
X697499Y112955D03*
X799861D03*
Y127128D03*
X792561Y120042D03*
Y134215D03*
X949861Y112955D03*
X942561Y120042D03*
Y134215D03*
X949861Y127128D03*
X1044923Y134215D03*
X1052223Y127128D03*
X1044923Y120042D03*
X1052223Y112955D03*
X1052463Y471087D03*
Y442333D03*
Y428160D03*
Y413987D03*
X1054863Y399813D03*
X1062865Y435221D03*
Y421047D03*
Y406874D03*
Y392701D03*
X1119853Y399782D03*
Y442302D03*
Y428128D03*
Y413955D03*
X1154585Y112955D03*
X1127153Y471081D03*
Y435215D03*
Y421041D03*
Y406868D03*
Y392695D03*
X1154585Y127128D03*
X1147285Y134215D03*
Y120042D03*
X1249647Y134215D03*
Y120042D03*
X1256947Y127128D03*
Y112955D03*
X1447265Y127096D03*
Y112923D03*
X1457667Y134209D03*
Y120035D03*
X1560029Y134209D03*
X1549627Y127096D03*
X1560029Y120035D03*
X1549627Y112923D03*
X1651989Y127096D03*
Y112923D03*
X1635265Y469037D03*
X1662391Y134209D03*
Y120035D03*
X1692253Y469006D03*
X1754351Y127096D03*
Y112923D03*
X1764753Y134209D03*
Y120035D03*
X264005Y513171D03*
X256705Y520258D03*
Y490297D03*
Y612817D03*
X264005Y591557D03*
Y605730D03*
X256705Y598644D03*
X264005Y577384D03*
X256705Y584471D03*
Y570297D03*
X264005Y563210D03*
X256705Y534431D03*
X264005Y527344D03*
X320993Y513139D03*
Y591525D03*
Y605699D03*
Y577352D03*
Y563179D03*
Y527313D03*
X331395Y490291D03*
Y612811D03*
Y598638D03*
Y584465D03*
Y570291D03*
Y534425D03*
Y520252D03*
X595377Y529394D03*
Y515221D03*
X605779Y536506D03*
Y522333D03*
Y492373D03*
X670067Y529388D03*
X662767Y536475D03*
Y522302D03*
X670067Y515215D03*
X662767Y492341D03*
X1052463Y529394D03*
Y515221D03*
X1062865Y536506D03*
Y522333D03*
Y492373D03*
X1119853Y536475D03*
Y522302D03*
Y492341D03*
X1127153Y529388D03*
Y515215D03*
X1627965Y584471D03*
Y570297D03*
Y534431D03*
Y520258D03*
Y490297D03*
Y612817D03*
Y598644D03*
X1635265Y527344D03*
Y513171D03*
Y605730D03*
Y591557D03*
Y577384D03*
Y563210D03*
X1692253Y605699D03*
Y591525D03*
Y577352D03*
Y563179D03*
Y527313D03*
Y513139D03*
X1702655Y534425D03*
Y520252D03*
Y490291D03*
Y612811D03*
Y598638D03*
Y584465D03*
Y570291D03*
G54D75*
X770472Y1490945D03*
X820079Y388583D03*
X1020866D03*
X1070472Y1490945D03*
G54D63*
X19685Y-83298D03*
X1821260D03*
X26789Y1373669D03*
X1796847Y1517889D03*
X1809883Y120792D03*
X184851Y334492D03*
X19685Y1801195D03*
X1821260D03*
G54D73*
X1030905Y1066535D03*
Y1263386D03*
X810038Y1066535D03*
Y1263386D03*
X573818Y1066535D03*
Y1263386D03*
X352952Y1066535D03*
Y1263386D03*
X116731Y1066535D03*
Y1263386D03*
X1724212Y1066535D03*
Y1263386D03*
X1487991Y1066535D03*
Y1263386D03*
X1267125Y1066535D03*
Y1263386D03*
%LPC*%
G75*
G36*
G01X145878Y1198621D02*
G02I-800J0D01*
G37*
G36*
G01Y1191141D02*
G02I-800J0D01*
G37*
G36*
G01X149618D02*
G02I-800J0D01*
G37*
G36*
G01Y1198621D02*
G02I-800J0D01*
G37*
G36*
G01X145878Y1221062D02*
G02I-800J0D01*
G37*
G36*
G01X149618D02*
G02I-800J0D01*
G37*
G36*
G01Y1213582D02*
G02I-800J0D01*
G37*
G36*
G01X145878D02*
G02I-800J0D01*
G37*
G36*
G01Y1206102D02*
G02I-800J0D01*
G37*
G36*
G01X149618D02*
G02I-800J0D01*
G37*
G36*
G01X145878Y1228543D02*
G02I-800J0D01*
G37*
G36*
G01X149618D02*
G02I-800J0D01*
G37*
G36*
G01Y1247243D02*
G02I-800J0D01*
G37*
G36*
G01X145878D02*
G02I-800J0D01*
G37*
G36*
G01X149618Y1239763D02*
G02I-800J0D01*
G37*
G36*
G01X145878D02*
G02I-800J0D01*
G37*
G36*
G01X157099Y1187401D02*
G02I-800J0D01*
G37*
G36*
G01X164579D02*
G02I-800J0D01*
G37*
G36*
G01X153359D02*
G02I-800J0D01*
G37*
G36*
G01X157099Y1202362D02*
G02I-800J0D01*
G37*
G36*
G01Y1194881D02*
G02I-800J0D01*
G37*
G36*
G01X153359Y1202362D02*
G02I-800J0D01*
G37*
G36*
G01Y1194881D02*
G02I-800J0D01*
G37*
G36*
G01X164579D02*
G02I-800J0D01*
G37*
G36*
G01Y1202362D02*
G02I-800J0D01*
G37*
G36*
G01X157099Y1217322D02*
G02I-800J0D01*
G37*
G36*
G01Y1209842D02*
G02I-800J0D01*
G37*
G36*
G01X153359D02*
G02I-800J0D01*
G37*
G36*
G01X164579D02*
G02I-800J0D01*
G37*
G36*
G01Y1217322D02*
G02I-800J0D01*
G37*
G36*
G01X153359D02*
G02I-800J0D01*
G37*
G36*
G01X160839Y1236023D02*
G02I-800J0D01*
G37*
G36*
G01X164579Y1224803D02*
G02I-800J0D01*
G37*
G36*
G01X157099D02*
G02I-800J0D01*
G37*
G36*
G01Y1228543D02*
G02I-800J0D01*
G37*
G36*
G01X164579D02*
G02I-800J0D01*
G37*
G36*
G01X160839Y1232283D02*
G02I-800J0D01*
G37*
G36*
G01X153359Y1236023D02*
G02I-800J0D01*
G37*
G36*
G01Y1232283D02*
G02I-800J0D01*
G37*
G36*
G01Y1250984D02*
G02I-800J0D01*
G37*
G36*
G01X157099Y1243503D02*
G02I-800J0D01*
G37*
G36*
G01Y1247243D02*
G02I-800J0D01*
G37*
G36*
G01X164579Y1243503D02*
G02I-800J0D01*
G37*
G36*
G01X160839Y1250984D02*
G02I-800J0D01*
G37*
G36*
G01X164579Y1247243D02*
G02I-800J0D01*
G37*
G36*
G01X153359Y1254724D02*
G02I-800J0D01*
G37*
G36*
G01X160839D02*
G02I-800J0D01*
G37*
G36*
G01X175799Y1075196D02*
G02I-800J0D01*
G37*
G36*
G01Y1078936D02*
G02I-800J0D01*
G37*
G36*
G01X179540Y1082677D02*
G02I-800J0D01*
G37*
G36*
G01Y1086417D02*
G02I-800J0D01*
G37*
G36*
G01X175799Y1093897D02*
G02I-800J0D01*
G37*
G36*
G01Y1097637D02*
G02I-800J0D01*
G37*
G36*
G01X179540Y1101376D02*
G02I-800J0D01*
G37*
G36*
G01Y1105117D02*
G02I-800J0D01*
G37*
G36*
G01X168319Y1187401D02*
G02I-800J0D01*
G37*
G36*
G01X175799Y1198621D02*
G02I-800J0D01*
G37*
G36*
G01Y1191141D02*
G02I-800J0D01*
G37*
G36*
G01X168319Y1194881D02*
G02I-800J0D01*
G37*
G36*
G01X172059Y1198621D02*
G02I-800J0D01*
G37*
G36*
G01Y1191141D02*
G02I-800J0D01*
G37*
G36*
G01X168319Y1202362D02*
G02I-800J0D01*
G37*
G36*
G01Y1209842D02*
G02I-800J0D01*
G37*
G36*
G01X172059Y1213582D02*
G02I-800J0D01*
G37*
G36*
G01Y1206102D02*
G02I-800J0D01*
G37*
G36*
G01X175799D02*
G02I-800J0D01*
G37*
G36*
G01X168319Y1217322D02*
G02I-800J0D01*
G37*
G36*
G01X175799Y1213582D02*
G02I-800J0D01*
G37*
G36*
G01X179540Y1228543D02*
G02I-800J0D01*
G37*
G36*
G01X172059Y1224803D02*
G02I-800J0D01*
G37*
G36*
G01X175799Y1232283D02*
G02I-800J0D01*
G37*
G36*
G01X172059Y1228543D02*
G02I-800J0D01*
G37*
G36*
G01X179540Y1224803D02*
G02I-800J0D01*
G37*
G36*
G01X175799Y1236023D02*
G02I-800J0D01*
G37*
G36*
G01X168319Y1232283D02*
G02I-800J0D01*
G37*
G36*
G01Y1236023D02*
G02I-800J0D01*
G37*
G36*
G01Y1250984D02*
G02I-800J0D01*
G37*
G36*
G01X179540Y1247243D02*
G02I-800J0D01*
G37*
G36*
G01X172059D02*
G02I-800J0D01*
G37*
G36*
G01X175799Y1250984D02*
G02I-800J0D01*
G37*
G36*
G01X172059Y1243503D02*
G02I-800J0D01*
G37*
G36*
G01X179540D02*
G02I-800J0D01*
G37*
G36*
G01X168319Y1254724D02*
G02I-800J0D01*
G37*
G36*
G01X175799D02*
G02I-800J0D01*
G37*
G36*
G01X190760Y1075196D02*
G02I-800J0D01*
G37*
G36*
G01X183280D02*
G02I-800J0D01*
G37*
G36*
G01X198240D02*
G02I-800J0D01*
G37*
G36*
G01X187020Y1082677D02*
G02I-800J0D01*
G37*
G36*
G01Y1086417D02*
G02I-800J0D01*
G37*
G36*
G01X183280Y1078936D02*
G02I-800J0D01*
G37*
G36*
G01X190760D02*
G02I-800J0D01*
G37*
G36*
G01X194500Y1086417D02*
G02I-800J0D01*
G37*
G36*
G01Y1082677D02*
G02I-800J0D01*
G37*
G36*
G01X198240Y1078936D02*
G02I-800J0D01*
G37*
G36*
G01X194500Y1105117D02*
G02I-800J0D01*
G37*
G36*
G01X198240Y1093897D02*
G02I-800J0D01*
G37*
G36*
G01X190760Y1097637D02*
G02I-800J0D01*
G37*
G36*
G01X187020Y1105117D02*
G02I-800J0D01*
G37*
G36*
G01X198240Y1097637D02*
G02I-800J0D01*
G37*
G36*
G01X183280Y1093897D02*
G02I-800J0D01*
G37*
G36*
G01Y1097637D02*
G02I-800J0D01*
G37*
G36*
G01X194500Y1101376D02*
G02I-800J0D01*
G37*
G36*
G01X187020D02*
G02I-800J0D01*
G37*
G36*
G01X190760Y1093897D02*
G02I-800J0D01*
G37*
G36*
G01X183280Y1236023D02*
G02I-800J0D01*
G37*
G36*
G01X198240D02*
G02I-800J0D01*
G37*
G36*
G01X187020Y1224803D02*
G02I-800J0D01*
G37*
G36*
G01X183280Y1232283D02*
G02I-800J0D01*
G37*
G36*
G01X194500Y1228543D02*
G02I-800J0D01*
G37*
G36*
G01X198240Y1232283D02*
G02I-800J0D01*
G37*
G36*
G01X190760Y1236023D02*
G02I-800J0D01*
G37*
G36*
G01X187020Y1228543D02*
G02I-800J0D01*
G37*
G36*
G01X194500Y1224803D02*
G02I-800J0D01*
G37*
G36*
G01X190760Y1232283D02*
G02I-800J0D01*
G37*
G36*
G01X183280Y1250984D02*
G02I-800J0D01*
G37*
G36*
G01X198240D02*
G02I-800J0D01*
G37*
G36*
G01X194500Y1247243D02*
G02I-800J0D01*
G37*
G36*
G01Y1243503D02*
G02I-800J0D01*
G37*
G36*
G01X190760Y1250984D02*
G02I-800J0D01*
G37*
G36*
G01X187020Y1247243D02*
G02I-800J0D01*
G37*
G36*
G01Y1243503D02*
G02I-800J0D01*
G37*
G36*
G01X183280Y1254724D02*
G02I-800J0D01*
G37*
G36*
G01X198240D02*
G02I-800J0D01*
G37*
G36*
G01X190760D02*
G02I-800J0D01*
G37*
G36*
G01X205721Y1075196D02*
G02I-800J0D01*
G37*
G36*
G01X213201D02*
G02I-800J0D01*
G37*
G36*
G01Y1078936D02*
G02I-800J0D01*
G37*
G36*
G01X209461Y1082677D02*
G02I-800J0D01*
G37*
G36*
G01X201981D02*
G02I-800J0D01*
G37*
G36*
G01Y1086417D02*
G02I-800J0D01*
G37*
G36*
G01X209461D02*
G02I-800J0D01*
G37*
G36*
G01X205721Y1078936D02*
G02I-800J0D01*
G37*
G36*
G01Y1097637D02*
G02I-800J0D01*
G37*
G36*
G01X209461Y1101376D02*
G02I-800J0D01*
G37*
G36*
G01X213201Y1097637D02*
G02I-800J0D01*
G37*
G36*
G01X209461Y1105117D02*
G02I-800J0D01*
G37*
G36*
G01X213201Y1093897D02*
G02I-800J0D01*
G37*
G36*
G01X201981Y1101376D02*
G02I-800J0D01*
G37*
G36*
G01X205721Y1093897D02*
G02I-800J0D01*
G37*
G36*
G01X201981Y1105117D02*
G02I-800J0D01*
G37*
G36*
G01X205721Y1232283D02*
G02I-800J0D01*
G37*
G36*
G01X201981Y1224803D02*
G02I-800J0D01*
G37*
G36*
G01X213201Y1232283D02*
G02I-800J0D01*
G37*
G36*
G01X209461Y1228543D02*
G02I-800J0D01*
G37*
G36*
G01X213201Y1236023D02*
G02I-800J0D01*
G37*
G36*
G01X209461Y1224803D02*
G02I-800J0D01*
G37*
G36*
G01X201981Y1228543D02*
G02I-800J0D01*
G37*
G36*
G01X205721Y1236023D02*
G02I-800J0D01*
G37*
G36*
G01X209461Y1243503D02*
G02I-800J0D01*
G37*
G36*
G01X205721Y1250984D02*
G02I-800J0D01*
G37*
G36*
G01X209461Y1247243D02*
G02I-800J0D01*
G37*
G36*
G01X201981Y1243503D02*
G02I-800J0D01*
G37*
G36*
G01X213201Y1250984D02*
G02I-800J0D01*
G37*
G36*
G01X201981Y1247243D02*
G02I-800J0D01*
G37*
G36*
G01X213201Y1254724D02*
G02I-800J0D01*
G37*
G36*
G01X205721D02*
G02I-800J0D01*
G37*
G36*
G01X228162Y1075196D02*
G02I-800J0D01*
G37*
G36*
G01X220681D02*
G02I-800J0D01*
G37*
G36*
G01Y1078936D02*
G02I-800J0D01*
G37*
G36*
G01X216941Y1086417D02*
G02I-800J0D01*
G37*
G36*
G01X224422Y1082677D02*
G02I-800J0D01*
G37*
G36*
G01X228162Y1078936D02*
G02I-800J0D01*
G37*
G36*
G01X216941Y1082677D02*
G02I-800J0D01*
G37*
G36*
G01X224422Y1086417D02*
G02I-800J0D01*
G37*
G36*
G01X216941Y1101376D02*
G02I-800J0D01*
G37*
G36*
G01X228162Y1093897D02*
G02I-800J0D01*
G37*
G36*
G01X220681Y1097637D02*
G02I-800J0D01*
G37*
G36*
G01X224421Y1101376D02*
G02I-800J0D01*
G37*
G36*
G01Y1105117D02*
G02I-800J0D01*
G37*
G36*
G01X216941D02*
G02I-800J0D01*
G37*
G36*
G01X220681Y1093897D02*
G02I-800J0D01*
G37*
G36*
G01X228162Y1097637D02*
G02I-800J0D01*
G37*
G36*
G01X220681Y1232283D02*
G02I-800J0D01*
G37*
G36*
G01Y1236023D02*
G02I-800J0D01*
G37*
G36*
G01X216941Y1224803D02*
G02I-800J0D01*
G37*
G36*
G01X224422D02*
G02I-800J0D01*
G37*
G36*
G01X228162Y1232283D02*
G02I-800J0D01*
G37*
G36*
G01X224422Y1228543D02*
G02I-800J0D01*
G37*
G36*
G01X216941D02*
G02I-800J0D01*
G37*
G36*
G01X228162Y1236023D02*
G02I-800J0D01*
G37*
G36*
G01X224422Y1243503D02*
G02I-800J0D01*
G37*
G36*
G01X216941Y1247243D02*
G02I-800J0D01*
G37*
G36*
G01X224422D02*
G02I-800J0D01*
G37*
G36*
G01X216941Y1243503D02*
G02I-800J0D01*
G37*
G36*
G01X220681Y1250984D02*
G02I-800J0D01*
G37*
G36*
G01X228162D02*
G02I-800J0D01*
G37*
G36*
G01X220681Y1254724D02*
G02I-800J0D01*
G37*
G36*
G01X228162D02*
G02I-800J0D01*
G37*
G36*
G01X235641Y1075195D02*
G02I-800J0D01*
G37*
G36*
G01X243121Y1075196D02*
G02I-800J0D01*
G37*
G36*
G01X231902Y1082677D02*
G02I-800J0D01*
G37*
G36*
G01Y1086417D02*
G02I-800J0D01*
G37*
G36*
G01X243121Y1078936D02*
G02I-800J0D01*
G37*
G36*
G01X246861Y1082677D02*
G02I-800J0D01*
G37*
G36*
G01X239381Y1082676D02*
G02I-800J0D01*
G37*
G36*
G01X235641Y1078935D02*
G02I-800J0D01*
G37*
G36*
G01X246861Y1086417D02*
G02I-800J0D01*
G37*
G36*
G01X239381Y1086416D02*
G02I-800J0D01*
G37*
G36*
G01X231902Y1101376D02*
G02I-800J0D01*
G37*
G36*
G01X235641Y1093897D02*
G02I-800J0D01*
G37*
G36*
G01X246862Y1105117D02*
G02I-800J0D01*
G37*
G36*
G01X243121Y1097637D02*
G02I-800J0D01*
G37*
G36*
G01X235641D02*
G02I-800J0D01*
G37*
G36*
G01X239382Y1101376D02*
G02I-800J0D01*
G37*
G36*
G01X246862D02*
G02I-800J0D01*
G37*
G36*
G01X239382Y1105117D02*
G02I-800J0D01*
G37*
G36*
G01X243121Y1093897D02*
G02I-800J0D01*
G37*
G36*
G01X231902Y1105117D02*
G02I-800J0D01*
G37*
G36*
G01X239382Y1224803D02*
G02I-800J0D01*
G37*
G36*
G01Y1228543D02*
G02I-800J0D01*
G37*
G36*
G01X231902D02*
G02I-800J0D01*
G37*
G36*
G01X243122Y1236023D02*
G02I-800J0D01*
G37*
G36*
G01X231902Y1224803D02*
G02I-800J0D01*
G37*
G36*
G01X243122Y1232283D02*
G02I-800J0D01*
G37*
G36*
G01X246862Y1228543D02*
G02I-800J0D01*
G37*
G36*
G01X235642Y1232283D02*
G02I-800J0D01*
G37*
G36*
G01X246862Y1224803D02*
G02I-800J0D01*
G37*
G36*
G01X235642Y1236023D02*
G02I-800J0D01*
G37*
G36*
G01X239382Y1247243D02*
G02I-800J0D01*
G37*
G36*
G01X246862Y1243503D02*
G02I-800J0D01*
G37*
G36*
G01X231902D02*
G02I-800J0D01*
G37*
G36*
G01X243122Y1250984D02*
G02I-800J0D01*
G37*
G36*
G01X235642D02*
G02I-800J0D01*
G37*
G36*
G01X246862Y1247243D02*
G02I-800J0D01*
G37*
G36*
G01X239382Y1243503D02*
G02I-800J0D01*
G37*
G36*
G01X231902Y1247243D02*
G02I-800J0D01*
G37*
G36*
G01X235642Y1254724D02*
G02I-800J0D01*
G37*
G36*
G01X243122D02*
G02I-800J0D01*
G37*
G36*
G01X250602Y1075196D02*
G02I-800J0D01*
G37*
G36*
G01X258082D02*
G02I-800J0D01*
G37*
G36*
G01X250602Y1078936D02*
G02I-800J0D01*
G37*
G36*
G01X261822Y1086417D02*
G02I-800J0D01*
G37*
G36*
G01X254342Y1082676D02*
G02I-800J0D01*
G37*
G36*
G01X258082Y1078936D02*
G02I-800J0D01*
G37*
G36*
G01X254342Y1086416D02*
G02I-800J0D01*
G37*
G36*
G01X261822Y1082677D02*
G02I-800J0D01*
G37*
G36*
G01X250602Y1097637D02*
G02I-800J0D01*
G37*
G36*
G01X258082D02*
G02I-800J0D01*
G37*
G36*
G01X250602Y1093897D02*
G02I-800J0D01*
G37*
G36*
G01X254343Y1105117D02*
G02I-800J0D01*
G37*
G36*
G01Y1101376D02*
G02I-800J0D01*
G37*
G36*
G01X258082Y1093897D02*
G02I-800J0D01*
G37*
G36*
G01X261823Y1105117D02*
G02I-800J0D01*
G37*
G36*
G01Y1101376D02*
G02I-800J0D01*
G37*
G36*
G01Y1224803D02*
G02I-800J0D01*
G37*
G36*
G01X254343Y1228543D02*
G02I-800J0D01*
G37*
G36*
G01X250603Y1232283D02*
G02I-800J0D01*
G37*
G36*
G01X258083D02*
G02I-800J0D01*
G37*
G36*
G01Y1236023D02*
G02I-800J0D01*
G37*
G36*
G01X261823Y1228543D02*
G02I-800J0D01*
G37*
G36*
G01X254343Y1224803D02*
G02I-800J0D01*
G37*
G36*
G01X250603Y1236023D02*
G02I-800J0D01*
G37*
G36*
G01X261823Y1243503D02*
G02I-800J0D01*
G37*
G36*
G01X250603Y1250984D02*
G02I-800J0D01*
G37*
G36*
G01X261823Y1247243D02*
G02I-800J0D01*
G37*
G36*
G01X258083Y1250984D02*
G02I-800J0D01*
G37*
G36*
G01X254343Y1247243D02*
G02I-800J0D01*
G37*
G36*
G01Y1243503D02*
G02I-800J0D01*
G37*
G36*
G01X258083Y1254724D02*
G02I-800J0D01*
G37*
G36*
G01X250603D02*
G02I-800J0D01*
G37*
G36*
G01X280523Y1075196D02*
G02I-800J0D01*
G37*
G36*
G01X265562D02*
G02I-800J0D01*
G37*
G36*
G01X273043D02*
G02I-800J0D01*
G37*
G36*
G01X276782Y1082677D02*
G02I-800J0D01*
G37*
G36*
G01Y1086417D02*
G02I-800J0D01*
G37*
G36*
G01X269302Y1082676D02*
G02I-800J0D01*
G37*
G36*
G01X273043Y1078936D02*
G02I-800J0D01*
G37*
G36*
G01X269302Y1086416D02*
G02I-800J0D01*
G37*
G36*
G01X280523Y1078936D02*
G02I-800J0D01*
G37*
G36*
G01X265562D02*
G02I-800J0D01*
G37*
G36*
G01Y1097637D02*
G02I-800J0D01*
G37*
G36*
G01X269303Y1105117D02*
G02I-800J0D01*
G37*
G36*
G01X273043Y1097637D02*
G02I-800J0D01*
G37*
G36*
G01X276784Y1105117D02*
G02I-800J0D01*
G37*
G36*
G01X280523Y1093897D02*
G02I-800J0D01*
G37*
G36*
G01X273043D02*
G02I-800J0D01*
G37*
G36*
G01X280523Y1097637D02*
G02I-800J0D01*
G37*
G36*
G01X269303Y1101376D02*
G02I-800J0D01*
G37*
G36*
G01X276784D02*
G02I-800J0D01*
G37*
G36*
G01X265562Y1093897D02*
G02I-800J0D01*
G37*
G36*
G01X265563Y1232283D02*
G02I-800J0D01*
G37*
G36*
G01X269303Y1224803D02*
G02I-800J0D01*
G37*
G36*
G01X276784D02*
G02I-800J0D01*
G37*
G36*
G01X273044Y1236023D02*
G02I-800J0D01*
G37*
G36*
G01X280524Y1232283D02*
G02I-800J0D01*
G37*
G36*
G01Y1236023D02*
G02I-800J0D01*
G37*
G36*
G01X276784Y1228543D02*
G02I-800J0D01*
G37*
G36*
G01X273044Y1232283D02*
G02I-800J0D01*
G37*
G36*
G01X269303Y1228543D02*
G02I-800J0D01*
G37*
G36*
G01X265563Y1236023D02*
G02I-800J0D01*
G37*
G36*
G01Y1250984D02*
G02I-800J0D01*
G37*
G36*
G01X269303Y1243503D02*
G02I-800J0D01*
G37*
G36*
G01Y1247243D02*
G02I-800J0D01*
G37*
G36*
G01X273044Y1250984D02*
G02I-800J0D01*
G37*
G36*
G01X276784Y1243503D02*
G02I-800J0D01*
G37*
G36*
G01Y1247243D02*
G02I-800J0D01*
G37*
G36*
G01X280524Y1250984D02*
G02I-800J0D01*
G37*
G36*
G01X265563Y1254724D02*
G02I-800J0D01*
G37*
G36*
G01X273044D02*
G02I-800J0D01*
G37*
G36*
G01X280524D02*
G02I-800J0D01*
G37*
G36*
G01X288003Y1075196D02*
G02I-800J0D01*
G37*
G36*
G01X295484D02*
G02I-800J0D01*
G37*
G36*
G01X291743Y1086417D02*
G02I-800J0D01*
G37*
G36*
G01X288003Y1078936D02*
G02I-800J0D01*
G37*
G36*
G01X291743Y1082677D02*
G02I-800J0D01*
G37*
G36*
G01X284263Y1082676D02*
G02I-800J0D01*
G37*
G36*
G01Y1086416D02*
G02I-800J0D01*
G37*
G36*
G01X295484Y1078936D02*
G02I-800J0D01*
G37*
G36*
G01X284264Y1101376D02*
G02I-800J0D01*
G37*
G36*
G01X295484Y1093897D02*
G02I-800J0D01*
G37*
G36*
G01X288003D02*
G02I-800J0D01*
G37*
G36*
G01X295484Y1097637D02*
G02I-800J0D01*
G37*
G36*
G01X284264Y1105117D02*
G02I-800J0D01*
G37*
G36*
G01X291744Y1101376D02*
G02I-800J0D01*
G37*
G36*
G01Y1105117D02*
G02I-800J0D01*
G37*
G36*
G01X288003Y1097637D02*
G02I-800J0D01*
G37*
G36*
G01X295484Y1123818D02*
G02I-800J0D01*
G37*
G36*
G01Y1116338D02*
G02I-800J0D01*
G37*
G36*
G01Y1131299D02*
G02I-800J0D01*
G37*
G36*
G01X295485Y1198621D02*
G02I-800J0D01*
G37*
G36*
G01Y1213582D02*
G02I-800J0D01*
G37*
G36*
G01Y1206102D02*
G02I-800J0D01*
G37*
G36*
G01X288004Y1232283D02*
G02I-800J0D01*
G37*
G36*
G01X284264Y1224803D02*
G02I-800J0D01*
G37*
G36*
G01Y1228543D02*
G02I-800J0D01*
G37*
G36*
G01X288004Y1236023D02*
G02I-800J0D01*
G37*
G36*
G01X295485D02*
G02I-800J0D01*
G37*
G36*
G01X291744Y1224803D02*
G02I-800J0D01*
G37*
G36*
G01X295485Y1232283D02*
G02I-800J0D01*
G37*
G36*
G01X291744Y1228543D02*
G02I-800J0D01*
G37*
G36*
G01X284264Y1243503D02*
G02I-800J0D01*
G37*
G36*
G01Y1247243D02*
G02I-800J0D01*
G37*
G36*
G01X288004Y1250984D02*
G02I-800J0D01*
G37*
G36*
G01X295485D02*
G02I-800J0D01*
G37*
G36*
G01X291744Y1247243D02*
G02I-800J0D01*
G37*
G36*
G01Y1243503D02*
G02I-800J0D01*
G37*
G36*
G01X288004Y1254724D02*
G02I-800J0D01*
G37*
G36*
G01X295485D02*
G02I-800J0D01*
G37*
G36*
G01X302964Y1075196D02*
G02I-800J0D01*
G37*
G36*
G01X310444D02*
G02I-800J0D01*
G37*
G36*
G01X306704Y1082677D02*
G02I-800J0D01*
G37*
G36*
G01X302964Y1078936D02*
G02I-800J0D01*
G37*
G36*
G01X306704Y1086417D02*
G02I-800J0D01*
G37*
G36*
G01X310444Y1078936D02*
G02I-800J0D01*
G37*
G36*
G01X299224Y1086416D02*
G02I-800J0D01*
G37*
G36*
G01Y1082676D02*
G02I-800J0D01*
G37*
G36*
G01X299225Y1105117D02*
G02I-800J0D01*
G37*
G36*
G01Y1101376D02*
G02I-800J0D01*
G37*
G36*
G01X310444Y1097637D02*
G02I-800J0D01*
G37*
G36*
G01X302964D02*
G02I-800J0D01*
G37*
G36*
G01X306705Y1105117D02*
G02I-800J0D01*
G37*
G36*
G01X310444Y1093897D02*
G02I-800J0D01*
G37*
G36*
G01X306705Y1101376D02*
G02I-800J0D01*
G37*
G36*
G01X302964Y1093897D02*
G02I-800J0D01*
G37*
G36*
G01X302965Y1120078D02*
G02I-800J0D01*
G37*
G36*
G01X306705Y1112598D02*
G02I-800J0D01*
G37*
G36*
G01X299225Y1116338D02*
G02I-800J0D01*
G37*
G36*
G01X306705Y1120078D02*
G02I-800J0D01*
G37*
G36*
G01X302965Y1112598D02*
G02I-800J0D01*
G37*
G36*
G01X299225Y1123818D02*
G02I-800J0D01*
G37*
G36*
G01X306705Y1127559D02*
G02I-800J0D01*
G37*
G36*
G01Y1135039D02*
G02I-800J0D01*
G37*
G36*
G01X302965D02*
G02I-800J0D01*
G37*
G36*
G01Y1127559D02*
G02I-800J0D01*
G37*
G36*
G01X299225Y1131299D02*
G02I-800J0D01*
G37*
G36*
G01Y1198621D02*
G02I-800J0D01*
G37*
G36*
G01X306705Y1202362D02*
G02I-800J0D01*
G37*
G36*
G01X302965D02*
G02I-800J0D01*
G37*
G36*
G01X299225Y1213582D02*
G02I-800J0D01*
G37*
G36*
G01X306705Y1209842D02*
G02I-800J0D01*
G37*
G36*
G01Y1217322D02*
G02I-800J0D01*
G37*
G36*
G01X302965Y1209842D02*
G02I-800J0D01*
G37*
G36*
G01X299225Y1206102D02*
G02I-800J0D01*
G37*
G36*
G01X302965Y1217322D02*
G02I-800J0D01*
G37*
G36*
G01Y1232283D02*
G02I-800J0D01*
G37*
G36*
G01X310445D02*
G02I-800J0D01*
G37*
G36*
G01X299225Y1224803D02*
G02I-800J0D01*
G37*
G36*
G01Y1228543D02*
G02I-800J0D01*
G37*
G36*
G01X310445Y1236023D02*
G02I-800J0D01*
G37*
G36*
G01X306705Y1228543D02*
G02I-800J0D01*
G37*
G36*
G01Y1224803D02*
G02I-800J0D01*
G37*
G36*
G01X302965Y1236023D02*
G02I-800J0D01*
G37*
G36*
G01X299225Y1247243D02*
G02I-800J0D01*
G37*
G36*
G01X310445Y1250984D02*
G02I-800J0D01*
G37*
G36*
G01X299225Y1243503D02*
G02I-800J0D01*
G37*
G36*
G01X306705D02*
G02I-800J0D01*
G37*
G36*
G01Y1247243D02*
G02I-800J0D01*
G37*
G36*
G01X302965Y1250984D02*
G02I-800J0D01*
G37*
G36*
G01X310445Y1254724D02*
G02I-800J0D01*
G37*
G36*
G01X302965D02*
G02I-800J0D01*
G37*
G36*
G01X317924Y1075196D02*
G02I-800J0D01*
G37*
G36*
G01X321666Y1090157D02*
G02I-800J0D01*
G37*
G36*
G01X325406D02*
G02I-800J0D01*
G37*
G36*
G01Y1082676D02*
G02I-800J0D01*
G37*
G36*
G01X317924Y1078936D02*
G02I-800J0D01*
G37*
G36*
G01X314184Y1082677D02*
G02I-800J0D01*
G37*
G36*
G01Y1086417D02*
G02I-800J0D01*
G37*
G36*
G01X321666Y1082676D02*
G02I-800J0D01*
G37*
G36*
G01X314185Y1101377D02*
G02I-800J0D01*
G37*
G36*
G01X317925Y1093897D02*
G02I-800J0D01*
G37*
G36*
G01X321666Y1101377D02*
G02I-800J0D01*
G37*
G36*
G01X314185Y1105117D02*
G02I-800J0D01*
G37*
G36*
G01X325406Y1101377D02*
G02I-800J0D01*
G37*
G36*
G01X317925Y1097637D02*
G02I-800J0D01*
G37*
G36*
G01X314185Y1120078D02*
G02I-800J0D01*
G37*
G36*
G01X325406Y1123818D02*
G02I-800J0D01*
G37*
G36*
G01Y1108858D02*
G02I-800J0D01*
G37*
G36*
G01X321666D02*
G02I-800J0D01*
G37*
G36*
G01X317925Y1112598D02*
G02I-800J0D01*
G37*
G36*
G01X325406Y1116338D02*
G02I-800J0D01*
G37*
G36*
G01X314185Y1112598D02*
G02I-800J0D01*
G37*
G36*
G01X317925Y1120078D02*
G02I-800J0D01*
G37*
G36*
G01X321666Y1116338D02*
G02I-800J0D01*
G37*
G36*
G01Y1123818D02*
G02I-800J0D01*
G37*
G36*
G01X314185Y1127558D02*
G02I-800J0D01*
G37*
G36*
G01X317925Y1135039D02*
G02I-800J0D01*
G37*
G36*
G01X314185D02*
G02I-800J0D01*
G37*
G36*
G01X325406Y1131299D02*
G02I-800J0D01*
G37*
G36*
G01X317925Y1127558D02*
G02I-800J0D01*
G37*
G36*
G01X321666Y1131299D02*
G02I-800J0D01*
G37*
G36*
G01Y1198621D02*
G02I-800J0D01*
G37*
G36*
G01X314185Y1202362D02*
G02I-800J0D01*
G37*
G36*
G01X325406Y1198621D02*
G02I-800J0D01*
G37*
G36*
G01X317925Y1202362D02*
G02I-800J0D01*
G37*
G36*
G01Y1217322D02*
G02I-800J0D01*
G37*
G36*
G01Y1209842D02*
G02I-800J0D01*
G37*
G36*
G01X325406Y1213582D02*
G02I-800J0D01*
G37*
G36*
G01X321666Y1221062D02*
G02I-800J0D01*
G37*
G36*
G01X314185Y1209842D02*
G02I-800J0D01*
G37*
G36*
G01X321666Y1206102D02*
G02I-800J0D01*
G37*
G36*
G01Y1213582D02*
G02I-800J0D01*
G37*
G36*
G01X325406Y1221062D02*
G02I-800J0D01*
G37*
G36*
G01Y1206102D02*
G02I-800J0D01*
G37*
G36*
G01X314185Y1217322D02*
G02I-800J0D01*
G37*
G36*
G01X317925Y1236023D02*
G02I-800J0D01*
G37*
G36*
G01X314185Y1224803D02*
G02I-800J0D01*
G37*
G36*
G01X325406Y1228543D02*
G02I-800J0D01*
G37*
G36*
G01X317925Y1232283D02*
G02I-800J0D01*
G37*
G36*
G01X314185Y1228543D02*
G02I-800J0D01*
G37*
G36*
G01X321666D02*
G02I-800J0D01*
G37*
G36*
G01X325406Y1239763D02*
G02I-800J0D01*
G37*
G36*
G01X314185Y1247243D02*
G02I-800J0D01*
G37*
G36*
G01X321666D02*
G02I-800J0D01*
G37*
G36*
G01X317925Y1250984D02*
G02I-800J0D01*
G37*
G36*
G01X321666Y1239763D02*
G02I-800J0D01*
G37*
G36*
G01X314185Y1243503D02*
G02I-800J0D01*
G37*
G36*
G01X325406Y1247243D02*
G02I-800J0D01*
G37*
G36*
G01X317925Y1254724D02*
G02I-800J0D01*
G37*
G36*
G01X602965Y1191141D02*
G02I-800J0D01*
G37*
G36*
G01Y1198621D02*
G02I-800J0D01*
G37*
G36*
G01Y1221062D02*
G02I-800J0D01*
G37*
G36*
G01Y1206102D02*
G02I-800J0D01*
G37*
G36*
G01Y1213582D02*
G02I-800J0D01*
G37*
G36*
G01Y1228543D02*
G02I-800J0D01*
G37*
G36*
G01Y1247243D02*
G02I-800J0D01*
G37*
G36*
G01Y1239763D02*
G02I-800J0D01*
G37*
G36*
G01X614186Y1187401D02*
G02I-800J0D01*
G37*
G36*
G01X610446D02*
G02I-800J0D01*
G37*
G36*
G01X621666D02*
G02I-800J0D01*
G37*
G36*
G01X606705Y1191141D02*
G02I-800J0D01*
G37*
G36*
G01X614186Y1194881D02*
G02I-800J0D01*
G37*
G36*
G01X606705Y1198621D02*
G02I-800J0D01*
G37*
G36*
G01X610446Y1194881D02*
G02I-800J0D01*
G37*
G36*
G01Y1202362D02*
G02I-800J0D01*
G37*
G36*
G01X614186D02*
G02I-800J0D01*
G37*
G36*
G01X621666D02*
G02I-800J0D01*
G37*
G36*
G01Y1194881D02*
G02I-800J0D01*
G37*
G36*
G01X614186Y1217322D02*
G02I-800J0D01*
G37*
G36*
G01X606705Y1221062D02*
G02I-800J0D01*
G37*
G36*
G01X610446Y1217322D02*
G02I-800J0D01*
G37*
G36*
G01Y1209842D02*
G02I-800J0D01*
G37*
G36*
G01X606705Y1206102D02*
G02I-800J0D01*
G37*
G36*
G01Y1213582D02*
G02I-800J0D01*
G37*
G36*
G01X621666Y1209842D02*
G02I-800J0D01*
G37*
G36*
G01X614186D02*
G02I-800J0D01*
G37*
G36*
G01X621666Y1217322D02*
G02I-800J0D01*
G37*
G36*
G01X606705Y1228543D02*
G02I-800J0D01*
G37*
G36*
G01X621666D02*
G02I-800J0D01*
G37*
G36*
G01Y1224803D02*
G02I-800J0D01*
G37*
G36*
G01X610446Y1232283D02*
G02I-800J0D01*
G37*
G36*
G01X617926Y1236023D02*
G02I-800J0D01*
G37*
G36*
G01X614186Y1228543D02*
G02I-800J0D01*
G37*
G36*
G01X617926Y1232283D02*
G02I-800J0D01*
G37*
G36*
G01X610446Y1236023D02*
G02I-800J0D01*
G37*
G36*
G01X614186Y1224803D02*
G02I-800J0D01*
G37*
G36*
G01X606705Y1247243D02*
G02I-800J0D01*
G37*
G36*
G01X617926Y1250984D02*
G02I-800J0D01*
G37*
G36*
G01X621666Y1243503D02*
G02I-800J0D01*
G37*
G36*
G01Y1247243D02*
G02I-800J0D01*
G37*
G36*
G01X614186D02*
G02I-800J0D01*
G37*
G36*
G01Y1243503D02*
G02I-800J0D01*
G37*
G36*
G01X610446Y1250984D02*
G02I-800J0D01*
G37*
G36*
G01X606705Y1239763D02*
G02I-800J0D01*
G37*
G36*
G01X610446Y1254724D02*
G02I-800J0D01*
G37*
G36*
G01X617926D02*
G02I-800J0D01*
G37*
G36*
G01X632886Y1075196D02*
G02I-800J0D01*
G37*
G36*
G01Y1078936D02*
G02I-800J0D01*
G37*
G36*
G01X636627Y1086417D02*
G02I-800J0D01*
G37*
G36*
G01Y1082677D02*
G02I-800J0D01*
G37*
G36*
G01X632886Y1097637D02*
G02I-800J0D01*
G37*
G36*
G01X636627Y1105117D02*
G02I-800J0D01*
G37*
G36*
G01X632886Y1093897D02*
G02I-800J0D01*
G37*
G36*
G01X636627Y1101376D02*
G02I-800J0D01*
G37*
G36*
G01X625406Y1187401D02*
G02I-800J0D01*
G37*
G36*
G01X629146Y1191141D02*
G02I-800J0D01*
G37*
G36*
G01X625406Y1194881D02*
G02I-800J0D01*
G37*
G36*
G01X632886Y1191141D02*
G02I-800J0D01*
G37*
G36*
G01X629146Y1198621D02*
G02I-800J0D01*
G37*
G36*
G01X625406Y1202362D02*
G02I-800J0D01*
G37*
G36*
G01X632886Y1198621D02*
G02I-800J0D01*
G37*
G36*
G01X629146Y1206102D02*
G02I-800J0D01*
G37*
G36*
G01X632886D02*
G02I-800J0D01*
G37*
G36*
G01X625406Y1217322D02*
G02I-800J0D01*
G37*
G36*
G01X629146Y1213582D02*
G02I-800J0D01*
G37*
G36*
G01X632886D02*
G02I-800J0D01*
G37*
G36*
G01X625406Y1209842D02*
G02I-800J0D01*
G37*
G36*
G01X629146Y1224803D02*
G02I-800J0D01*
G37*
G36*
G01Y1228543D02*
G02I-800J0D01*
G37*
G36*
G01X636627D02*
G02I-800J0D01*
G37*
G36*
G01X632886Y1232283D02*
G02I-800J0D01*
G37*
G36*
G01Y1236023D02*
G02I-800J0D01*
G37*
G36*
G01X625406Y1232283D02*
G02I-800J0D01*
G37*
G36*
G01Y1236023D02*
G02I-800J0D01*
G37*
G36*
G01X636627Y1224803D02*
G02I-800J0D01*
G37*
G36*
G01X625406Y1250984D02*
G02I-800J0D01*
G37*
G36*
G01X636627Y1243503D02*
G02I-800J0D01*
G37*
G36*
G01X632886Y1250984D02*
G02I-800J0D01*
G37*
G36*
G01X636627Y1247243D02*
G02I-800J0D01*
G37*
G36*
G01X629146Y1243503D02*
G02I-800J0D01*
G37*
G36*
G01Y1247243D02*
G02I-800J0D01*
G37*
G36*
G01X625406Y1254724D02*
G02I-800J0D01*
G37*
G36*
G01X632886D02*
G02I-800J0D01*
G37*
G36*
G01X640367Y1075196D02*
G02I-800J0D01*
G37*
G36*
G01X647847D02*
G02I-800J0D01*
G37*
G36*
G01X644107Y1086417D02*
G02I-800J0D01*
G37*
G36*
G01Y1082677D02*
G02I-800J0D01*
G37*
G36*
G01X647847Y1078936D02*
G02I-800J0D01*
G37*
G36*
G01X640367D02*
G02I-800J0D01*
G37*
G36*
G01X651587Y1082677D02*
G02I-800J0D01*
G37*
G36*
G01Y1086417D02*
G02I-800J0D01*
G37*
G36*
G01Y1105117D02*
G02I-800J0D01*
G37*
G36*
G01X647847Y1093897D02*
G02I-800J0D01*
G37*
G36*
G01X640367Y1097637D02*
G02I-800J0D01*
G37*
G36*
G01X644107Y1105117D02*
G02I-800J0D01*
G37*
G36*
G01X647847Y1097637D02*
G02I-800J0D01*
G37*
G36*
G01X640367Y1093897D02*
G02I-800J0D01*
G37*
G36*
G01X644107Y1101376D02*
G02I-800J0D01*
G37*
G36*
G01X651587D02*
G02I-800J0D01*
G37*
G36*
G01X640367Y1236023D02*
G02I-800J0D01*
G37*
G36*
G01X647847D02*
G02I-800J0D01*
G37*
G36*
G01X640367Y1232283D02*
G02I-800J0D01*
G37*
G36*
G01X644107Y1224803D02*
G02I-800J0D01*
G37*
G36*
G01X647847Y1232283D02*
G02I-800J0D01*
G37*
G36*
G01X644107Y1228543D02*
G02I-800J0D01*
G37*
G36*
G01X651587D02*
G02I-800J0D01*
G37*
G36*
G01Y1224803D02*
G02I-800J0D01*
G37*
G36*
G01X640367Y1250984D02*
G02I-800J0D01*
G37*
G36*
G01X651587Y1247243D02*
G02I-800J0D01*
G37*
G36*
G01Y1243503D02*
G02I-800J0D01*
G37*
G36*
G01X647847Y1250984D02*
G02I-800J0D01*
G37*
G36*
G01X644107Y1247243D02*
G02I-800J0D01*
G37*
G36*
G01Y1243503D02*
G02I-800J0D01*
G37*
G36*
G01X640367Y1254724D02*
G02I-800J0D01*
G37*
G36*
G01X647847D02*
G02I-800J0D01*
G37*
G36*
G01X662808Y1075196D02*
G02I-800J0D01*
G37*
G36*
G01X655327D02*
G02I-800J0D01*
G37*
G36*
G01X670288D02*
G02I-800J0D01*
G37*
G36*
G01X662808Y1078936D02*
G02I-800J0D01*
G37*
G36*
G01X666548Y1082677D02*
G02I-800J0D01*
G37*
G36*
G01X659068D02*
G02I-800J0D01*
G37*
G36*
G01X655327Y1078936D02*
G02I-800J0D01*
G37*
G36*
G01X666548Y1086417D02*
G02I-800J0D01*
G37*
G36*
G01X659068D02*
G02I-800J0D01*
G37*
G36*
G01X670288Y1078936D02*
G02I-800J0D01*
G37*
G36*
G01X662808Y1097637D02*
G02I-800J0D01*
G37*
G36*
G01X655327Y1093897D02*
G02I-800J0D01*
G37*
G36*
G01X670288D02*
G02I-800J0D01*
G37*
G36*
G01X666548Y1105117D02*
G02I-800J0D01*
G37*
G36*
G01X655327Y1097637D02*
G02I-800J0D01*
G37*
G36*
G01X662808Y1093897D02*
G02I-800J0D01*
G37*
G36*
G01X670288Y1097637D02*
G02I-800J0D01*
G37*
G36*
G01X666548Y1101376D02*
G02I-800J0D01*
G37*
G36*
G01X659068Y1105117D02*
G02I-800J0D01*
G37*
G36*
G01Y1101376D02*
G02I-800J0D01*
G37*
G36*
G01X670288Y1232283D02*
G02I-800J0D01*
G37*
G36*
G01X655327Y1236023D02*
G02I-800J0D01*
G37*
G36*
G01X662808Y1232283D02*
G02I-800J0D01*
G37*
G36*
G01X666548Y1224803D02*
G02I-800J0D01*
G37*
G36*
G01X662808Y1236023D02*
G02I-800J0D01*
G37*
G36*
G01X659068Y1224803D02*
G02I-800J0D01*
G37*
G36*
G01X666548Y1228543D02*
G02I-800J0D01*
G37*
G36*
G01X659068D02*
G02I-800J0D01*
G37*
G36*
G01X670288Y1236023D02*
G02I-800J0D01*
G37*
G36*
G01X655327Y1232283D02*
G02I-800J0D01*
G37*
G36*
G01X666548Y1247243D02*
G02I-800J0D01*
G37*
G36*
G01X670288Y1250984D02*
G02I-800J0D01*
G37*
G36*
G01X659068Y1247243D02*
G02I-800J0D01*
G37*
G36*
G01X662808Y1250984D02*
G02I-800J0D01*
G37*
G36*
G01X666548Y1243503D02*
G02I-800J0D01*
G37*
G36*
G01X659068D02*
G02I-800J0D01*
G37*
G36*
G01X655327Y1250984D02*
G02I-800J0D01*
G37*
G36*
G01X662808Y1254724D02*
G02I-800J0D01*
G37*
G36*
G01X670288D02*
G02I-800J0D01*
G37*
G36*
G01X655327D02*
G02I-800J0D01*
G37*
G36*
G01X677768Y1075196D02*
G02I-800J0D01*
G37*
G36*
G01X685249D02*
G02I-800J0D01*
G37*
G36*
G01X677768Y1078936D02*
G02I-800J0D01*
G37*
G36*
G01X681509Y1086417D02*
G02I-800J0D01*
G37*
G36*
G01X685249Y1078936D02*
G02I-800J0D01*
G37*
G36*
G01X674028Y1086417D02*
G02I-800J0D01*
G37*
G36*
G01Y1082677D02*
G02I-800J0D01*
G37*
G36*
G01X681509D02*
G02I-800J0D01*
G37*
G36*
G01X674028Y1105117D02*
G02I-800J0D01*
G37*
G36*
G01X685249Y1093897D02*
G02I-800J0D01*
G37*
G36*
G01X677768D02*
G02I-800J0D01*
G37*
G36*
G01X685249Y1097637D02*
G02I-800J0D01*
G37*
G36*
G01X677768D02*
G02I-800J0D01*
G37*
G36*
G01X681508Y1105117D02*
G02I-800J0D01*
G37*
G36*
G01X674028Y1101376D02*
G02I-800J0D01*
G37*
G36*
G01X681508D02*
G02I-800J0D01*
G37*
G36*
G01X677768Y1236023D02*
G02I-800J0D01*
G37*
G36*
G01X685249Y1232283D02*
G02I-800J0D01*
G37*
G36*
G01X674028Y1228543D02*
G02I-800J0D01*
G37*
G36*
G01X681509Y1224803D02*
G02I-800J0D01*
G37*
G36*
G01X685249Y1236023D02*
G02I-800J0D01*
G37*
G36*
G01X677768Y1232283D02*
G02I-800J0D01*
G37*
G36*
G01X674028Y1224803D02*
G02I-800J0D01*
G37*
G36*
G01X681509Y1228543D02*
G02I-800J0D01*
G37*
G36*
G01X674028Y1243503D02*
G02I-800J0D01*
G37*
G36*
G01X681509Y1247243D02*
G02I-800J0D01*
G37*
G36*
G01X674028D02*
G02I-800J0D01*
G37*
G36*
G01X685249Y1250984D02*
G02I-800J0D01*
G37*
G36*
G01X677768D02*
G02I-800J0D01*
G37*
G36*
G01X681509Y1243503D02*
G02I-800J0D01*
G37*
G36*
G01X685249Y1254724D02*
G02I-800J0D01*
G37*
G36*
G01X677768D02*
G02I-800J0D01*
G37*
G36*
G01X700208Y1075196D02*
G02I-800J0D01*
G37*
G36*
G01X692728Y1075195D02*
G02I-800J0D01*
G37*
G36*
G01X688989Y1086417D02*
G02I-800J0D01*
G37*
G36*
G01Y1082677D02*
G02I-800J0D01*
G37*
G36*
G01X692728Y1078935D02*
G02I-800J0D01*
G37*
G36*
G01X700208Y1078936D02*
G02I-800J0D01*
G37*
G36*
G01X696468Y1086416D02*
G02I-800J0D01*
G37*
G36*
G01Y1082676D02*
G02I-800J0D01*
G37*
G36*
G01X688989Y1105117D02*
G02I-800J0D01*
G37*
G36*
G01X696469Y1101376D02*
G02I-800J0D01*
G37*
G36*
G01X700208Y1097637D02*
G02I-800J0D01*
G37*
G36*
G01X696469Y1105117D02*
G02I-800J0D01*
G37*
G36*
G01X692728Y1093897D02*
G02I-800J0D01*
G37*
G36*
G01Y1097637D02*
G02I-800J0D01*
G37*
G36*
G01X700208Y1093897D02*
G02I-800J0D01*
G37*
G36*
G01X688989Y1101376D02*
G02I-800J0D01*
G37*
G36*
G01Y1228543D02*
G02I-800J0D01*
G37*
G36*
G01X692729Y1236023D02*
G02I-800J0D01*
G37*
G36*
G01X700209Y1232283D02*
G02I-800J0D01*
G37*
G36*
G01X688989Y1224803D02*
G02I-800J0D01*
G37*
G36*
G01X700209Y1236023D02*
G02I-800J0D01*
G37*
G36*
G01X692729Y1232283D02*
G02I-800J0D01*
G37*
G36*
G01X696469Y1228543D02*
G02I-800J0D01*
G37*
G36*
G01Y1224803D02*
G02I-800J0D01*
G37*
G36*
G01X692729Y1250984D02*
G02I-800J0D01*
G37*
G36*
G01X688989Y1247243D02*
G02I-800J0D01*
G37*
G36*
G01Y1243503D02*
G02I-800J0D01*
G37*
G36*
G01X696469Y1247243D02*
G02I-800J0D01*
G37*
G36*
G01X700209Y1250984D02*
G02I-800J0D01*
G37*
G36*
G01X696469Y1243503D02*
G02I-800J0D01*
G37*
G36*
G01X700209Y1254724D02*
G02I-800J0D01*
G37*
G36*
G01X692729D02*
G02I-800J0D01*
G37*
G36*
G01X707689Y1075196D02*
G02I-800J0D01*
G37*
G36*
G01X715169D02*
G02I-800J0D01*
G37*
G36*
G01X707689Y1078936D02*
G02I-800J0D01*
G37*
G36*
G01X718909Y1086417D02*
G02I-800J0D01*
G37*
G36*
G01X715169Y1078936D02*
G02I-800J0D01*
G37*
G36*
G01X703948Y1082677D02*
G02I-800J0D01*
G37*
G36*
G01X711429Y1086416D02*
G02I-800J0D01*
G37*
G36*
G01X703948Y1086417D02*
G02I-800J0D01*
G37*
G36*
G01X718909Y1082677D02*
G02I-800J0D01*
G37*
G36*
G01X711429Y1082676D02*
G02I-800J0D01*
G37*
G36*
G01X715169Y1097637D02*
G02I-800J0D01*
G37*
G36*
G01X707689Y1093897D02*
G02I-800J0D01*
G37*
G36*
G01X703949Y1105117D02*
G02I-800J0D01*
G37*
G36*
G01X718910D02*
G02I-800J0D01*
G37*
G36*
G01Y1101376D02*
G02I-800J0D01*
G37*
G36*
G01X711430Y1105117D02*
G02I-800J0D01*
G37*
G36*
G01X715169Y1093897D02*
G02I-800J0D01*
G37*
G36*
G01X707689Y1097637D02*
G02I-800J0D01*
G37*
G36*
G01X703949Y1101376D02*
G02I-800J0D01*
G37*
G36*
G01X711430D02*
G02I-800J0D01*
G37*
G36*
G01X707690Y1236023D02*
G02I-800J0D01*
G37*
G36*
G01X718910Y1228543D02*
G02I-800J0D01*
G37*
G36*
G01X715170Y1236023D02*
G02I-800J0D01*
G37*
G36*
G01X711430Y1228543D02*
G02I-800J0D01*
G37*
G36*
G01X703949D02*
G02I-800J0D01*
G37*
G36*
G01X715170Y1232283D02*
G02I-800J0D01*
G37*
G36*
G01X703949Y1224803D02*
G02I-800J0D01*
G37*
G36*
G01X718910D02*
G02I-800J0D01*
G37*
G36*
G01X711430D02*
G02I-800J0D01*
G37*
G36*
G01X707690Y1232283D02*
G02I-800J0D01*
G37*
G36*
G01X718910Y1243503D02*
G02I-800J0D01*
G37*
G36*
G01Y1247243D02*
G02I-800J0D01*
G37*
G36*
G01X707690Y1250984D02*
G02I-800J0D01*
G37*
G36*
G01X703949Y1243503D02*
G02I-800J0D01*
G37*
G36*
G01X715170Y1250984D02*
G02I-800J0D01*
G37*
G36*
G01X711430Y1247243D02*
G02I-800J0D01*
G37*
G36*
G01Y1243503D02*
G02I-800J0D01*
G37*
G36*
G01X703949Y1247243D02*
G02I-800J0D01*
G37*
G36*
G01X715170Y1254724D02*
G02I-800J0D01*
G37*
G36*
G01X707690D02*
G02I-800J0D01*
G37*
G36*
G01X722649Y1075196D02*
G02I-800J0D01*
G37*
G36*
G01X730130D02*
G02I-800J0D01*
G37*
G36*
G01X726389Y1086416D02*
G02I-800J0D01*
G37*
G36*
G01X733869Y1086417D02*
G02I-800J0D01*
G37*
G36*
G01X722649Y1078936D02*
G02I-800J0D01*
G37*
G36*
G01X730130D02*
G02I-800J0D01*
G37*
G36*
G01X733869Y1082677D02*
G02I-800J0D01*
G37*
G36*
G01X726389Y1082676D02*
G02I-800J0D01*
G37*
G36*
G01X726390Y1101376D02*
G02I-800J0D01*
G37*
G36*
G01X733871Y1105117D02*
G02I-800J0D01*
G37*
G36*
G01X726390D02*
G02I-800J0D01*
G37*
G36*
G01X722649Y1097637D02*
G02I-800J0D01*
G37*
G36*
G01Y1093897D02*
G02I-800J0D01*
G37*
G36*
G01X730130Y1097637D02*
G02I-800J0D01*
G37*
G36*
G01X733871Y1101376D02*
G02I-800J0D01*
G37*
G36*
G01X730130Y1093897D02*
G02I-800J0D01*
G37*
G36*
G01X726390Y1228543D02*
G02I-800J0D01*
G37*
G36*
G01X733871D02*
G02I-800J0D01*
G37*
G36*
G01X722650Y1236023D02*
G02I-800J0D01*
G37*
G36*
G01X733871Y1224803D02*
G02I-800J0D01*
G37*
G36*
G01X722650Y1232283D02*
G02I-800J0D01*
G37*
G36*
G01X726390Y1224803D02*
G02I-800J0D01*
G37*
G36*
G01X730131Y1236023D02*
G02I-800J0D01*
G37*
G36*
G01Y1232283D02*
G02I-800J0D01*
G37*
G36*
G01Y1250984D02*
G02I-800J0D01*
G37*
G36*
G01X733871Y1247243D02*
G02I-800J0D01*
G37*
G36*
G01X722650Y1250984D02*
G02I-800J0D01*
G37*
G36*
G01X726390Y1243503D02*
G02I-800J0D01*
G37*
G36*
G01X733871D02*
G02I-800J0D01*
G37*
G36*
G01X726390Y1247243D02*
G02I-800J0D01*
G37*
G36*
G01X722650Y1254724D02*
G02I-800J0D01*
G37*
G36*
G01X730131D02*
G02I-800J0D01*
G37*
G36*
G01X737610Y1075196D02*
G02I-800J0D01*
G37*
G36*
G01X745090D02*
G02I-800J0D01*
G37*
G36*
G01Y1078936D02*
G02I-800J0D01*
G37*
G36*
G01X748830Y1086417D02*
G02I-800J0D01*
G37*
G36*
G01X741350Y1086416D02*
G02I-800J0D01*
G37*
G36*
G01Y1082676D02*
G02I-800J0D01*
G37*
G36*
G01X737610Y1078936D02*
G02I-800J0D01*
G37*
G36*
G01X748830Y1082677D02*
G02I-800J0D01*
G37*
G36*
G01X737610Y1097637D02*
G02I-800J0D01*
G37*
G36*
G01X748831Y1105117D02*
G02I-800J0D01*
G37*
G36*
G01X745090Y1093897D02*
G02I-800J0D01*
G37*
G36*
G01X741351Y1105117D02*
G02I-800J0D01*
G37*
G36*
G01X745090Y1097637D02*
G02I-800J0D01*
G37*
G36*
G01X737610Y1093897D02*
G02I-800J0D01*
G37*
G36*
G01X741351Y1101376D02*
G02I-800J0D01*
G37*
G36*
G01X748831D02*
G02I-800J0D01*
G37*
G36*
G01X745091Y1236023D02*
G02I-800J0D01*
G37*
G36*
G01X737611Y1232283D02*
G02I-800J0D01*
G37*
G36*
G01X745091D02*
G02I-800J0D01*
G37*
G36*
G01X737611Y1236023D02*
G02I-800J0D01*
G37*
G36*
G01X741351Y1224803D02*
G02I-800J0D01*
G37*
G36*
G01Y1228543D02*
G02I-800J0D01*
G37*
G36*
G01X748831Y1224803D02*
G02I-800J0D01*
G37*
G36*
G01Y1228543D02*
G02I-800J0D01*
G37*
G36*
G01X741351Y1243503D02*
G02I-800J0D01*
G37*
G36*
G01Y1247243D02*
G02I-800J0D01*
G37*
G36*
G01X745091Y1250984D02*
G02I-800J0D01*
G37*
G36*
G01X737611D02*
G02I-800J0D01*
G37*
G36*
G01X748831Y1247243D02*
G02I-800J0D01*
G37*
G36*
G01Y1243503D02*
G02I-800J0D01*
G37*
G36*
G01X745091Y1254724D02*
G02I-800J0D01*
G37*
G36*
G01X737611D02*
G02I-800J0D01*
G37*
G36*
G01X752571Y1075196D02*
G02I-800J0D01*
G37*
G36*
G01X767531D02*
G02I-800J0D01*
G37*
G36*
G01X760051D02*
G02I-800J0D01*
G37*
G36*
G01X763791Y1086417D02*
G02I-800J0D01*
G37*
G36*
G01X767531Y1078936D02*
G02I-800J0D01*
G37*
G36*
G01X756311Y1086416D02*
G02I-800J0D01*
G37*
G36*
G01X760051Y1078936D02*
G02I-800J0D01*
G37*
G36*
G01X756311Y1082676D02*
G02I-800J0D01*
G37*
G36*
G01X763791Y1082677D02*
G02I-800J0D01*
G37*
G36*
G01X752571Y1078936D02*
G02I-800J0D01*
G37*
G36*
G01Y1097637D02*
G02I-800J0D01*
G37*
G36*
G01X763792Y1101376D02*
G02I-800J0D01*
G37*
G36*
G01Y1105117D02*
G02I-800J0D01*
G37*
G36*
G01X756312D02*
G02I-800J0D01*
G37*
G36*
G01X760051Y1097637D02*
G02I-800J0D01*
G37*
G36*
G01Y1093897D02*
G02I-800J0D01*
G37*
G36*
G01X767531Y1097637D02*
G02I-800J0D01*
G37*
G36*
G01X756312Y1101376D02*
G02I-800J0D01*
G37*
G36*
G01X767531Y1093897D02*
G02I-800J0D01*
G37*
G36*
G01X752571D02*
G02I-800J0D01*
G37*
G36*
G01X756312Y1123818D02*
G02I-800J0D01*
G37*
G36*
G01X760052Y1112598D02*
G02I-800J0D01*
G37*
G36*
G01X752571Y1123818D02*
G02I-800J0D01*
G37*
G36*
G01X763792Y1112598D02*
G02I-800J0D01*
G37*
G36*
G01X756312Y1116338D02*
G02I-800J0D01*
G37*
G36*
G01X752571D02*
G02I-800J0D01*
G37*
G36*
G01X760052Y1120078D02*
G02I-800J0D01*
G37*
G36*
G01X763792D02*
G02I-800J0D01*
G37*
G36*
G01X752571Y1131299D02*
G02I-800J0D01*
G37*
G36*
G01X763792Y1135039D02*
G02I-800J0D01*
G37*
G36*
G01X756312Y1131299D02*
G02I-800J0D01*
G37*
G36*
G01X763792Y1127559D02*
G02I-800J0D01*
G37*
G36*
G01X760052Y1135039D02*
G02I-800J0D01*
G37*
G36*
G01Y1127559D02*
G02I-800J0D01*
G37*
G36*
G01X763792Y1202362D02*
G02I-800J0D01*
G37*
G36*
G01X756312Y1198621D02*
G02I-800J0D01*
G37*
G36*
G01X760052Y1202362D02*
G02I-800J0D01*
G37*
G36*
G01X752572Y1198621D02*
G02I-800J0D01*
G37*
G36*
G01X763792Y1217322D02*
G02I-800J0D01*
G37*
G36*
G01X752572Y1213582D02*
G02I-800J0D01*
G37*
G36*
G01X763792Y1209842D02*
G02I-800J0D01*
G37*
G36*
G01X756312Y1213582D02*
G02I-800J0D01*
G37*
G36*
G01X752572Y1206102D02*
G02I-800J0D01*
G37*
G36*
G01X760052Y1217322D02*
G02I-800J0D01*
G37*
G36*
G01Y1209842D02*
G02I-800J0D01*
G37*
G36*
G01X756312Y1206102D02*
G02I-800J0D01*
G37*
G36*
G01Y1228543D02*
G02I-800J0D01*
G37*
G36*
G01X752572Y1236023D02*
G02I-800J0D01*
G37*
G36*
G01X763792Y1228543D02*
G02I-800J0D01*
G37*
G36*
G01X752572Y1232283D02*
G02I-800J0D01*
G37*
G36*
G01X767532D02*
G02I-800J0D01*
G37*
G36*
G01Y1236023D02*
G02I-800J0D01*
G37*
G36*
G01X760052Y1232283D02*
G02I-800J0D01*
G37*
G36*
G01X763792Y1224803D02*
G02I-800J0D01*
G37*
G36*
G01X760052Y1236023D02*
G02I-800J0D01*
G37*
G36*
G01X756312Y1224803D02*
G02I-800J0D01*
G37*
G36*
G01X767532Y1250984D02*
G02I-800J0D01*
G37*
G36*
G01X756312Y1243503D02*
G02I-800J0D01*
G37*
G36*
G01X763792D02*
G02I-800J0D01*
G37*
G36*
G01Y1247243D02*
G02I-800J0D01*
G37*
G36*
G01X752572Y1250984D02*
G02I-800J0D01*
G37*
G36*
G01X760052D02*
G02I-800J0D01*
G37*
G36*
G01X756312Y1247243D02*
G02I-800J0D01*
G37*
G36*
G01X752572Y1254724D02*
G02I-800J0D01*
G37*
G36*
G01X760052D02*
G02I-800J0D01*
G37*
G36*
G01X767532D02*
G02I-800J0D01*
G37*
G36*
G01X775011Y1075196D02*
G02I-800J0D01*
G37*
G36*
G01X782493Y1090157D02*
G02I-800J0D01*
G37*
G36*
G01X778753D02*
G02I-800J0D01*
G37*
G36*
G01X782493Y1082676D02*
G02I-800J0D01*
G37*
G36*
G01X775011Y1078936D02*
G02I-800J0D01*
G37*
G36*
G01X771271Y1086417D02*
G02I-800J0D01*
G37*
G36*
G01Y1082677D02*
G02I-800J0D01*
G37*
G36*
G01X778753Y1082676D02*
G02I-800J0D01*
G37*
G36*
G01X771272Y1101377D02*
G02I-800J0D01*
G37*
G36*
G01X782493D02*
G02I-800J0D01*
G37*
G36*
G01X778753D02*
G02I-800J0D01*
G37*
G36*
G01X775012Y1097637D02*
G02I-800J0D01*
G37*
G36*
G01X771272Y1105117D02*
G02I-800J0D01*
G37*
G36*
G01X775012Y1093897D02*
G02I-800J0D01*
G37*
G36*
G01Y1112598D02*
G02I-800J0D01*
G37*
G36*
G01X771272D02*
G02I-800J0D01*
G37*
G36*
G01X782493Y1123818D02*
G02I-800J0D01*
G37*
G36*
G01X778753D02*
G02I-800J0D01*
G37*
G36*
G01X782493Y1116338D02*
G02I-800J0D01*
G37*
G36*
G01X778753Y1108858D02*
G02I-800J0D01*
G37*
G36*
G01X771272Y1120078D02*
G02I-800J0D01*
G37*
G36*
G01X782493Y1108858D02*
G02I-800J0D01*
G37*
G36*
G01X778753Y1116338D02*
G02I-800J0D01*
G37*
G36*
G01X775012Y1120078D02*
G02I-800J0D01*
G37*
G36*
G01X771272Y1127558D02*
G02I-800J0D01*
G37*
G36*
G01Y1135039D02*
G02I-800J0D01*
G37*
G36*
G01X782493Y1131299D02*
G02I-800J0D01*
G37*
G36*
G01X775012Y1127558D02*
G02I-800J0D01*
G37*
G36*
G01Y1135039D02*
G02I-800J0D01*
G37*
G36*
G01X778753Y1131299D02*
G02I-800J0D01*
G37*
G36*
G01X782493Y1198621D02*
G02I-800J0D01*
G37*
G36*
G01X775012Y1202362D02*
G02I-800J0D01*
G37*
G36*
G01X771272D02*
G02I-800J0D01*
G37*
G36*
G01X778753Y1198621D02*
G02I-800J0D01*
G37*
G36*
G01Y1206102D02*
G02I-800J0D01*
G37*
G36*
G01X771272Y1209842D02*
G02I-800J0D01*
G37*
G36*
G01X782493Y1213582D02*
G02I-800J0D01*
G37*
G36*
G01X775012Y1209842D02*
G02I-800J0D01*
G37*
G36*
G01X778753Y1221062D02*
G02I-800J0D01*
G37*
G36*
G01X782493D02*
G02I-800J0D01*
G37*
G36*
G01Y1206102D02*
G02I-800J0D01*
G37*
G36*
G01X771272Y1217322D02*
G02I-800J0D01*
G37*
G36*
G01X775012D02*
G02I-800J0D01*
G37*
G36*
G01X778753Y1213582D02*
G02I-800J0D01*
G37*
G36*
G01X771272Y1228543D02*
G02I-800J0D01*
G37*
G36*
G01X782493D02*
G02I-800J0D01*
G37*
G36*
G01X771272Y1224803D02*
G02I-800J0D01*
G37*
G36*
G01X778753Y1228543D02*
G02I-800J0D01*
G37*
G36*
G01X775012Y1232283D02*
G02I-800J0D01*
G37*
G36*
G01Y1236023D02*
G02I-800J0D01*
G37*
G36*
G01X778753Y1239763D02*
G02I-800J0D01*
G37*
G36*
G01X782493D02*
G02I-800J0D01*
G37*
G36*
G01X778753Y1247243D02*
G02I-800J0D01*
G37*
G36*
G01X771272Y1243503D02*
G02I-800J0D01*
G37*
G36*
G01X782493Y1247243D02*
G02I-800J0D01*
G37*
G36*
G01X771272D02*
G02I-800J0D01*
G37*
G36*
G01X775012Y1250984D02*
G02I-800J0D01*
G37*
G36*
G01Y1254724D02*
G02I-800J0D01*
G37*
G36*
G01X940026Y1577634D02*
G03X940910Y1577268I884J885D01*
G01X956342D01*
G02X956484Y1577209I0J-200D01*
G01X959830Y1573863D01*
G02X959889Y1573721I-141J-142D01*
G01Y1543680D01*
G03X960255Y1542796I1251J0D01*
G01X964295Y1538756D01*
G03X965179Y1538390I884J885D01*
G01X1019906D01*
G02X1020048Y1538331I0J-200D01*
G01X1031515Y1526864D01*
G02X1031574Y1526722I-141J-142D01*
G01Y1492904D01*
G02X1031515Y1492762I-200J0D01*
G01X1031368Y1492615D01*
G02X1031226Y1492556I-142J141D01*
G01X947183D01*
G02X947041Y1492615I0J200D01*
G01X944876Y1494780D01*
G03X943992Y1495146I-884J-885D01*
G01X933579D01*
G03X932695Y1494780I0J-1251D01*
G01X917141Y1479226D01*
G03X916775Y1478342I885J-884D01*
G01Y1465020D01*
G02X916716Y1464878I-200J0D01*
G01X914188Y1462350D01*
G03X913822Y1461466I885J-884D01*
G01Y1460928D01*
G02X913763Y1460786I-200J0D01*
G01X913527Y1460550D01*
G03X913161Y1459666I885J-884D01*
G01Y1446448D01*
G02X913102Y1446306I-200J0D01*
G01X912955Y1446159D01*
G02X912813Y1446100I-142J141D01*
G01X900559D01*
G02X900417Y1446159I0J200D01*
G01X900270Y1446306D01*
G02X900211Y1446448I141J142D01*
G01Y1459640D01*
G03X899845Y1460524I-1251J0D01*
G01X899532Y1460837D01*
G02X899473Y1460979I141J142D01*
G01Y1462024D01*
G03X899107Y1462908I-1251J0D01*
G01X894403Y1467612D01*
G02X894344Y1467754I141J142D01*
G01Y1473096D01*
G03X893978Y1473980I-1251J0D01*
G01X888953Y1479005D01*
G03X888069Y1479371I-884J-885D01*
G01X880504D01*
G03X879620Y1479005I0J-1251D01*
G01X872265Y1471650D01*
G03X871899Y1470766I885J-884D01*
G01Y1460991D01*
G02X871840Y1460849I-200J0D01*
G01X871502Y1460511D01*
G03X871136Y1459627I885J-884D01*
G01Y1446423D01*
G02X871077Y1446281I-200J0D01*
G01X870968Y1446172D01*
G02X870826Y1446113I-142J141D01*
G01X858702D01*
G02X858560Y1446172I0J200D01*
G01X858139Y1446593D01*
G02X858080Y1446735I141J142D01*
G01Y1459524D01*
G03X857714Y1460408I-1251J0D01*
G01X853660Y1464462D01*
G03X852776Y1464828I-884J-885D01*
G01X828441D01*
G03X827557Y1464462I0J-1251D01*
G01X827039Y1463944D01*
G03X826673Y1463060I885J-884D01*
G01Y1461847D01*
G02X826614Y1461705I-200J0D01*
G01X826571Y1461662D01*
G02X826429Y1461603I-142J141D01*
G01X825036D01*
G03X824152Y1461237I0J-1251D01*
G01X821533Y1458618D01*
G02X821391Y1458559I-142J141D01*
G01X820451D01*
G03X819567Y1458193I0J-1251D01*
G01X819360Y1457986D01*
G03X818994Y1457102I885J-884D01*
G01Y1446462D01*
G02X818935Y1446320I-200J0D01*
G01X818826Y1446211D01*
G02X818684Y1446152I-142J141D01*
G01X806393D01*
G02X806251Y1446211I0J200D01*
G01X806063Y1446399D01*
G02X806004Y1446541I141J142D01*
G01Y1459828D01*
G02X806063Y1459970I200J0D01*
G01X806195Y1460102D01*
G03X806561Y1460986I-885J884D01*
G01Y1474310D01*
G02X806615Y1474447I200J0D01*
G03X806950Y1475299I-916J852D01*
G01Y1523715D01*
G02X807009Y1523857I200J0D01*
G01X816830Y1533678D01*
G03X817196Y1534562I-885J884D01*
G01Y1620853D01*
G02X817255Y1620995I200J0D01*
G01X822528Y1626268D01*
G02X822670Y1626327I142J-141D01*
G01X927565D01*
G02X927707Y1626268I0J-200D01*
G01X932114Y1621861D01*
G02X932173Y1621719I-141J-142D01*
G01Y1586005D01*
G03X932539Y1585121I1251J0D01*
G01X940026Y1577634D01*
G37*
G36*
G01X953110Y1480583D02*
G03X953130Y1480563I894J874D01*
G02X953192Y1480419I-138J-145D01*
G01Y1451442D01*
G02X953133Y1451300I-200J0D01*
G01X952668Y1450835D01*
G02X952526Y1450776I-142J141D01*
G01X930592D01*
G02X930450Y1450835I0J200D01*
G01X929621Y1451664D01*
G02X929562Y1451806I141J142D01*
G01Y1480891D01*
G02X929621Y1481033I200J0D01*
G01X930418Y1481830D01*
G02X930560Y1481889I142J-141D01*
G01X951737D01*
G02X951894Y1481812I-1J-200D01*
G03X951995Y1481698I984J770D01*
G01X953110Y1480583D01*
G37*
G36*
G01X955751Y1485453D02*
X957168Y1486870D01*
G02X957310Y1486929I142J-141D01*
G01X1045732D01*
G02X1045874Y1486870I0J-200D01*
G01X1046659Y1486085D01*
G02X1046718Y1485943I-141J-142D01*
G01Y1452303D01*
G02X1046659Y1452161I-200J0D01*
G01X1045333Y1450835D01*
G02X1045191Y1450776I-142J141D01*
G01X956304D01*
G02X956162Y1450835I0J200D01*
G01X955751Y1451246D01*
G02X955692Y1451388I141J142D01*
G01Y1485311D01*
G02X955751Y1485453I200J0D01*
G37*
G36*
G01X1060051Y1198621D02*
G02I-800J0D01*
G37*
G36*
G01Y1191141D02*
G02I-800J0D01*
G37*
G36*
G01Y1221062D02*
G02I-800J0D01*
G37*
G36*
G01Y1206102D02*
G02I-800J0D01*
G37*
G36*
G01Y1213582D02*
G02I-800J0D01*
G37*
G36*
G01Y1228543D02*
G02I-800J0D01*
G37*
G36*
G01Y1247243D02*
G02I-800J0D01*
G37*
G36*
G01Y1239763D02*
G02I-800J0D01*
G37*
G36*
G01X1071272Y1187401D02*
G02I-800J0D01*
G37*
G36*
G01X1067532D02*
G02I-800J0D01*
G37*
G36*
G01X1063791Y1198621D02*
G02I-800J0D01*
G37*
G36*
G01X1067532Y1194881D02*
G02I-800J0D01*
G37*
G36*
G01X1063791Y1191141D02*
G02I-800J0D01*
G37*
G36*
G01X1071272Y1194881D02*
G02I-800J0D01*
G37*
G36*
G01Y1202362D02*
G02I-800J0D01*
G37*
G36*
G01X1067532D02*
G02I-800J0D01*
G37*
G36*
G01X1071272Y1217322D02*
G02I-800J0D01*
G37*
G36*
G01X1067532D02*
G02I-800J0D01*
G37*
G36*
G01X1063791Y1221062D02*
G02I-800J0D01*
G37*
G36*
G01Y1206102D02*
G02I-800J0D01*
G37*
G36*
G01X1071272Y1209842D02*
G02I-800J0D01*
G37*
G36*
G01X1063791Y1213582D02*
G02I-800J0D01*
G37*
G36*
G01X1067532Y1209842D02*
G02I-800J0D01*
G37*
G36*
G01X1071272Y1228543D02*
G02I-800J0D01*
G37*
G36*
G01X1067532Y1236023D02*
G02I-800J0D01*
G37*
G36*
G01Y1232283D02*
G02I-800J0D01*
G37*
G36*
G01X1075012Y1236023D02*
G02I-800J0D01*
G37*
G36*
G01Y1232283D02*
G02I-800J0D01*
G37*
G36*
G01X1071272Y1224803D02*
G02I-800J0D01*
G37*
G36*
G01X1063791Y1228543D02*
G02I-800J0D01*
G37*
G36*
G01X1075012Y1250984D02*
G02I-800J0D01*
G37*
G36*
G01X1071272Y1247243D02*
G02I-800J0D01*
G37*
G36*
G01X1063791D02*
G02I-800J0D01*
G37*
G36*
G01X1071272Y1243503D02*
G02I-800J0D01*
G37*
G36*
G01X1063791Y1239763D02*
G02I-800J0D01*
G37*
G36*
G01X1067532Y1250984D02*
G02I-800J0D01*
G37*
G36*
G01Y1254724D02*
G02I-800J0D01*
G37*
G36*
G01X1075012D02*
G02I-800J0D01*
G37*
G36*
G01X1089972Y1075196D02*
G02I-800J0D01*
G37*
G36*
G01Y1078936D02*
G02I-800J0D01*
G37*
G36*
G01Y1097637D02*
G02I-800J0D01*
G37*
G36*
G01Y1093897D02*
G02I-800J0D01*
G37*
G36*
G01X1078752Y1187401D02*
G02I-800J0D01*
G37*
G36*
G01X1082492D02*
G02I-800J0D01*
G37*
G36*
G01X1078752Y1194881D02*
G02I-800J0D01*
G37*
G36*
G01Y1202362D02*
G02I-800J0D01*
G37*
G36*
G01X1089972Y1191141D02*
G02I-800J0D01*
G37*
G36*
G01Y1198621D02*
G02I-800J0D01*
G37*
G36*
G01X1082492Y1202362D02*
G02I-800J0D01*
G37*
G36*
G01X1086232Y1198621D02*
G02I-800J0D01*
G37*
G36*
G01X1082492Y1194881D02*
G02I-800J0D01*
G37*
G36*
G01X1086232Y1191141D02*
G02I-800J0D01*
G37*
G36*
G01X1089972Y1206102D02*
G02I-800J0D01*
G37*
G36*
G01X1078752Y1209842D02*
G02I-800J0D01*
G37*
G36*
G01X1082492D02*
G02I-800J0D01*
G37*
G36*
G01Y1217322D02*
G02I-800J0D01*
G37*
G36*
G01X1089972Y1213582D02*
G02I-800J0D01*
G37*
G36*
G01X1078752Y1217322D02*
G02I-800J0D01*
G37*
G36*
G01X1086232Y1206102D02*
G02I-800J0D01*
G37*
G36*
G01Y1213582D02*
G02I-800J0D01*
G37*
G36*
G01X1089972Y1232283D02*
G02I-800J0D01*
G37*
G36*
G01X1082492D02*
G02I-800J0D01*
G37*
G36*
G01Y1236023D02*
G02I-800J0D01*
G37*
G36*
G01X1089972D02*
G02I-800J0D01*
G37*
G36*
G01X1078752Y1224803D02*
G02I-800J0D01*
G37*
G36*
G01Y1228543D02*
G02I-800J0D01*
G37*
G36*
G01X1086232Y1224803D02*
G02I-800J0D01*
G37*
G36*
G01Y1228543D02*
G02I-800J0D01*
G37*
G36*
G01X1078752Y1243503D02*
G02I-800J0D01*
G37*
G36*
G01X1082492Y1250984D02*
G02I-800J0D01*
G37*
G36*
G01X1078752Y1247243D02*
G02I-800J0D01*
G37*
G36*
G01X1086232Y1243503D02*
G02I-800J0D01*
G37*
G36*
G01X1089972Y1250984D02*
G02I-800J0D01*
G37*
G36*
G01X1086232Y1247243D02*
G02I-800J0D01*
G37*
G36*
G01X1082492Y1254724D02*
G02I-800J0D01*
G37*
G36*
G01X1089972D02*
G02I-800J0D01*
G37*
G36*
G01X1097453Y1075196D02*
G02I-800J0D01*
G37*
G36*
G01X1104933D02*
G02I-800J0D01*
G37*
G36*
G01X1101193Y1082677D02*
G02I-800J0D01*
G37*
G36*
G01X1104933Y1078936D02*
G02I-800J0D01*
G37*
G36*
G01X1108673Y1082677D02*
G02I-800J0D01*
G37*
G36*
G01Y1086417D02*
G02I-800J0D01*
G37*
G36*
G01X1093713Y1082677D02*
G02I-800J0D01*
G37*
G36*
G01X1101193Y1086417D02*
G02I-800J0D01*
G37*
G36*
G01X1093713D02*
G02I-800J0D01*
G37*
G36*
G01X1097453Y1078936D02*
G02I-800J0D01*
G37*
G36*
G01X1093713Y1105116D02*
G02I-800J0D01*
G37*
G36*
G01X1104933Y1097637D02*
G02I-800J0D01*
G37*
G36*
G01X1097453D02*
G02I-800J0D01*
G37*
G36*
G01X1101193Y1105116D02*
G02I-800J0D01*
G37*
G36*
G01X1104933Y1093897D02*
G02I-800J0D01*
G37*
G36*
G01X1101193Y1101376D02*
G02I-800J0D01*
G37*
G36*
G01X1097453Y1093897D02*
G02I-800J0D01*
G37*
G36*
G01X1093713Y1101376D02*
G02I-800J0D01*
G37*
G36*
G01X1108673Y1105116D02*
G02I-800J0D01*
G37*
G36*
G01Y1101376D02*
G02I-800J0D01*
G37*
G36*
G01X1101193Y1228543D02*
G02I-800J0D01*
G37*
G36*
G01X1104933Y1236023D02*
G02I-800J0D01*
G37*
G36*
G01X1093713Y1224803D02*
G02I-800J0D01*
G37*
G36*
G01X1104933Y1232283D02*
G02I-800J0D01*
G37*
G36*
G01X1108673Y1224803D02*
G02I-800J0D01*
G37*
G36*
G01X1097453Y1236023D02*
G02I-800J0D01*
G37*
G36*
G01X1101193Y1224803D02*
G02I-800J0D01*
G37*
G36*
G01X1108673Y1228543D02*
G02I-800J0D01*
G37*
G36*
G01X1097453Y1232283D02*
G02I-800J0D01*
G37*
G36*
G01X1093713Y1228543D02*
G02I-800J0D01*
G37*
G36*
G01Y1247243D02*
G02I-800J0D01*
G37*
G36*
G01X1097453Y1250984D02*
G02I-800J0D01*
G37*
G36*
G01X1093713Y1243503D02*
G02I-800J0D01*
G37*
G36*
G01X1108673D02*
G02I-800J0D01*
G37*
G36*
G01X1101193D02*
G02I-800J0D01*
G37*
G36*
G01X1108673Y1247243D02*
G02I-800J0D01*
G37*
G36*
G01X1101193D02*
G02I-800J0D01*
G37*
G36*
G01X1104933Y1250984D02*
G02I-800J0D01*
G37*
G36*
G01X1097453Y1254724D02*
G02I-800J0D01*
G37*
G36*
G01X1104933D02*
G02I-800J0D01*
G37*
G36*
G01X1112413Y1075196D02*
G02I-800J0D01*
G37*
G36*
G01X1119894D02*
G02I-800J0D01*
G37*
G36*
G01X1123634Y1086417D02*
G02I-800J0D01*
G37*
G36*
G01X1119894Y1078936D02*
G02I-800J0D01*
G37*
G36*
G01X1116154Y1082677D02*
G02I-800J0D01*
G37*
G36*
G01X1112413Y1078936D02*
G02I-800J0D01*
G37*
G36*
G01X1116154Y1086417D02*
G02I-800J0D01*
G37*
G36*
G01X1123634Y1082677D02*
G02I-800J0D01*
G37*
G36*
G01X1119894Y1097637D02*
G02I-800J0D01*
G37*
G36*
G01X1116154Y1101376D02*
G02I-800J0D01*
G37*
G36*
G01X1112413Y1093897D02*
G02I-800J0D01*
G37*
G36*
G01Y1097637D02*
G02I-800J0D01*
G37*
G36*
G01X1123634Y1105116D02*
G02I-800J0D01*
G37*
G36*
G01X1119894Y1093897D02*
G02I-800J0D01*
G37*
G36*
G01X1123634Y1101376D02*
G02I-800J0D01*
G37*
G36*
G01X1116154Y1105116D02*
G02I-800J0D01*
G37*
G36*
G01X1123634Y1224803D02*
G02I-800J0D01*
G37*
G36*
G01X1119894Y1232283D02*
G02I-800J0D01*
G37*
G36*
G01X1116154Y1228543D02*
G02I-800J0D01*
G37*
G36*
G01X1112413Y1232283D02*
G02I-800J0D01*
G37*
G36*
G01X1119894Y1236023D02*
G02I-800J0D01*
G37*
G36*
G01X1116154Y1224803D02*
G02I-800J0D01*
G37*
G36*
G01X1112413Y1236023D02*
G02I-800J0D01*
G37*
G36*
G01X1123634Y1228543D02*
G02I-800J0D01*
G37*
G36*
G01Y1243503D02*
G02I-800J0D01*
G37*
G36*
G01X1119894Y1250984D02*
G02I-800J0D01*
G37*
G36*
G01X1123634Y1247243D02*
G02I-800J0D01*
G37*
G36*
G01X1116154Y1243503D02*
G02I-800J0D01*
G37*
G36*
G01Y1247243D02*
G02I-800J0D01*
G37*
G36*
G01X1112413Y1250984D02*
G02I-800J0D01*
G37*
G36*
G01Y1254724D02*
G02I-800J0D01*
G37*
G36*
G01X1119894D02*
G02I-800J0D01*
G37*
G36*
G01X1127374Y1075196D02*
G02I-800J0D01*
G37*
G36*
G01X1134854D02*
G02I-800J0D01*
G37*
G36*
G01Y1078936D02*
G02I-800J0D01*
G37*
G36*
G01X1127374D02*
G02I-800J0D01*
G37*
G36*
G01X1131114Y1086417D02*
G02I-800J0D01*
G37*
G36*
G01Y1082677D02*
G02I-800J0D01*
G37*
G36*
G01X1138595Y1086417D02*
G02I-800J0D01*
G37*
G36*
G01Y1082677D02*
G02I-800J0D01*
G37*
G36*
G01X1127374Y1093897D02*
G02I-800J0D01*
G37*
G36*
G01X1131114Y1105116D02*
G02I-800J0D01*
G37*
G36*
G01X1134854Y1093897D02*
G02I-800J0D01*
G37*
G36*
G01X1131114Y1101376D02*
G02I-800J0D01*
G37*
G36*
G01X1134854Y1097637D02*
G02I-800J0D01*
G37*
G36*
G01X1138594Y1105116D02*
G02I-800J0D01*
G37*
G36*
G01X1127374Y1097637D02*
G02I-800J0D01*
G37*
G36*
G01X1138594Y1101376D02*
G02I-800J0D01*
G37*
G36*
G01X1134854Y1236023D02*
G02I-800J0D01*
G37*
G36*
G01X1138595Y1228543D02*
G02I-800J0D01*
G37*
G36*
G01X1134854Y1232283D02*
G02I-800J0D01*
G37*
G36*
G01X1127374D02*
G02I-800J0D01*
G37*
G36*
G01Y1236023D02*
G02I-800J0D01*
G37*
G36*
G01X1138595Y1224803D02*
G02I-800J0D01*
G37*
G36*
G01X1131114Y1228543D02*
G02I-800J0D01*
G37*
G36*
G01Y1224803D02*
G02I-800J0D01*
G37*
G36*
G01X1138595Y1243503D02*
G02I-800J0D01*
G37*
G36*
G01X1131114Y1247243D02*
G02I-800J0D01*
G37*
G36*
G01X1127374Y1250984D02*
G02I-800J0D01*
G37*
G36*
G01X1138595Y1247243D02*
G02I-800J0D01*
G37*
G36*
G01X1131114Y1243503D02*
G02I-800J0D01*
G37*
G36*
G01X1134854Y1250984D02*
G02I-800J0D01*
G37*
G36*
G01X1127374Y1254724D02*
G02I-800J0D01*
G37*
G36*
G01X1134854D02*
G02I-800J0D01*
G37*
G36*
G01X1142335Y1075196D02*
G02I-800J0D01*
G37*
G36*
G01X1157294D02*
G02I-800J0D01*
G37*
G36*
G01X1149814Y1075195D02*
G02I-800J0D01*
G37*
G36*
G01X1146075Y1086417D02*
G02I-800J0D01*
G37*
G36*
G01Y1082677D02*
G02I-800J0D01*
G37*
G36*
G01X1142335Y1078936D02*
G02I-800J0D01*
G37*
G36*
G01X1149814Y1078935D02*
G02I-800J0D01*
G37*
G36*
G01X1157294Y1078936D02*
G02I-800J0D01*
G37*
G36*
G01X1153554Y1086416D02*
G02I-800J0D01*
G37*
G36*
G01Y1082676D02*
G02I-800J0D01*
G37*
G36*
G01X1146075Y1105116D02*
G02I-800J0D01*
G37*
G36*
G01X1142335Y1093897D02*
G02I-800J0D01*
G37*
G36*
G01X1146075Y1101376D02*
G02I-800J0D01*
G37*
G36*
G01X1142335Y1097637D02*
G02I-800J0D01*
G37*
G36*
G01X1149814D02*
G02I-800J0D01*
G37*
G36*
G01X1157294Y1093897D02*
G02I-800J0D01*
G37*
G36*
G01X1153555Y1101376D02*
G02I-800J0D01*
G37*
G36*
G01X1157294Y1097637D02*
G02I-800J0D01*
G37*
G36*
G01X1149814Y1093897D02*
G02I-800J0D01*
G37*
G36*
G01X1153555Y1105116D02*
G02I-800J0D01*
G37*
G36*
G01X1149815Y1236023D02*
G02I-800J0D01*
G37*
G36*
G01Y1232283D02*
G02I-800J0D01*
G37*
G36*
G01X1153555Y1228543D02*
G02I-800J0D01*
G37*
G36*
G01X1146075Y1224803D02*
G02I-800J0D01*
G37*
G36*
G01X1157295Y1232283D02*
G02I-800J0D01*
G37*
G36*
G01Y1236023D02*
G02I-800J0D01*
G37*
G36*
G01X1142335D02*
G02I-800J0D01*
G37*
G36*
G01X1146075Y1228543D02*
G02I-800J0D01*
G37*
G36*
G01X1153555Y1224803D02*
G02I-800J0D01*
G37*
G36*
G01X1142335Y1232283D02*
G02I-800J0D01*
G37*
G36*
G01Y1250984D02*
G02I-800J0D01*
G37*
G36*
G01X1146075Y1247243D02*
G02I-800J0D01*
G37*
G36*
G01X1153555Y1243503D02*
G02I-800J0D01*
G37*
G36*
G01X1146075D02*
G02I-800J0D01*
G37*
G36*
G01X1153555Y1247243D02*
G02I-800J0D01*
G37*
G36*
G01X1149815Y1250984D02*
G02I-800J0D01*
G37*
G36*
G01X1157295D02*
G02I-800J0D01*
G37*
G36*
G01X1142335Y1254724D02*
G02I-800J0D01*
G37*
G36*
G01X1149815D02*
G02I-800J0D01*
G37*
G36*
G01X1157295D02*
G02I-800J0D01*
G37*
G36*
G01X1164775Y1075196D02*
G02I-800J0D01*
G37*
G36*
G01X1172255D02*
G02I-800J0D01*
G37*
G36*
G01X1161034Y1086417D02*
G02I-800J0D01*
G37*
G36*
G01X1168515Y1086416D02*
G02I-800J0D01*
G37*
G36*
G01X1164775Y1078936D02*
G02I-800J0D01*
G37*
G36*
G01X1161034Y1082677D02*
G02I-800J0D01*
G37*
G36*
G01X1172255Y1078936D02*
G02I-800J0D01*
G37*
G36*
G01X1168515Y1082676D02*
G02I-800J0D01*
G37*
G36*
G01X1161035Y1105116D02*
G02I-800J0D01*
G37*
G36*
G01Y1101376D02*
G02I-800J0D01*
G37*
G36*
G01X1172255Y1093897D02*
G02I-800J0D01*
G37*
G36*
G01X1168516Y1105116D02*
G02I-800J0D01*
G37*
G36*
G01X1172255Y1097637D02*
G02I-800J0D01*
G37*
G36*
G01X1164775Y1093897D02*
G02I-800J0D01*
G37*
G36*
G01Y1097637D02*
G02I-800J0D01*
G37*
G36*
G01X1168516Y1101376D02*
G02I-800J0D01*
G37*
G36*
G01X1161035Y1224803D02*
G02I-800J0D01*
G37*
G36*
G01X1164776Y1232283D02*
G02I-800J0D01*
G37*
G36*
G01X1168516Y1224803D02*
G02I-800J0D01*
G37*
G36*
G01X1161035Y1228543D02*
G02I-800J0D01*
G37*
G36*
G01X1172256Y1232283D02*
G02I-800J0D01*
G37*
G36*
G01X1164776Y1236023D02*
G02I-800J0D01*
G37*
G36*
G01X1172256D02*
G02I-800J0D01*
G37*
G36*
G01X1168516Y1228543D02*
G02I-800J0D01*
G37*
G36*
G01X1172256Y1250984D02*
G02I-800J0D01*
G37*
G36*
G01X1168516Y1247243D02*
G02I-800J0D01*
G37*
G36*
G01X1164776Y1250984D02*
G02I-800J0D01*
G37*
G36*
G01X1161035Y1247243D02*
G02I-800J0D01*
G37*
G36*
G01Y1243503D02*
G02I-800J0D01*
G37*
G36*
G01X1168516D02*
G02I-800J0D01*
G37*
G36*
G01X1172256Y1254724D02*
G02I-800J0D01*
G37*
G36*
G01X1164776D02*
G02I-800J0D01*
G37*
G36*
G01X1179735Y1075196D02*
G02I-800J0D01*
G37*
G36*
G01X1187216D02*
G02I-800J0D01*
G37*
G36*
G01X1175995Y1086417D02*
G02I-800J0D01*
G37*
G36*
G01X1183475Y1086416D02*
G02I-800J0D01*
G37*
G36*
G01X1175995Y1082677D02*
G02I-800J0D01*
G37*
G36*
G01X1179735Y1078936D02*
G02I-800J0D01*
G37*
G36*
G01X1183475Y1082676D02*
G02I-800J0D01*
G37*
G36*
G01X1187216Y1078936D02*
G02I-800J0D01*
G37*
G36*
G01X1179735Y1097637D02*
G02I-800J0D01*
G37*
G36*
G01X1187216Y1093897D02*
G02I-800J0D01*
G37*
G36*
G01X1183476Y1105116D02*
G02I-800J0D01*
G37*
G36*
G01X1175996D02*
G02I-800J0D01*
G37*
G36*
G01X1179735Y1093897D02*
G02I-800J0D01*
G37*
G36*
G01X1183476Y1101376D02*
G02I-800J0D01*
G37*
G36*
G01X1175996D02*
G02I-800J0D01*
G37*
G36*
G01X1187216Y1097637D02*
G02I-800J0D01*
G37*
G36*
G01X1183476Y1228543D02*
G02I-800J0D01*
G37*
G36*
G01X1187217Y1236023D02*
G02I-800J0D01*
G37*
G36*
G01X1179736D02*
G02I-800J0D01*
G37*
G36*
G01X1187217Y1232283D02*
G02I-800J0D01*
G37*
G36*
G01X1175996Y1228543D02*
G02I-800J0D01*
G37*
G36*
G01X1179736Y1232283D02*
G02I-800J0D01*
G37*
G36*
G01X1183476Y1224803D02*
G02I-800J0D01*
G37*
G36*
G01X1175996D02*
G02I-800J0D01*
G37*
G36*
G01Y1243503D02*
G02I-800J0D01*
G37*
G36*
G01X1183476Y1247243D02*
G02I-800J0D01*
G37*
G36*
G01X1179736Y1250984D02*
G02I-800J0D01*
G37*
G36*
G01X1187217D02*
G02I-800J0D01*
G37*
G36*
G01X1183476Y1243503D02*
G02I-800J0D01*
G37*
G36*
G01X1175996Y1247243D02*
G02I-800J0D01*
G37*
G36*
G01X1179736Y1254724D02*
G02I-800J0D01*
G37*
G36*
G01X1187217D02*
G02I-800J0D01*
G37*
G36*
G01X1194696Y1075196D02*
G02I-800J0D01*
G37*
G36*
G01X1202176D02*
G02I-800J0D01*
G37*
G36*
G01X1190955Y1086417D02*
G02I-800J0D01*
G37*
G36*
G01X1205916Y1082677D02*
G02I-800J0D01*
G37*
G36*
G01X1190955D02*
G02I-800J0D01*
G37*
G36*
G01X1198436Y1082676D02*
G02I-800J0D01*
G37*
G36*
G01X1194696Y1078936D02*
G02I-800J0D01*
G37*
G36*
G01X1205916Y1086417D02*
G02I-800J0D01*
G37*
G36*
G01X1202176Y1078936D02*
G02I-800J0D01*
G37*
G36*
G01X1198436Y1086416D02*
G02I-800J0D01*
G37*
G36*
G01X1202176Y1093897D02*
G02I-800J0D01*
G37*
G36*
G01X1194696Y1097637D02*
G02I-800J0D01*
G37*
G36*
G01X1198437Y1105116D02*
G02I-800J0D01*
G37*
G36*
G01X1205917D02*
G02I-800J0D01*
G37*
G36*
G01X1198437Y1101376D02*
G02I-800J0D01*
G37*
G36*
G01X1205917D02*
G02I-800J0D01*
G37*
G36*
G01X1190957D02*
G02I-800J0D01*
G37*
G36*
G01X1194696Y1093897D02*
G02I-800J0D01*
G37*
G36*
G01X1202176Y1097637D02*
G02I-800J0D01*
G37*
G36*
G01X1190957Y1105116D02*
G02I-800J0D01*
G37*
G36*
G01X1198437Y1224803D02*
G02I-800J0D01*
G37*
G36*
G01X1194697Y1236023D02*
G02I-800J0D01*
G37*
G36*
G01X1190957Y1228543D02*
G02I-800J0D01*
G37*
G36*
G01X1202177Y1236023D02*
G02I-800J0D01*
G37*
G36*
G01X1190957Y1224803D02*
G02I-800J0D01*
G37*
G36*
G01X1194697Y1232283D02*
G02I-800J0D01*
G37*
G36*
G01X1198437Y1228543D02*
G02I-800J0D01*
G37*
G36*
G01X1202177Y1232283D02*
G02I-800J0D01*
G37*
G36*
G01X1205917Y1228543D02*
G02I-800J0D01*
G37*
G36*
G01Y1224803D02*
G02I-800J0D01*
G37*
G36*
G01X1190957Y1243503D02*
G02I-800J0D01*
G37*
G36*
G01X1202177Y1250984D02*
G02I-800J0D01*
G37*
G36*
G01X1198437Y1247243D02*
G02I-800J0D01*
G37*
G36*
G01X1194697Y1250984D02*
G02I-800J0D01*
G37*
G36*
G01X1198437Y1243503D02*
G02I-800J0D01*
G37*
G36*
G01X1190957Y1247243D02*
G02I-800J0D01*
G37*
G36*
G01X1205917Y1243503D02*
G02I-800J0D01*
G37*
G36*
G01Y1247243D02*
G02I-800J0D01*
G37*
G36*
G01X1202177Y1254724D02*
G02I-800J0D01*
G37*
G36*
G01X1194697D02*
G02I-800J0D01*
G37*
G36*
G01X1217137Y1075196D02*
G02I-800J0D01*
G37*
G36*
G01X1209657D02*
G02I-800J0D01*
G37*
G36*
G01X1213397Y1082676D02*
G02I-800J0D01*
G37*
G36*
G01Y1086416D02*
G02I-800J0D01*
G37*
G36*
G01X1220877Y1086417D02*
G02I-800J0D01*
G37*
G36*
G01X1209657Y1078936D02*
G02I-800J0D01*
G37*
G36*
G01X1217137D02*
G02I-800J0D01*
G37*
G36*
G01X1220877Y1082677D02*
G02I-800J0D01*
G37*
G36*
G01X1220878Y1105116D02*
G02I-800J0D01*
G37*
G36*
G01X1217137Y1093897D02*
G02I-800J0D01*
G37*
G36*
G01X1213398Y1101376D02*
G02I-800J0D01*
G37*
G36*
G01Y1105116D02*
G02I-800J0D01*
G37*
G36*
G01X1209657Y1093897D02*
G02I-800J0D01*
G37*
G36*
G01X1217137Y1097637D02*
G02I-800J0D01*
G37*
G36*
G01X1220878Y1101376D02*
G02I-800J0D01*
G37*
G36*
G01X1209657Y1097637D02*
G02I-800J0D01*
G37*
G36*
G01X1213398Y1123818D02*
G02I-800J0D01*
G37*
G36*
G01X1209658Y1116338D02*
G02I-800J0D01*
G37*
G36*
G01X1213398D02*
G02I-800J0D01*
G37*
G36*
G01X1217138Y1120078D02*
G02I-800J0D01*
G37*
G36*
G01Y1112598D02*
G02I-800J0D01*
G37*
G36*
G01X1209658Y1123818D02*
G02I-800J0D01*
G37*
G36*
G01X1220878Y1112598D02*
G02I-800J0D01*
G37*
G36*
G01Y1120078D02*
G02I-800J0D01*
G37*
G36*
G01X1217138Y1127559D02*
G02I-800J0D01*
G37*
G36*
G01Y1135039D02*
G02I-800J0D01*
G37*
G36*
G01X1213398Y1131299D02*
G02I-800J0D01*
G37*
G36*
G01X1209658D02*
G02I-800J0D01*
G37*
G36*
G01X1220878Y1135039D02*
G02I-800J0D01*
G37*
G36*
G01Y1127559D02*
G02I-800J0D01*
G37*
G36*
G01X1213398Y1198621D02*
G02I-800J0D01*
G37*
G36*
G01X1209658D02*
G02I-800J0D01*
G37*
G36*
G01X1217138Y1202362D02*
G02I-800J0D01*
G37*
G36*
G01X1220878D02*
G02I-800J0D01*
G37*
G36*
G01Y1217322D02*
G02I-800J0D01*
G37*
G36*
G01Y1209842D02*
G02I-800J0D01*
G37*
G36*
G01X1213398Y1206102D02*
G02I-800J0D01*
G37*
G36*
G01X1217138Y1217322D02*
G02I-800J0D01*
G37*
G36*
G01X1213398Y1213582D02*
G02I-800J0D01*
G37*
G36*
G01X1209658Y1206102D02*
G02I-800J0D01*
G37*
G36*
G01Y1213582D02*
G02I-800J0D01*
G37*
G36*
G01X1217138Y1209842D02*
G02I-800J0D01*
G37*
G36*
G01X1220878Y1224803D02*
G02I-800J0D01*
G37*
G36*
G01X1213398Y1228543D02*
G02I-800J0D01*
G37*
G36*
G01X1209658Y1232283D02*
G02I-800J0D01*
G37*
G36*
G01X1217138Y1236023D02*
G02I-800J0D01*
G37*
G36*
G01Y1232283D02*
G02I-800J0D01*
G37*
G36*
G01X1213398Y1224803D02*
G02I-800J0D01*
G37*
G36*
G01X1220878Y1228543D02*
G02I-800J0D01*
G37*
G36*
G01X1209658Y1236023D02*
G02I-800J0D01*
G37*
G36*
G01X1213398Y1243503D02*
G02I-800J0D01*
G37*
G36*
G01X1220878Y1247243D02*
G02I-800J0D01*
G37*
G36*
G01Y1243503D02*
G02I-800J0D01*
G37*
G36*
G01X1213398Y1247243D02*
G02I-800J0D01*
G37*
G36*
G01X1209658Y1250984D02*
G02I-800J0D01*
G37*
G36*
G01X1217138D02*
G02I-800J0D01*
G37*
G36*
G01X1209658Y1254724D02*
G02I-800J0D01*
G37*
G36*
G01X1217138D02*
G02I-800J0D01*
G37*
G36*
G01X1232097Y1075196D02*
G02I-800J0D01*
G37*
G36*
G01X1224617D02*
G02I-800J0D01*
G37*
G36*
G01X1235839Y1090157D02*
G02I-800J0D01*
G37*
G36*
G01X1232097Y1078936D02*
G02I-800J0D01*
G37*
G36*
G01X1235839Y1082676D02*
G02I-800J0D01*
G37*
G36*
G01X1228357Y1086417D02*
G02I-800J0D01*
G37*
G36*
G01X1224617Y1078936D02*
G02I-800J0D01*
G37*
G36*
G01X1228357Y1082677D02*
G02I-800J0D01*
G37*
G36*
G01X1228358Y1101377D02*
G02I-800J0D01*
G37*
G36*
G01X1232098Y1093897D02*
G02I-800J0D01*
G37*
G36*
G01X1235839Y1101377D02*
G02I-800J0D01*
G37*
G36*
G01X1228358Y1105117D02*
G02I-800J0D01*
G37*
G36*
G01X1224617Y1093897D02*
G02I-800J0D01*
G37*
G36*
G01Y1097637D02*
G02I-800J0D01*
G37*
G36*
G01X1232098D02*
G02I-800J0D01*
G37*
G36*
G01X1228358Y1112598D02*
G02I-800J0D01*
G37*
G36*
G01X1235839Y1123818D02*
G02I-800J0D01*
G37*
G36*
G01X1232098Y1120078D02*
G02I-800J0D01*
G37*
G36*
G01Y1112598D02*
G02I-800J0D01*
G37*
G36*
G01X1235839Y1108858D02*
G02I-800J0D01*
G37*
G36*
G01Y1116338D02*
G02I-800J0D01*
G37*
G36*
G01X1228358Y1120078D02*
G02I-800J0D01*
G37*
G36*
G01X1232098Y1135039D02*
G02I-800J0D01*
G37*
G36*
G01X1228358Y1127558D02*
G02I-800J0D01*
G37*
G36*
G01X1235839Y1131299D02*
G02I-800J0D01*
G37*
G36*
G01X1232098Y1127558D02*
G02I-800J0D01*
G37*
G36*
G01X1228358Y1135039D02*
G02I-800J0D01*
G37*
G36*
G01X1232098Y1202362D02*
G02I-800J0D01*
G37*
G36*
G01X1235839Y1198621D02*
G02I-800J0D01*
G37*
G36*
G01X1228358Y1202362D02*
G02I-800J0D01*
G37*
G36*
G01X1235839Y1213582D02*
G02I-800J0D01*
G37*
G36*
G01X1232098Y1209842D02*
G02I-800J0D01*
G37*
G36*
G01X1228358D02*
G02I-800J0D01*
G37*
G36*
G01X1235839Y1221062D02*
G02I-800J0D01*
G37*
G36*
G01X1232098Y1217322D02*
G02I-800J0D01*
G37*
G36*
G01X1235839Y1206102D02*
G02I-800J0D01*
G37*
G36*
G01X1228358Y1217322D02*
G02I-800J0D01*
G37*
G36*
G01X1232098Y1232283D02*
G02I-800J0D01*
G37*
G36*
G01X1228358Y1228543D02*
G02I-800J0D01*
G37*
G36*
G01Y1224803D02*
G02I-800J0D01*
G37*
G36*
G01X1224618Y1236023D02*
G02I-800J0D01*
G37*
G36*
G01X1232098D02*
G02I-800J0D01*
G37*
G36*
G01X1235839Y1228543D02*
G02I-800J0D01*
G37*
G36*
G01X1224618Y1232283D02*
G02I-800J0D01*
G37*
G36*
G01X1228358Y1247243D02*
G02I-800J0D01*
G37*
G36*
G01X1224618Y1250984D02*
G02I-800J0D01*
G37*
G36*
G01X1235839Y1239763D02*
G02I-800J0D01*
G37*
G36*
G01X1228358Y1243503D02*
G02I-800J0D01*
G37*
G36*
G01X1232098Y1250984D02*
G02I-800J0D01*
G37*
G36*
G01X1235839Y1247243D02*
G02I-800J0D01*
G37*
G36*
G01X1232098Y1254724D02*
G02I-800J0D01*
G37*
G36*
G01X1224618D02*
G02I-800J0D01*
G37*
G36*
G01X1239579Y1090157D02*
G02I-800J0D01*
G37*
G36*
G01Y1082676D02*
G02I-800J0D01*
G37*
G36*
G01Y1101377D02*
G02I-800J0D01*
G37*
G36*
G01Y1108858D02*
G02I-800J0D01*
G37*
G36*
G01Y1116338D02*
G02I-800J0D01*
G37*
G36*
G01Y1123818D02*
G02I-800J0D01*
G37*
G36*
G01Y1131299D02*
G02I-800J0D01*
G37*
G36*
G01Y1198621D02*
G02I-800J0D01*
G37*
G36*
G01Y1221062D02*
G02I-800J0D01*
G37*
G36*
G01Y1206102D02*
G02I-800J0D01*
G37*
G36*
G01Y1213582D02*
G02I-800J0D01*
G37*
G36*
G01Y1228543D02*
G02I-800J0D01*
G37*
G36*
G01Y1247243D02*
G02I-800J0D01*
G37*
G36*
G01Y1239763D02*
G02I-800J0D01*
G37*
G36*
G01X1524619Y1187401D02*
G02I-800J0D01*
G37*
G36*
G01X1528359D02*
G02I-800J0D01*
G37*
G36*
G01X1517138Y1198621D02*
G02I-800J0D01*
G37*
G36*
G01X1524619Y1194881D02*
G02I-800J0D01*
G37*
G36*
G01X1520878Y1198621D02*
G02I-800J0D01*
G37*
G36*
G01X1524619Y1202362D02*
G02I-800J0D01*
G37*
G36*
G01X1517138Y1191141D02*
G02I-800J0D01*
G37*
G36*
G01X1528359Y1202362D02*
G02I-800J0D01*
G37*
G36*
G01Y1194881D02*
G02I-800J0D01*
G37*
G36*
G01X1520878Y1191141D02*
G02I-800J0D01*
G37*
G36*
G01Y1221062D02*
G02I-800J0D01*
G37*
G36*
G01X1517138Y1213582D02*
G02I-800J0D01*
G37*
G36*
G01Y1206102D02*
G02I-800J0D01*
G37*
G36*
G01X1520878D02*
G02I-800J0D01*
G37*
G36*
G01X1528359Y1217322D02*
G02I-800J0D01*
G37*
G36*
G01X1524619Y1209842D02*
G02I-800J0D01*
G37*
G36*
G01X1517138Y1221062D02*
G02I-800J0D01*
G37*
G36*
G01X1528359Y1209842D02*
G02I-800J0D01*
G37*
G36*
G01X1524619Y1217322D02*
G02I-800J0D01*
G37*
G36*
G01X1520878Y1213582D02*
G02I-800J0D01*
G37*
G36*
G01X1528359Y1228543D02*
G02I-800J0D01*
G37*
G36*
G01X1517138D02*
G02I-800J0D01*
G37*
G36*
G01X1524619Y1232283D02*
G02I-800J0D01*
G37*
G36*
G01X1520878Y1228543D02*
G02I-800J0D01*
G37*
G36*
G01X1524619Y1236023D02*
G02I-800J0D01*
G37*
G36*
G01X1528359Y1224803D02*
G02I-800J0D01*
G37*
G36*
G01X1517138Y1239763D02*
G02I-800J0D01*
G37*
G36*
G01X1520878D02*
G02I-800J0D01*
G37*
G36*
G01Y1247243D02*
G02I-800J0D01*
G37*
G36*
G01X1517138D02*
G02I-800J0D01*
G37*
G36*
G01X1528359Y1243503D02*
G02I-800J0D01*
G37*
G36*
G01Y1247243D02*
G02I-800J0D01*
G37*
G36*
G01X1524619Y1250984D02*
G02I-800J0D01*
G37*
G36*
G01Y1254724D02*
G02I-800J0D01*
G37*
G36*
G01X1547059Y1075196D02*
G02I-800J0D01*
G37*
G36*
G01Y1078936D02*
G02I-800J0D01*
G37*
G36*
G01Y1097637D02*
G02I-800J0D01*
G37*
G36*
G01Y1093897D02*
G02I-800J0D01*
G37*
G36*
G01X1535839Y1187401D02*
G02I-800J0D01*
G37*
G36*
G01X1539579D02*
G02I-800J0D01*
G37*
G36*
G01X1543319Y1191141D02*
G02I-800J0D01*
G37*
G36*
G01X1539579Y1202362D02*
G02I-800J0D01*
G37*
G36*
G01X1535839Y1194881D02*
G02I-800J0D01*
G37*
G36*
G01X1543319Y1198621D02*
G02I-800J0D01*
G37*
G36*
G01X1547059D02*
G02I-800J0D01*
G37*
G36*
G01Y1191141D02*
G02I-800J0D01*
G37*
G36*
G01X1535839Y1202362D02*
G02I-800J0D01*
G37*
G36*
G01X1539579Y1194881D02*
G02I-800J0D01*
G37*
G36*
G01X1543319Y1213582D02*
G02I-800J0D01*
G37*
G36*
G01Y1206102D02*
G02I-800J0D01*
G37*
G36*
G01X1547059Y1213582D02*
G02I-800J0D01*
G37*
G36*
G01X1535839Y1209842D02*
G02I-800J0D01*
G37*
G36*
G01Y1217322D02*
G02I-800J0D01*
G37*
G36*
G01X1547059Y1206102D02*
G02I-800J0D01*
G37*
G36*
G01X1539579Y1209842D02*
G02I-800J0D01*
G37*
G36*
G01Y1217322D02*
G02I-800J0D01*
G37*
G36*
G01X1547059Y1232283D02*
G02I-800J0D01*
G37*
G36*
G01X1535839Y1224803D02*
G02I-800J0D01*
G37*
G36*
G01X1539579Y1236023D02*
G02I-800J0D01*
G37*
G36*
G01X1532099Y1232283D02*
G02I-800J0D01*
G37*
G36*
G01X1543319Y1228543D02*
G02I-800J0D01*
G37*
G36*
G01X1535839D02*
G02I-800J0D01*
G37*
G36*
G01X1547059Y1236023D02*
G02I-800J0D01*
G37*
G36*
G01X1543319Y1224803D02*
G02I-800J0D01*
G37*
G36*
G01X1532099Y1236023D02*
G02I-800J0D01*
G37*
G36*
G01X1539579Y1232283D02*
G02I-800J0D01*
G37*
G36*
G01X1547059Y1250984D02*
G02I-800J0D01*
G37*
G36*
G01X1543319Y1243503D02*
G02I-800J0D01*
G37*
G36*
G01Y1247243D02*
G02I-800J0D01*
G37*
G36*
G01X1539579Y1250984D02*
G02I-800J0D01*
G37*
G36*
G01X1535839Y1243503D02*
G02I-800J0D01*
G37*
G36*
G01X1532099Y1250984D02*
G02I-800J0D01*
G37*
G36*
G01X1535839Y1247243D02*
G02I-800J0D01*
G37*
G36*
G01X1547059Y1254724D02*
G02I-800J0D01*
G37*
G36*
G01X1539579D02*
G02I-800J0D01*
G37*
G36*
G01X1532099D02*
G02I-800J0D01*
G37*
G36*
G01X1554540Y1075196D02*
G02I-800J0D01*
G37*
G36*
G01X1562020D02*
G02I-800J0D01*
G37*
G36*
G01X1558280Y1082677D02*
G02I-800J0D01*
G37*
G36*
G01X1554540Y1078936D02*
G02I-800J0D01*
G37*
G36*
G01X1562020D02*
G02I-800J0D01*
G37*
G36*
G01X1550800Y1086417D02*
G02I-800J0D01*
G37*
G36*
G01Y1082677D02*
G02I-800J0D01*
G37*
G36*
G01X1558280Y1086417D02*
G02I-800J0D01*
G37*
G36*
G01Y1101376D02*
G02I-800J0D01*
G37*
G36*
G01X1562020Y1093897D02*
G02I-800J0D01*
G37*
G36*
G01X1558280Y1105116D02*
G02I-800J0D01*
G37*
G36*
G01X1562020Y1097637D02*
G02I-800J0D01*
G37*
G36*
G01X1550800Y1101376D02*
G02I-800J0D01*
G37*
G36*
G01Y1105116D02*
G02I-800J0D01*
G37*
G36*
G01X1554540Y1093897D02*
G02I-800J0D01*
G37*
G36*
G01Y1097637D02*
G02I-800J0D01*
G37*
G36*
G01Y1232283D02*
G02I-800J0D01*
G37*
G36*
G01X1550800Y1228543D02*
G02I-800J0D01*
G37*
G36*
G01X1554540Y1236023D02*
G02I-800J0D01*
G37*
G36*
G01X1550800Y1224803D02*
G02I-800J0D01*
G37*
G36*
G01X1558280Y1228543D02*
G02I-800J0D01*
G37*
G36*
G01X1562020Y1236023D02*
G02I-800J0D01*
G37*
G36*
G01Y1232283D02*
G02I-800J0D01*
G37*
G36*
G01X1558280Y1224803D02*
G02I-800J0D01*
G37*
G36*
G01X1562020Y1250984D02*
G02I-800J0D01*
G37*
G36*
G01X1550800Y1243503D02*
G02I-800J0D01*
G37*
G36*
G01X1558280Y1247243D02*
G02I-800J0D01*
G37*
G36*
G01X1550800D02*
G02I-800J0D01*
G37*
G36*
G01X1558280Y1243503D02*
G02I-800J0D01*
G37*
G36*
G01X1554540Y1250984D02*
G02I-800J0D01*
G37*
G36*
G01X1562020Y1254724D02*
G02I-800J0D01*
G37*
G36*
G01X1554540D02*
G02I-800J0D01*
G37*
G36*
G01X1576981Y1075196D02*
G02I-800J0D01*
G37*
G36*
G01X1569500D02*
G02I-800J0D01*
G37*
G36*
G01Y1078936D02*
G02I-800J0D01*
G37*
G36*
G01X1573241Y1086417D02*
G02I-800J0D01*
G37*
G36*
G01X1565760Y1082677D02*
G02I-800J0D01*
G37*
G36*
G01Y1086417D02*
G02I-800J0D01*
G37*
G36*
G01X1573241Y1082677D02*
G02I-800J0D01*
G37*
G36*
G01X1576981Y1078936D02*
G02I-800J0D01*
G37*
G36*
G01X1565760Y1105116D02*
G02I-800J0D01*
G37*
G36*
G01X1576981Y1097637D02*
G02I-800J0D01*
G37*
G36*
G01X1569500D02*
G02I-800J0D01*
G37*
G36*
G01X1576981Y1093897D02*
G02I-800J0D01*
G37*
G36*
G01X1569500D02*
G02I-800J0D01*
G37*
G36*
G01X1573241Y1101376D02*
G02I-800J0D01*
G37*
G36*
G01Y1105116D02*
G02I-800J0D01*
G37*
G36*
G01X1565760Y1101376D02*
G02I-800J0D01*
G37*
G36*
G01X1573241Y1228543D02*
G02I-800J0D01*
G37*
G36*
G01X1569500Y1236023D02*
G02I-800J0D01*
G37*
G36*
G01X1565760Y1224803D02*
G02I-800J0D01*
G37*
G36*
G01X1576981Y1236023D02*
G02I-800J0D01*
G37*
G36*
G01X1573241Y1224803D02*
G02I-800J0D01*
G37*
G36*
G01X1565760Y1228543D02*
G02I-800J0D01*
G37*
G36*
G01X1576981Y1232283D02*
G02I-800J0D01*
G37*
G36*
G01X1569500D02*
G02I-800J0D01*
G37*
G36*
G01X1573241Y1247243D02*
G02I-800J0D01*
G37*
G36*
G01X1565760Y1243503D02*
G02I-800J0D01*
G37*
G36*
G01Y1247243D02*
G02I-800J0D01*
G37*
G36*
G01X1576981Y1250984D02*
G02I-800J0D01*
G37*
G36*
G01X1573241Y1243503D02*
G02I-800J0D01*
G37*
G36*
G01X1569500Y1250984D02*
G02I-800J0D01*
G37*
G36*
G01Y1254724D02*
G02I-800J0D01*
G37*
G36*
G01X1576981D02*
G02I-800J0D01*
G37*
G36*
G01X1584461Y1075196D02*
G02I-800J0D01*
G37*
G36*
G01X1591941D02*
G02I-800J0D01*
G37*
G36*
G01X1595682Y1082677D02*
G02I-800J0D01*
G37*
G36*
G01X1580721D02*
G02I-800J0D01*
G37*
G36*
G01X1584461Y1078936D02*
G02I-800J0D01*
G37*
G36*
G01X1595682Y1086417D02*
G02I-800J0D01*
G37*
G36*
G01X1588201Y1082677D02*
G02I-800J0D01*
G37*
G36*
G01X1580721Y1086417D02*
G02I-800J0D01*
G37*
G36*
G01X1588201D02*
G02I-800J0D01*
G37*
G36*
G01X1591941Y1078936D02*
G02I-800J0D01*
G37*
G36*
G01X1595681Y1105116D02*
G02I-800J0D01*
G37*
G36*
G01X1591941Y1097637D02*
G02I-800J0D01*
G37*
G36*
G01X1584461Y1093897D02*
G02I-800J0D01*
G37*
G36*
G01X1595681Y1101376D02*
G02I-800J0D01*
G37*
G36*
G01X1584461Y1097637D02*
G02I-800J0D01*
G37*
G36*
G01X1588201Y1105116D02*
G02I-800J0D01*
G37*
G36*
G01X1580721Y1101376D02*
G02I-800J0D01*
G37*
G36*
G01X1591941Y1093897D02*
G02I-800J0D01*
G37*
G36*
G01X1588201Y1101376D02*
G02I-800J0D01*
G37*
G36*
G01X1580721Y1105116D02*
G02I-800J0D01*
G37*
G36*
G01X1595682Y1224803D02*
G02I-800J0D01*
G37*
G36*
G01X1591941Y1232283D02*
G02I-800J0D01*
G37*
G36*
G01X1584461Y1236023D02*
G02I-800J0D01*
G37*
G36*
G01X1580721Y1228543D02*
G02I-800J0D01*
G37*
G36*
G01X1584461Y1232283D02*
G02I-800J0D01*
G37*
G36*
G01X1595682Y1228543D02*
G02I-800J0D01*
G37*
G36*
G01X1580721Y1224803D02*
G02I-800J0D01*
G37*
G36*
G01X1588201Y1228543D02*
G02I-800J0D01*
G37*
G36*
G01Y1224803D02*
G02I-800J0D01*
G37*
G36*
G01X1591941Y1236023D02*
G02I-800J0D01*
G37*
G36*
G01X1580721Y1247243D02*
G02I-800J0D01*
G37*
G36*
G01X1588201D02*
G02I-800J0D01*
G37*
G36*
G01Y1243503D02*
G02I-800J0D01*
G37*
G36*
G01X1595682D02*
G02I-800J0D01*
G37*
G36*
G01X1580721D02*
G02I-800J0D01*
G37*
G36*
G01X1595682Y1247243D02*
G02I-800J0D01*
G37*
G36*
G01X1584461Y1250984D02*
G02I-800J0D01*
G37*
G36*
G01X1591941D02*
G02I-800J0D01*
G37*
G36*
G01X1584461Y1254724D02*
G02I-800J0D01*
G37*
G36*
G01X1591941D02*
G02I-800J0D01*
G37*
G36*
G01X1606901Y1075195D02*
G02I-800J0D01*
G37*
G36*
G01X1599422Y1075196D02*
G02I-800J0D01*
G37*
G36*
G01X1610641Y1086416D02*
G02I-800J0D01*
G37*
G36*
G01X1606901Y1078935D02*
G02I-800J0D01*
G37*
G36*
G01X1610641Y1082676D02*
G02I-800J0D01*
G37*
G36*
G01X1603162Y1082677D02*
G02I-800J0D01*
G37*
G36*
G01Y1086417D02*
G02I-800J0D01*
G37*
G36*
G01X1599422Y1078936D02*
G02I-800J0D01*
G37*
G36*
G01X1606901Y1093897D02*
G02I-800J0D01*
G37*
G36*
G01X1603162Y1101376D02*
G02I-800J0D01*
G37*
G36*
G01X1599422Y1097637D02*
G02I-800J0D01*
G37*
G36*
G01Y1093897D02*
G02I-800J0D01*
G37*
G36*
G01X1603162Y1105116D02*
G02I-800J0D01*
G37*
G36*
G01X1610642Y1101376D02*
G02I-800J0D01*
G37*
G36*
G01Y1105116D02*
G02I-800J0D01*
G37*
G36*
G01X1606901Y1097637D02*
G02I-800J0D01*
G37*
G36*
G01X1599422Y1236023D02*
G02I-800J0D01*
G37*
G36*
G01X1606902D02*
G02I-800J0D01*
G37*
G36*
G01X1610642Y1228543D02*
G02I-800J0D01*
G37*
G36*
G01X1606902Y1232283D02*
G02I-800J0D01*
G37*
G36*
G01X1603162Y1224803D02*
G02I-800J0D01*
G37*
G36*
G01X1610642D02*
G02I-800J0D01*
G37*
G36*
G01X1603162Y1228543D02*
G02I-800J0D01*
G37*
G36*
G01X1599422Y1232283D02*
G02I-800J0D01*
G37*
G36*
G01Y1250984D02*
G02I-800J0D01*
G37*
G36*
G01X1610642Y1247243D02*
G02I-800J0D01*
G37*
G36*
G01X1606902Y1250984D02*
G02I-800J0D01*
G37*
G36*
G01X1610642Y1243503D02*
G02I-800J0D01*
G37*
G36*
G01X1603162Y1247243D02*
G02I-800J0D01*
G37*
G36*
G01Y1243503D02*
G02I-800J0D01*
G37*
G36*
G01X1599422Y1254724D02*
G02I-800J0D01*
G37*
G36*
G01X1606902D02*
G02I-800J0D01*
G37*
G36*
G01X1614381Y1075196D02*
G02I-800J0D01*
G37*
G36*
G01X1621862D02*
G02I-800J0D01*
G37*
G36*
G01X1614381Y1078936D02*
G02I-800J0D01*
G37*
G36*
G01X1625602Y1082676D02*
G02I-800J0D01*
G37*
G36*
G01X1618121Y1082677D02*
G02I-800J0D01*
G37*
G36*
G01X1621862Y1078936D02*
G02I-800J0D01*
G37*
G36*
G01X1618121Y1086417D02*
G02I-800J0D01*
G37*
G36*
G01X1625602Y1086416D02*
G02I-800J0D01*
G37*
G36*
G01X1621862Y1093897D02*
G02I-800J0D01*
G37*
G36*
G01X1618122Y1105116D02*
G02I-800J0D01*
G37*
G36*
G01Y1101376D02*
G02I-800J0D01*
G37*
G36*
G01X1614381Y1093897D02*
G02I-800J0D01*
G37*
G36*
G01Y1097637D02*
G02I-800J0D01*
G37*
G36*
G01X1625603Y1101376D02*
G02I-800J0D01*
G37*
G36*
G01Y1105116D02*
G02I-800J0D01*
G37*
G36*
G01X1621862Y1097637D02*
G02I-800J0D01*
G37*
G36*
G01X1618122Y1228543D02*
G02I-800J0D01*
G37*
G36*
G01X1625603Y1224803D02*
G02I-800J0D01*
G37*
G36*
G01X1618122D02*
G02I-800J0D01*
G37*
G36*
G01X1621863Y1236023D02*
G02I-800J0D01*
G37*
G36*
G01X1614382D02*
G02I-800J0D01*
G37*
G36*
G01X1621863Y1232283D02*
G02I-800J0D01*
G37*
G36*
G01X1625603Y1228543D02*
G02I-800J0D01*
G37*
G36*
G01X1614382Y1232283D02*
G02I-800J0D01*
G37*
G36*
G01X1625603Y1247243D02*
G02I-800J0D01*
G37*
G36*
G01Y1243503D02*
G02I-800J0D01*
G37*
G36*
G01X1614382Y1250984D02*
G02I-800J0D01*
G37*
G36*
G01X1618122Y1243503D02*
G02I-800J0D01*
G37*
G36*
G01Y1247243D02*
G02I-800J0D01*
G37*
G36*
G01X1621863Y1250984D02*
G02I-800J0D01*
G37*
G36*
G01Y1254724D02*
G02I-800J0D01*
G37*
G36*
G01X1614382D02*
G02I-800J0D01*
G37*
G36*
G01X1636822Y1075196D02*
G02I-800J0D01*
G37*
G36*
G01X1644303D02*
G02I-800J0D01*
G37*
G36*
G01X1629342D02*
G02I-800J0D01*
G37*
G36*
G01X1633082Y1082677D02*
G02I-800J0D01*
G37*
G36*
G01X1644303Y1078936D02*
G02I-800J0D01*
G37*
G36*
G01X1629342D02*
G02I-800J0D01*
G37*
G36*
G01X1640562Y1086416D02*
G02I-800J0D01*
G37*
G36*
G01X1633082Y1086417D02*
G02I-800J0D01*
G37*
G36*
G01X1636822Y1078936D02*
G02I-800J0D01*
G37*
G36*
G01X1640562Y1082676D02*
G02I-800J0D01*
G37*
G36*
G01X1640563Y1101376D02*
G02I-800J0D01*
G37*
G36*
G01X1629342Y1093897D02*
G02I-800J0D01*
G37*
G36*
G01X1636822D02*
G02I-800J0D01*
G37*
G36*
G01X1640563Y1105116D02*
G02I-800J0D01*
G37*
G36*
G01X1633083D02*
G02I-800J0D01*
G37*
G36*
G01Y1101376D02*
G02I-800J0D01*
G37*
G36*
G01X1636822Y1097637D02*
G02I-800J0D01*
G37*
G36*
G01X1644303D02*
G02I-800J0D01*
G37*
G36*
G01Y1093897D02*
G02I-800J0D01*
G37*
G36*
G01X1629342Y1097637D02*
G02I-800J0D01*
G37*
G36*
G01X1633083Y1228543D02*
G02I-800J0D01*
G37*
G36*
G01X1629343Y1236023D02*
G02I-800J0D01*
G37*
G36*
G01Y1232283D02*
G02I-800J0D01*
G37*
G36*
G01X1640563Y1224803D02*
G02I-800J0D01*
G37*
G36*
G01X1636823Y1236023D02*
G02I-800J0D01*
G37*
G36*
G01X1644304Y1232283D02*
G02I-800J0D01*
G37*
G36*
G01X1633083Y1224803D02*
G02I-800J0D01*
G37*
G36*
G01X1644304Y1236023D02*
G02I-800J0D01*
G37*
G36*
G01X1636823Y1232283D02*
G02I-800J0D01*
G37*
G36*
G01X1640563Y1228543D02*
G02I-800J0D01*
G37*
G36*
G01X1633083Y1243503D02*
G02I-800J0D01*
G37*
G36*
G01X1640563D02*
G02I-800J0D01*
G37*
G36*
G01X1636823Y1250984D02*
G02I-800J0D01*
G37*
G36*
G01X1633083Y1247243D02*
G02I-800J0D01*
G37*
G36*
G01X1644304Y1250984D02*
G02I-800J0D01*
G37*
G36*
G01X1629343D02*
G02I-800J0D01*
G37*
G36*
G01X1640563Y1247243D02*
G02I-800J0D01*
G37*
G36*
G01X1636823Y1254724D02*
G02I-800J0D01*
G37*
G36*
G01X1629343D02*
G02I-800J0D01*
G37*
G36*
G01X1644304D02*
G02I-800J0D01*
G37*
G36*
G01X1651783Y1075196D02*
G02I-800J0D01*
G37*
G36*
G01X1659263D02*
G02I-800J0D01*
G37*
G36*
G01X1655523Y1086416D02*
G02I-800J0D01*
G37*
G36*
G01Y1082676D02*
G02I-800J0D01*
G37*
G36*
G01X1651783Y1078936D02*
G02I-800J0D01*
G37*
G36*
G01X1648042Y1082677D02*
G02I-800J0D01*
G37*
G36*
G01Y1086417D02*
G02I-800J0D01*
G37*
G36*
G01X1659263Y1078936D02*
G02I-800J0D01*
G37*
G36*
G01Y1097637D02*
G02I-800J0D01*
G37*
G36*
G01X1648044Y1101376D02*
G02I-800J0D01*
G37*
G36*
G01X1659263Y1093897D02*
G02I-800J0D01*
G37*
G36*
G01X1655524Y1105116D02*
G02I-800J0D01*
G37*
G36*
G01X1651783Y1093897D02*
G02I-800J0D01*
G37*
G36*
G01X1648044Y1105116D02*
G02I-800J0D01*
G37*
G36*
G01X1655524Y1101376D02*
G02I-800J0D01*
G37*
G36*
G01X1651783Y1097637D02*
G02I-800J0D01*
G37*
G36*
G01X1655524Y1228543D02*
G02I-800J0D01*
G37*
G36*
G01X1648044D02*
G02I-800J0D01*
G37*
G36*
G01X1659264Y1232283D02*
G02I-800J0D01*
G37*
G36*
G01X1655524Y1224803D02*
G02I-800J0D01*
G37*
G36*
G01X1659264Y1236023D02*
G02I-800J0D01*
G37*
G36*
G01X1651784D02*
G02I-800J0D01*
G37*
G36*
G01X1648044Y1224803D02*
G02I-800J0D01*
G37*
G36*
G01X1651784Y1232283D02*
G02I-800J0D01*
G37*
G36*
G01X1655524Y1243503D02*
G02I-800J0D01*
G37*
G36*
G01X1651784Y1250984D02*
G02I-800J0D01*
G37*
G36*
G01X1648044Y1247243D02*
G02I-800J0D01*
G37*
G36*
G01X1655524D02*
G02I-800J0D01*
G37*
G36*
G01X1648044Y1243503D02*
G02I-800J0D01*
G37*
G36*
G01X1659264Y1250984D02*
G02I-800J0D01*
G37*
G36*
G01X1651784Y1254724D02*
G02I-800J0D01*
G37*
G36*
G01X1659264D02*
G02I-800J0D01*
G37*
G36*
G01X1674224Y1075196D02*
G02I-800J0D01*
G37*
G36*
G01X1666744D02*
G02I-800J0D01*
G37*
G36*
G01X1663003Y1086417D02*
G02I-800J0D01*
G37*
G36*
G01Y1082677D02*
G02I-800J0D01*
G37*
G36*
G01X1670484Y1086416D02*
G02I-800J0D01*
G37*
G36*
G01X1666744Y1078936D02*
G02I-800J0D01*
G37*
G36*
G01X1674224D02*
G02I-800J0D01*
G37*
G36*
G01X1670484Y1082676D02*
G02I-800J0D01*
G37*
G36*
G01X1666744Y1093897D02*
G02I-800J0D01*
G37*
G36*
G01X1663004Y1105116D02*
G02I-800J0D01*
G37*
G36*
G01X1670485D02*
G02I-800J0D01*
G37*
G36*
G01X1674224Y1097637D02*
G02I-800J0D01*
G37*
G36*
G01X1670485Y1101376D02*
G02I-800J0D01*
G37*
G36*
G01X1674224Y1093897D02*
G02I-800J0D01*
G37*
G36*
G01X1666744Y1097637D02*
G02I-800J0D01*
G37*
G36*
G01X1663004Y1101376D02*
G02I-800J0D01*
G37*
G36*
G01X1674225Y1112598D02*
G02I-800J0D01*
G37*
G36*
G01X1666745Y1123818D02*
G02I-800J0D01*
G37*
G36*
G01X1674225Y1120078D02*
G02I-800J0D01*
G37*
G36*
G01X1670485Y1123818D02*
G02I-800J0D01*
G37*
G36*
G01X1666745Y1116338D02*
G02I-800J0D01*
G37*
G36*
G01X1670485D02*
G02I-800J0D01*
G37*
G36*
G01X1666745Y1131299D02*
G02I-800J0D01*
G37*
G36*
G01X1670485D02*
G02I-800J0D01*
G37*
G36*
G01X1674225Y1127559D02*
G02I-800J0D01*
G37*
G36*
G01Y1135039D02*
G02I-800J0D01*
G37*
G36*
G01Y1202362D02*
G02I-800J0D01*
G37*
G36*
G01X1666745Y1198621D02*
G02I-800J0D01*
G37*
G36*
G01X1670485D02*
G02I-800J0D01*
G37*
G36*
G01X1666745Y1206102D02*
G02I-800J0D01*
G37*
G36*
G01X1670485Y1213582D02*
G02I-800J0D01*
G37*
G36*
G01X1674225Y1209842D02*
G02I-800J0D01*
G37*
G36*
G01X1670485Y1206102D02*
G02I-800J0D01*
G37*
G36*
G01X1666745Y1213582D02*
G02I-800J0D01*
G37*
G36*
G01X1674225Y1217322D02*
G02I-800J0D01*
G37*
G36*
G01Y1236023D02*
G02I-800J0D01*
G37*
G36*
G01X1663004Y1228543D02*
G02I-800J0D01*
G37*
G36*
G01X1670485D02*
G02I-800J0D01*
G37*
G36*
G01X1674225Y1232283D02*
G02I-800J0D01*
G37*
G36*
G01X1666745D02*
G02I-800J0D01*
G37*
G36*
G01Y1236023D02*
G02I-800J0D01*
G37*
G36*
G01X1663004Y1224803D02*
G02I-800J0D01*
G37*
G36*
G01X1670485D02*
G02I-800J0D01*
G37*
G36*
G01X1674225Y1250984D02*
G02I-800J0D01*
G37*
G36*
G01X1663004Y1247243D02*
G02I-800J0D01*
G37*
G36*
G01Y1243503D02*
G02I-800J0D01*
G37*
G36*
G01X1666745Y1250984D02*
G02I-800J0D01*
G37*
G36*
G01X1670485Y1247243D02*
G02I-800J0D01*
G37*
G36*
G01Y1243503D02*
G02I-800J0D01*
G37*
G36*
G01X1666745Y1254724D02*
G02I-800J0D01*
G37*
G36*
G01X1674225D02*
G02I-800J0D01*
G37*
G36*
G01X1681704Y1075196D02*
G02I-800J0D01*
G37*
G36*
G01X1689184D02*
G02I-800J0D01*
G37*
G36*
G01X1692926Y1090157D02*
G02I-800J0D01*
G37*
G36*
G01Y1082676D02*
G02I-800J0D01*
G37*
G36*
G01X1685444Y1082677D02*
G02I-800J0D01*
G37*
G36*
G01Y1086417D02*
G02I-800J0D01*
G37*
G36*
G01X1681704Y1078936D02*
G02I-800J0D01*
G37*
G36*
G01X1689184D02*
G02I-800J0D01*
G37*
G36*
G01X1677964Y1086417D02*
G02I-800J0D01*
G37*
G36*
G01Y1082677D02*
G02I-800J0D01*
G37*
G36*
G01X1692926Y1101377D02*
G02I-800J0D01*
G37*
G36*
G01X1685445D02*
G02I-800J0D01*
G37*
G36*
G01X1677965Y1105116D02*
G02I-800J0D01*
G37*
G36*
G01X1681704Y1097637D02*
G02I-800J0D01*
G37*
G36*
G01X1677965Y1101376D02*
G02I-800J0D01*
G37*
G36*
G01X1689185Y1097637D02*
G02I-800J0D01*
G37*
G36*
G01X1685445Y1105117D02*
G02I-800J0D01*
G37*
G36*
G01X1681704Y1093897D02*
G02I-800J0D01*
G37*
G36*
G01X1689185D02*
G02I-800J0D01*
G37*
G36*
G01X1677965Y1120078D02*
G02I-800J0D01*
G37*
G36*
G01Y1112598D02*
G02I-800J0D01*
G37*
G36*
G01X1692926Y1116338D02*
G02I-800J0D01*
G37*
G36*
G01Y1108858D02*
G02I-800J0D01*
G37*
G36*
G01X1685445Y1120078D02*
G02I-800J0D01*
G37*
G36*
G01X1689185D02*
G02I-800J0D01*
G37*
G36*
G01X1685445Y1112598D02*
G02I-800J0D01*
G37*
G36*
G01X1692926Y1123818D02*
G02I-800J0D01*
G37*
G36*
G01X1689185Y1112598D02*
G02I-800J0D01*
G37*
G36*
G01X1677965Y1135039D02*
G02I-800J0D01*
G37*
G36*
G01Y1127559D02*
G02I-800J0D01*
G37*
G36*
G01X1685445Y1135039D02*
G02I-800J0D01*
G37*
G36*
G01Y1127558D02*
G02I-800J0D01*
G37*
G36*
G01X1692926Y1131299D02*
G02I-800J0D01*
G37*
G36*
G01X1689185Y1127558D02*
G02I-800J0D01*
G37*
G36*
G01Y1135039D02*
G02I-800J0D01*
G37*
G36*
G01X1685445Y1202362D02*
G02I-800J0D01*
G37*
G36*
G01X1692926Y1198621D02*
G02I-800J0D01*
G37*
G36*
G01X1689185Y1202362D02*
G02I-800J0D01*
G37*
G36*
G01X1677965D02*
G02I-800J0D01*
G37*
G36*
G01X1692926Y1213582D02*
G02I-800J0D01*
G37*
G36*
G01X1685445Y1217322D02*
G02I-800J0D01*
G37*
G36*
G01Y1209842D02*
G02I-800J0D01*
G37*
G36*
G01X1692926Y1206102D02*
G02I-800J0D01*
G37*
G36*
G01X1677965Y1209842D02*
G02I-800J0D01*
G37*
G36*
G01X1692926Y1221062D02*
G02I-800J0D01*
G37*
G36*
G01X1689185Y1209842D02*
G02I-800J0D01*
G37*
G36*
G01X1677965Y1217322D02*
G02I-800J0D01*
G37*
G36*
G01X1689185D02*
G02I-800J0D01*
G37*
G36*
G01X1677965Y1228543D02*
G02I-800J0D01*
G37*
G36*
G01X1681705Y1236023D02*
G02I-800J0D01*
G37*
G36*
G01Y1232283D02*
G02I-800J0D01*
G37*
G36*
G01X1692926Y1228543D02*
G02I-800J0D01*
G37*
G36*
G01X1685445Y1224803D02*
G02I-800J0D01*
G37*
G36*
G01Y1228543D02*
G02I-800J0D01*
G37*
G36*
G01X1677965Y1224803D02*
G02I-800J0D01*
G37*
G36*
G01X1689185Y1232283D02*
G02I-800J0D01*
G37*
G36*
G01Y1236023D02*
G02I-800J0D01*
G37*
G36*
G01X1685445Y1243503D02*
G02I-800J0D01*
G37*
G36*
G01X1677965D02*
G02I-800J0D01*
G37*
G36*
G01X1692926Y1247243D02*
G02I-800J0D01*
G37*
G36*
G01X1685445D02*
G02I-800J0D01*
G37*
G36*
G01X1677965D02*
G02I-800J0D01*
G37*
G36*
G01X1689185Y1250984D02*
G02I-800J0D01*
G37*
G36*
G01X1692926Y1239763D02*
G02I-800J0D01*
G37*
G36*
G01X1681705Y1250984D02*
G02I-800J0D01*
G37*
G36*
G01X1689185Y1254724D02*
G02I-800J0D01*
G37*
G36*
G01X1681705D02*
G02I-800J0D01*
G37*
G36*
G01X1696666Y1090157D02*
G02I-800J0D01*
G37*
G36*
G01Y1082676D02*
G02I-800J0D01*
G37*
G36*
G01Y1101377D02*
G02I-800J0D01*
G37*
G36*
G01Y1123818D02*
G02I-800J0D01*
G37*
G36*
G01Y1116338D02*
G02I-800J0D01*
G37*
G36*
G01Y1108858D02*
G02I-800J0D01*
G37*
G36*
G01Y1131299D02*
G02I-800J0D01*
G37*
G36*
G01Y1198621D02*
G02I-800J0D01*
G37*
G36*
G01Y1221062D02*
G02I-800J0D01*
G37*
G36*
G01Y1213582D02*
G02I-800J0D01*
G37*
G36*
G01Y1206102D02*
G02I-800J0D01*
G37*
G36*
G01Y1228543D02*
G02I-800J0D01*
G37*
G36*
G01Y1239763D02*
G02I-800J0D01*
G37*
G36*
G01Y1247243D02*
G02I-800J0D01*
G37*
%LPD*%
G75*
G54D15*
X7271Y70981D03*
X11011Y79720D03*
X8786Y88425D03*
X14264Y94236D03*
X10292D03*
X12786Y87903D03*
X18000Y90000D03*
X18298Y102141D03*
X8000Y102500D03*
X10131Y115473D03*
X15143Y115581D03*
X14996Y133034D03*
X11442Y132719D03*
X19855Y133000D03*
X9082Y135789D03*
X19855Y141362D03*
X11999Y141415D03*
X15948Y141267D03*
X10966Y162073D03*
Y159073D03*
X16909Y153263D03*
X12247Y166341D03*
X17313Y166937D03*
X21909Y153263D03*
X22335Y166721D03*
X16709Y175943D03*
X19572Y219470D03*
Y221970D03*
X10259Y218085D03*
X13059D03*
X19638Y226320D03*
X16859Y216385D03*
X19572Y216970D03*
X22599Y228646D03*
X18206Y244571D03*
X15586Y249108D03*
X13715Y259381D03*
X8970Y254871D03*
X18206Y264571D03*
X7036Y272371D03*
X8335Y280663D03*
X14807Y282181D03*
X15586Y269108D03*
X15499Y288542D03*
X17033Y1006819D03*
X14357Y1009906D03*
X20216Y1009748D03*
X14197Y1014205D03*
Y1017759D03*
X20197Y1014205D03*
Y1017759D03*
X12599Y1438143D03*
X16304Y1468196D03*
X15889Y1494254D03*
X10089D03*
X6489Y1501334D03*
X19745Y1508846D03*
X7983Y1529035D03*
Y1525635D03*
X19735Y1530499D03*
X19859Y1520657D03*
X6951Y1538547D03*
X18879Y1534334D03*
X10367Y1553080D03*
X32350Y67562D03*
X28442Y55340D03*
X32350Y59562D03*
Y63562D03*
X26588Y97667D03*
X35442D03*
X35048Y103411D03*
X35688Y111255D03*
Y114655D03*
X22439Y102495D03*
X35207Y106561D03*
X28388Y121742D03*
X35688Y125428D03*
X28388Y132515D03*
Y118342D03*
X35688Y128828D03*
X28388Y135915D03*
X22935Y162073D03*
Y159073D03*
X26565Y177448D03*
X32507Y180517D03*
X30567Y195176D03*
X28067D03*
X25567D03*
X33067D03*
X29585Y199248D03*
X32585D03*
X29921Y206806D03*
X32585Y202048D03*
X25648Y210509D03*
X28148D03*
X29585Y201748D03*
X27421Y206806D03*
X27340Y230556D03*
X36185Y230117D03*
X31595Y227824D03*
X32201Y238714D03*
X23844Y239299D03*
X21556Y232971D03*
X31682Y246874D03*
X33902Y244297D03*
X26325Y262078D03*
X25549Y256394D03*
X31682Y266874D03*
X29116Y281129D03*
X37117Y279991D03*
X25549Y276394D03*
X34845Y291756D03*
X26629Y295619D03*
X35650Y491982D03*
Y495982D03*
X30177Y534211D03*
X34359Y541135D03*
X34732Y534909D03*
X25819Y527726D03*
Y548726D03*
X34425Y546553D03*
X34448Y552726D03*
X25819Y544726D03*
X30123Y611071D03*
X27686Y621311D03*
X36494Y616905D03*
X36306Y622285D03*
X27686Y629311D03*
Y625311D03*
X36692Y633724D03*
X36575Y627713D03*
X35293Y662952D03*
X35250Y671508D03*
X34565Y699082D03*
X36529Y1006321D03*
X30479Y1006509D03*
X24456Y1006401D03*
X32093Y1009748D03*
X26155Y1009985D03*
X29197Y1014205D03*
X32197Y1017759D03*
X26197D03*
X35197Y1014205D03*
X21196Y1065529D03*
Y1063029D03*
X36089Y1062601D03*
Y1065101D03*
X35925Y1075663D03*
X33425D03*
X28996Y1065529D03*
X23796D03*
X26396D03*
Y1063029D03*
X23796D03*
X28996D03*
X28606Y1082678D03*
X23406D03*
X26006D03*
Y1080178D03*
X23406D03*
X28606D03*
X20806Y1082678D03*
Y1080178D03*
X21321Y1098769D03*
X26521D03*
X29121D03*
X23921D03*
Y1101335D03*
X29121D03*
X26521D03*
X21321D03*
X32574Y1111633D03*
X29874D03*
X27274D03*
X24674D03*
Y1121333D03*
X27274D03*
X29874D03*
X32574D03*
X24674Y1130333D03*
X21974D03*
X21209Y1138705D03*
X23709D03*
X31631Y1198651D03*
X29860Y1438552D03*
X23603Y1449735D03*
X29880Y1441702D03*
X35825Y1464845D03*
X33189Y1501373D03*
X22381Y1554152D03*
X26231Y1554167D03*
X45988Y90512D03*
X51550Y90615D03*
X48476Y180812D03*
X48643Y442919D03*
X48596Y451419D03*
X45643Y472905D03*
X41643Y473419D03*
X49643Y472905D03*
Y464419D03*
X41643Y464919D03*
X48390Y485128D03*
X51239Y485138D03*
X40009Y481467D03*
X43948Y492108D03*
X44563Y482165D03*
X39801Y504825D03*
X42301D03*
X44801D03*
X43804Y500202D03*
X45256Y495993D03*
X45293Y522569D03*
X39742Y517401D03*
X42242D03*
X44742D03*
X46993Y529169D03*
X41408Y531882D03*
X43908D03*
X45293Y525369D03*
X46408Y531882D03*
X38358Y531948D03*
X52869Y537958D03*
X46643Y555194D03*
X52869Y540458D03*
X43843Y555194D03*
X46643Y571194D03*
X43843D03*
Y563194D03*
X46643D03*
X51000Y581222D03*
X45400D03*
X48200D03*
X51000Y591215D03*
X45400D03*
X48200D03*
X51172Y607762D03*
X48372D03*
X45572D03*
Y610562D03*
X48372D03*
X51172D03*
X40362Y610548D03*
X54192Y633473D03*
X42172Y633716D03*
X49192Y628078D03*
X47179Y633736D03*
X37847Y662910D03*
X39549Y682108D03*
X36910D03*
X37804Y671508D03*
X40165Y699082D03*
X37365D03*
X49249Y837718D03*
X52349D03*
X46049D03*
X53549Y843118D03*
X52077Y905295D03*
X48429Y916430D03*
X47264Y919649D03*
X48683Y1006510D03*
X42470Y1006738D03*
X50541Y1009589D03*
X44999Y1009510D03*
X38823Y1009273D03*
X47197Y1014205D03*
X41197D03*
X44197Y1017759D03*
X38197D03*
X48704Y1017982D03*
X43889Y1062601D03*
X38689D03*
X41289D03*
Y1065101D03*
X38689D03*
X43889D03*
X47314Y1072228D03*
X41172Y1079064D03*
X46166Y1093757D03*
X39659Y1105100D03*
X42259D03*
X44859D03*
X47559D03*
X48585Y1123867D03*
X47559Y1114800D03*
X44859D03*
X42259D03*
X39659D03*
X48547Y1133688D03*
X51047D03*
X55188Y1205179D03*
X51023Y1201416D03*
X48842Y1211109D03*
X53479Y1216256D03*
X43198Y1254055D03*
X45698D03*
X48198D03*
X45698Y1251555D03*
X43198D03*
X48198D03*
X47621Y1343672D03*
X39225Y1464845D03*
X48089Y1501387D03*
X39095Y1501361D03*
X47074Y1555923D03*
X40951Y1555932D03*
X64785Y79993D03*
Y82593D03*
Y85193D03*
Y74793D03*
Y77393D03*
X64829Y92874D03*
X55871Y99961D03*
X55921Y95236D03*
X66856Y104249D03*
Y107649D03*
X66478Y162368D03*
X63878D03*
X69261Y211695D03*
Y208695D03*
X65189Y210713D03*
Y213213D03*
Y208213D03*
X54733Y212978D03*
Y215478D03*
Y207978D03*
Y210478D03*
X65189Y215713D03*
X57987Y258880D03*
X60562Y264180D03*
X58062D03*
X66956Y267526D03*
Y270026D03*
X54167Y457339D03*
X56667D03*
X65737Y445603D03*
X57857Y446071D03*
X56667Y459839D03*
X54167D03*
Y462339D03*
X56667D03*
X62224Y473045D03*
X67670Y464818D03*
X58224Y465004D03*
X63154Y462371D03*
X55124Y478625D03*
X53739Y485138D03*
X56239D03*
X56824Y482425D03*
X55124Y475825D03*
X62700Y491214D03*
X66403Y495487D03*
X62700Y493714D03*
X66403Y492987D03*
X68202Y537877D03*
X56572Y539731D03*
X68202Y542877D03*
Y545377D03*
Y540377D03*
X61330Y544895D03*
X56572Y542231D03*
X64130Y541895D03*
Y544895D03*
X61630Y541895D03*
X68188Y548358D03*
X64408Y582747D03*
X63859Y590801D03*
X67684Y597232D03*
X63684Y597130D03*
X67684Y605637D03*
X61854Y617853D03*
Y620653D03*
X53972Y607762D03*
Y610562D03*
X59684Y605443D03*
X63684D03*
X66530Y625013D03*
X58181Y627908D03*
X64692Y642184D03*
X56049Y827218D03*
X68649D03*
X69049Y847718D03*
X65549Y850718D03*
X68598Y859415D03*
X68778Y873821D03*
X63969Y869475D03*
X63930Y874694D03*
X68100Y910122D03*
X71528Y913190D03*
X64632Y901500D03*
X59962Y910251D03*
X53197Y1014205D03*
Y1017759D03*
X55699Y1072761D03*
X61588Y1074481D03*
X62109Y1087656D03*
Y1084656D03*
Y1079656D03*
Y1091656D03*
X60269Y1198820D03*
X63094Y1207604D03*
X55596Y1210466D03*
X68245Y1212054D03*
X58443Y1272257D03*
X54843Y1501625D03*
X60227Y1514751D03*
X60277Y1528395D03*
X55862Y1541791D03*
X65478Y1541980D03*
X60303Y1534436D03*
X60747Y1555890D03*
X64747D03*
X60864Y1583484D03*
X58064D03*
X55264D03*
X69816Y1592527D03*
X60554Y1615152D03*
X73110Y98551D03*
X77804Y95879D03*
X76005Y114623D03*
Y111223D03*
X76660Y103783D03*
X76005Y125396D03*
Y128796D03*
X75194Y141247D03*
X71422Y147540D03*
X82661Y143740D03*
X80041Y148277D03*
X73578Y165393D03*
Y162793D03*
Y170493D03*
Y167993D03*
X80502Y177616D03*
X81083Y172190D03*
X72575Y181426D03*
X75786Y181366D03*
X78581Y181009D03*
X83756Y168697D03*
X84844Y191941D03*
X75400Y184012D03*
X72783Y184221D03*
X72061Y208695D03*
X71761Y211695D03*
X76819Y213859D03*
Y211359D03*
X80522Y213132D03*
Y215632D03*
X80766Y256303D03*
X75438Y265701D03*
X85541Y266114D03*
X80525Y265896D03*
X72256Y267526D03*
X69756D03*
Y270026D03*
X72256D03*
X83014Y281982D03*
X77073Y281716D03*
X71130Y462152D03*
Y459652D03*
Y464652D03*
X73630Y459652D03*
Y462152D03*
Y464652D03*
X78033Y491133D03*
X71461Y498151D03*
Y495151D03*
X73961D03*
X78033Y498633D03*
Y496133D03*
Y493633D03*
X73961Y498151D03*
X78133Y553297D03*
Y555897D03*
X75688Y548358D03*
X73188D03*
X70688D03*
X78133Y558497D03*
Y566597D03*
Y563697D03*
Y561097D03*
X72128Y570686D03*
X74923Y570478D03*
X75340Y576484D03*
X74983Y573689D03*
X72337Y573303D03*
X78733Y578405D03*
X84159Y578986D03*
X83684Y596729D03*
X72515Y596089D03*
X77734Y596782D03*
X81740Y619758D03*
Y616958D03*
Y614158D03*
X69670Y619513D03*
Y616713D03*
Y613913D03*
X79684Y605443D03*
X82648Y670679D03*
X73914Y660107D03*
X79043Y667391D03*
X84845Y659857D03*
X84314Y686107D03*
X82562Y680037D03*
X78735Y683426D03*
X72149Y827318D03*
X74349Y824718D03*
Y821918D03*
X74700Y842890D03*
X84367Y878286D03*
X76528Y878533D03*
X74028Y889065D03*
X83079Y888515D03*
X72035Y898346D03*
X80339Y897943D03*
X76203Y897910D03*
X80593Y946082D03*
X78167Y949261D03*
X76332Y953421D03*
X87632Y1007522D03*
X70059Y1075656D03*
X70302Y1067656D03*
X77734Y1095676D03*
X70947Y1201565D03*
Y1205835D03*
X71006Y1228684D03*
X71020Y1224323D03*
X74909Y1593009D03*
X71910Y1625009D03*
X78291Y1625743D03*
X83689Y1624736D03*
X82291Y1633801D03*
X78291D03*
X70291D03*
X86407Y132509D03*
Y118335D03*
Y121735D03*
Y135909D03*
X91224Y141247D03*
X92337Y144172D03*
X95711Y143518D03*
X94811Y152373D03*
X97961Y152562D03*
X103456Y157370D03*
X98826Y172665D03*
X98763Y178560D03*
X98653Y183834D03*
X99639Y186629D03*
X98943Y200864D03*
X92898Y192490D03*
X98173Y190185D03*
X89353Y206767D03*
X86853D03*
X91853D03*
X98966Y207037D03*
X99032Y212455D03*
X89483Y221708D03*
X86983D03*
X86398Y224421D03*
X88098Y231021D03*
Y228221D03*
X96333Y221642D03*
X91983Y221708D03*
X103841Y228631D03*
X93649Y236189D03*
X91149D03*
X88649D03*
X91090Y248765D03*
X88590D03*
X93590D03*
X97747Y265897D03*
X100247D03*
X94087Y270695D03*
X91287D03*
X88787D03*
Y268195D03*
X91287D03*
X94087D03*
X98255Y374510D03*
X100120Y377898D03*
X100066Y381976D03*
X86788Y581659D03*
X87684Y605443D03*
X95973Y655660D03*
X92897Y658359D03*
X95917Y658374D03*
X95539Y664443D03*
X86289Y822088D03*
X86367Y848086D03*
X90000Y871389D03*
X103770Y868206D03*
X103692Y900295D03*
X91387Y905295D03*
X100058Y977651D03*
X99836Y980330D03*
X103836Y988813D03*
X100200Y988800D03*
X95836Y988813D03*
X85706Y998507D03*
X94398Y1006648D03*
X101025Y1009655D03*
X94586Y1023900D03*
X91765Y1018307D03*
X88007Y1013678D03*
X88479Y1023731D03*
X88287Y1026537D03*
X97609Y1018469D03*
X90450Y1033542D03*
X93496Y1547768D03*
X107364Y116594D03*
X118307Y110784D03*
X113307D03*
X107364Y119594D03*
X117886Y124663D03*
X112864Y124879D03*
X107798Y124283D03*
X119230Y138838D03*
X106205Y161306D03*
X107540Y176665D03*
Y168665D03*
Y196665D03*
Y192665D03*
X107653Y186778D03*
X107572Y204864D03*
Y208864D03*
X112621Y218085D03*
X115421D03*
X103213Y219379D03*
X117948Y249108D03*
X109329Y248371D03*
X111993Y710102D03*
X120250Y758841D03*
X113505Y796856D03*
X109591Y796905D03*
X102355Y874267D03*
X102947Y877196D03*
X102320Y891043D03*
X110887Y884000D03*
X103972Y977609D03*
X103836Y980330D03*
X111836Y988813D03*
X119836D03*
X115836D03*
X107836D03*
X103825Y1009655D03*
X105971Y1025745D03*
X114770Y1016827D03*
X110409Y1024094D03*
X114770Y1029427D03*
X110970Y1030672D03*
X101970D03*
X104970D03*
X107970D03*
X102761Y1096233D03*
X108971Y1109564D03*
X103124D03*
Y1122164D03*
X108971D03*
X103124Y1134764D03*
X108971D03*
X103124Y1147364D03*
X108971D03*
X103124Y1172564D03*
X108971D03*
X103124Y1159964D03*
X108971D03*
X103861Y1182703D03*
X118533Y1207737D03*
X112048Y1214372D03*
X107803Y1218169D03*
X128950Y97667D03*
X133200Y95111D03*
X124606Y102495D03*
X119333Y116594D03*
X130750Y132515D03*
Y121742D03*
Y118342D03*
X119333Y119594D03*
X122867Y125107D03*
X130750Y135915D03*
X124340Y142862D03*
X131481Y143762D03*
X125381Y148717D03*
X131947Y199248D03*
X127929Y195176D03*
X130429D03*
X132929D03*
X134947Y199248D03*
X128010Y210509D03*
X130510D03*
X132283Y206806D03*
X129783D03*
X131947Y201748D03*
X122000Y226320D03*
X119221Y216385D03*
X121934Y216970D03*
Y219470D03*
Y221970D03*
X129702Y230556D03*
X133957Y227824D03*
X124961Y228646D03*
X128687Y242078D03*
X123918Y232971D03*
X134044Y246874D03*
X120568Y244571D03*
X127911Y256394D03*
X126131Y359511D03*
X125753Y365856D03*
X119099Y755052D03*
X118467Y796785D03*
X122437Y860775D03*
X125698Y857515D03*
X122432Y857540D03*
X129666Y857514D03*
X133424Y857303D03*
X122887Y888000D03*
X123387Y892000D03*
X135836Y988813D03*
X131836D03*
X123836D03*
X127836D03*
X120617Y1029427D03*
Y1016827D03*
X133579Y1097469D03*
X124925Y1102091D03*
X130380Y1105091D03*
X124880D03*
X124925Y1114691D03*
Y1127291D03*
X124880Y1117691D03*
X130380D03*
X124925Y1139891D03*
X124880Y1130291D03*
X130380D03*
X130434Y1144964D03*
X124474Y1142997D03*
X130380Y1155491D03*
X124880D03*
X124925Y1152491D03*
X124474Y1168197D03*
X130434Y1170164D03*
X124925Y1165091D03*
Y1177691D03*
X131000Y1180266D03*
X124765Y1180691D03*
X135757Y1221407D03*
X135448Y1229402D03*
Y1234921D03*
X126433Y1230407D03*
X129250Y1227650D03*
X137410Y103411D03*
X137804Y97667D03*
X148600Y90650D03*
X148350Y95236D03*
X138050Y111255D03*
Y114655D03*
X137569Y106561D03*
X138050Y128828D03*
Y125428D03*
X135429Y195176D03*
X134947Y202048D03*
X138547Y230117D03*
X134563Y238714D03*
X138664Y241699D03*
X148061Y378600D03*
X148692Y391001D03*
X148061Y382600D03*
X148692Y394401D03*
Y405174D03*
X140690Y401513D03*
Y398113D03*
X148692Y408574D03*
X138290Y412287D03*
X148692Y419347D03*
Y422747D03*
X138290Y415687D03*
Y426460D03*
X148692Y433521D03*
X138290Y429860D03*
X148692Y436921D03*
X138290Y440633D03*
X148176Y458711D03*
X138290Y444033D03*
X148940Y455921D03*
X145376Y458711D03*
X138290Y469387D03*
Y472787D03*
X147520Y463600D03*
X148692Y476499D03*
X138290Y483560D03*
X148692Y490673D03*
X138290Y486960D03*
X148692Y479899D03*
Y494073D03*
Y524033D03*
Y520633D03*
X138290Y516921D03*
Y513521D03*
Y531094D03*
X148692Y538206D03*
Y534806D03*
X138290Y527694D03*
X142024Y552466D03*
X147925Y603600D03*
Y619600D03*
Y623600D03*
X149469Y634190D03*
X152658Y645389D03*
X136862Y857244D03*
X147836Y988813D03*
X139836D03*
X151836D03*
X143836D03*
X142026Y1012354D03*
X136571Y1009354D03*
X136526Y1012354D03*
X136571Y1021954D03*
X142026Y1024954D03*
X136526D03*
X144640Y1039439D03*
X150952Y1040115D03*
X146595Y1053457D03*
X136432Y1224472D03*
X167191Y92874D03*
X153912Y90615D03*
X158283Y95236D03*
X158233Y99961D03*
X166240Y162368D03*
X157095Y210478D03*
Y207978D03*
Y215478D03*
Y212978D03*
X160424Y264180D03*
X162924D03*
X160349Y258880D03*
X164496Y309405D03*
X150703Y453682D03*
X159836Y988813D03*
X155836Y997860D03*
X160733Y1056594D03*
X153693Y1051037D03*
X160547Y1049283D03*
X160627Y1053561D03*
X160807Y1043955D03*
X166188Y1066551D03*
X163191Y1065313D03*
X159228Y1065613D03*
X165649Y1159350D03*
Y1151870D03*
X167147Y77393D03*
Y74793D03*
Y85193D03*
Y82593D03*
Y79993D03*
X175472Y98551D03*
X178367Y111223D03*
Y114623D03*
X179022Y103783D03*
X169218Y107649D03*
Y104249D03*
X178367Y128796D03*
Y125396D03*
X173784Y147540D03*
X177556Y141247D03*
X185023Y143740D03*
X182403Y148277D03*
X175940Y162793D03*
Y165393D03*
X168840Y162368D03*
X175940Y167993D03*
Y170493D03*
X178148Y181366D03*
X180943Y181009D03*
X174937Y181426D03*
X182864Y177616D03*
X183445Y172190D03*
X175145Y184221D03*
X177762Y184012D03*
X171623Y211695D03*
X182884Y213132D03*
X179181Y211359D03*
Y213859D03*
X174123Y211695D03*
X167551Y208213D03*
Y213213D03*
Y210713D03*
X171623Y208695D03*
X174423D03*
X167551Y215713D03*
X182884Y215632D03*
X177800Y265701D03*
X182887Y265896D03*
X174618Y267526D03*
Y270026D03*
X169318Y267526D03*
X172118D03*
Y270026D03*
X169318D03*
X179435Y281716D03*
X170215Y311671D03*
X175615Y550907D03*
X173115D03*
X175615Y553407D03*
X173115D03*
X174923Y545263D03*
Y541863D03*
X177385Y566929D03*
X171339Y572070D03*
X172686Y569928D03*
X175033Y570962D03*
X174776Y568475D03*
X177099Y569426D03*
X169389Y1155610D03*
X191568Y76587D03*
Y72615D03*
X193007Y100625D03*
X186026Y97475D03*
X185957Y106186D03*
X197380Y112083D03*
X188769Y118335D03*
Y121735D03*
Y132509D03*
Y135909D03*
X193586Y141247D03*
X198073Y143518D03*
X197173Y152373D03*
X201015Y183834D03*
X201125Y178560D03*
X186118Y168697D03*
X201188Y172665D03*
X187206Y191941D03*
X195260Y192490D03*
X200535Y190185D03*
X201305Y200864D03*
X189215Y206767D03*
X191715D03*
X194215D03*
X201394Y212455D03*
X201328Y207037D03*
X194345Y221708D03*
X198695Y221642D03*
X190460Y228221D03*
Y231021D03*
X191845Y221708D03*
X188760Y224421D03*
X189345Y221708D03*
X191011Y236189D03*
X193511D03*
X196011D03*
X190952Y248765D03*
X193452D03*
X195952D03*
X183128Y256303D03*
X187903Y266114D03*
X196449Y268195D03*
X193649D03*
X196449Y270695D03*
X193649D03*
X191149D03*
Y268195D03*
X185376Y281982D03*
X185328Y545528D03*
X194063Y577716D03*
X191125Y610400D03*
X203248Y55513D03*
X199473Y68581D03*
X205848Y60513D03*
X208645Y60369D03*
X199486Y80581D03*
X214389Y86012D03*
X203616Y88801D03*
X214389Y94374D03*
X206533Y94351D03*
X210482Y94279D03*
X209530Y86046D03*
X205976Y85731D03*
X209726Y116594D03*
X201669Y103621D03*
X215669Y110784D03*
X209726Y119594D03*
X210160Y124283D03*
X215226Y124879D03*
X208567Y161306D03*
X200323Y152562D03*
X205818Y157370D03*
X209902Y176665D03*
Y168665D03*
X202001Y186629D03*
X209902Y196665D03*
Y192665D03*
X210015Y186778D03*
X209934Y204864D03*
Y208864D03*
X214983Y218085D03*
X205575Y219379D03*
X206203Y228631D03*
X211691Y248371D03*
X200109Y265897D03*
X202609D03*
X212980Y390995D03*
X204675Y382109D03*
X212980Y405168D03*
Y394395D03*
X205680Y401482D03*
Y398082D03*
X212980Y408568D03*
Y419341D03*
Y422741D03*
X205680Y415655D03*
Y412255D03*
Y426428D03*
Y440602D03*
Y429828D03*
X212980Y433515D03*
Y436915D03*
X205680Y444002D03*
X212980Y469381D03*
Y472781D03*
X205680Y490641D03*
Y479868D03*
X212980Y483554D03*
X205680Y476468D03*
X212980Y486954D03*
X205680Y494041D03*
Y524002D03*
X212980Y516915D03*
Y513515D03*
X205680Y520602D03*
Y534775D03*
X212980Y527688D03*
X205680Y538175D03*
X212980Y531088D03*
X204674Y551683D03*
Y558917D03*
Y561420D03*
X200495Y577937D03*
X208500Y595500D03*
X203500Y606929D03*
X208000Y604567D03*
X203460Y618400D03*
X203741Y612592D03*
X209158Y610072D03*
X209094Y616317D03*
X208540Y621591D03*
X205941Y668934D03*
X201115Y695581D03*
X203046Y693716D03*
X213969Y1447453D03*
Y1461853D03*
Y1458453D03*
Y1450853D03*
X231312Y97667D03*
X221695Y116594D03*
X226968Y102495D03*
X220669Y110784D03*
X221695Y119594D03*
X225229Y125107D03*
X220248Y124663D03*
X226702Y142862D03*
X227743Y148717D03*
X221592Y138838D03*
X230291Y195176D03*
X230372Y210509D03*
X224362Y226320D03*
X224296Y216970D03*
Y219470D03*
Y221970D03*
X221583Y216385D03*
X217783Y218085D03*
X232064Y230556D03*
X227323Y228646D03*
X231049Y242078D03*
X226280Y232971D03*
X220310Y249108D03*
X222930Y244571D03*
X233417Y253198D03*
X230842Y313888D03*
X233258Y359186D03*
X228267Y396718D03*
X221375Y455024D03*
X220349Y465622D03*
X225500Y530000D03*
X225000Y540500D03*
X224000Y547075D03*
X224200Y549800D03*
X223500Y568000D03*
X224104Y562800D03*
X224040Y558800D03*
X221693Y594982D03*
X222289Y590895D03*
X220333Y617930D03*
X220255Y629749D03*
X217906Y1430452D03*
Y1427052D03*
X219525Y1440028D03*
X216125D03*
X227249Y1447453D03*
Y1450853D03*
Y1458453D03*
Y1461853D03*
X224780Y1478149D03*
X217985Y1483055D03*
X225765Y1471985D03*
X233313Y1476699D03*
X221899Y1488800D03*
X218021Y1494724D03*
X222843Y1498442D03*
X217614Y1489671D03*
X233180Y1486442D03*
X233166Y1491454D03*
X226135Y1502442D03*
X230758Y1505046D03*
X226971Y1514578D03*
X227552Y1530675D03*
X232622Y1531104D03*
X226971Y1522578D03*
X219981Y1530797D03*
X223322Y1518578D03*
X222119Y1539941D03*
X227882Y1540816D03*
X233753Y1539752D03*
X239772Y103411D03*
X240166Y97667D03*
X235562Y95111D03*
X240412Y114655D03*
Y111255D03*
X239931Y106561D03*
X233112Y132515D03*
Y121742D03*
X240412Y125428D03*
X233112Y118342D03*
X240412Y128828D03*
X233112Y135915D03*
X233843Y143762D03*
X232791Y195176D03*
X235291D03*
X237309Y199248D03*
X234309D03*
X237791Y195176D03*
X237309Y202048D03*
X232872Y210509D03*
X234645Y206806D03*
X232145D03*
X234309Y201748D03*
X240909Y230117D03*
X236319Y227824D03*
X236925Y238714D03*
X236406Y246874D03*
X238626Y244297D03*
X234986Y336161D03*
X236264Y342494D03*
X245362Y546712D03*
Y542712D03*
X247536Y602689D03*
X247278Y618288D03*
X243278D03*
X240194Y643113D03*
X242102Y656321D03*
X250102D03*
X246102D03*
X245000Y678462D03*
X244267Y696911D03*
X235790Y754332D03*
X241204Y814841D03*
X237591Y815266D03*
X248556Y824003D03*
X246311Y819000D03*
X238400Y836900D03*
X234976Y1481676D03*
X243535Y1511473D03*
X245500Y1517033D03*
X237633Y1511909D03*
X244600Y1531700D03*
X240808Y1519942D03*
X235687Y1522578D03*
X237580Y1528604D03*
X245937Y1524237D03*
X239949Y1541327D03*
X244912Y1539389D03*
X250962Y90650D03*
X256274Y90615D03*
X260595Y99961D03*
X260645Y95236D03*
X250712D03*
X259457Y210478D03*
Y207978D03*
Y215478D03*
Y212978D03*
X262786Y264180D03*
X262711Y258880D03*
X257993Y307994D03*
X256475Y422088D03*
X252695Y442956D03*
X254512Y438323D03*
X261965Y458455D03*
X250336Y456386D03*
X254678Y445873D03*
X263301Y444232D03*
X262526Y451108D03*
X249125Y465874D03*
X264005Y467337D03*
Y470737D03*
X256705Y474424D03*
X264005Y484910D03*
X256705Y488597D03*
X264005Y481510D03*
X256705Y477824D03*
Y491997D03*
X264005Y514871D03*
X256705Y518558D03*
X264005Y511471D03*
X256705Y521958D03*
Y532731D03*
Y536131D03*
X264005Y525644D03*
Y529044D03*
Y561510D03*
X256705Y571997D03*
Y568597D03*
X264005Y564910D03*
X256705Y586171D03*
X264005Y575684D03*
Y579084D03*
X256705Y582771D03*
X264005Y589857D03*
X256705Y600344D03*
X264005Y593257D03*
Y604030D03*
X256705Y596944D03*
Y611117D03*
Y614517D03*
X264005Y607430D03*
X252688Y636364D03*
X248690Y678519D03*
X248090Y691114D03*
X254634Y698241D03*
X248506Y812042D03*
X256303Y812254D03*
X250700Y819900D03*
X254058Y819851D03*
X255289Y824340D03*
X252305Y831018D03*
X252100Y836800D03*
X250876Y1532782D03*
X255909Y1542043D03*
X250790Y1539759D03*
X269509Y77393D03*
Y74793D03*
Y85193D03*
Y82593D03*
Y79993D03*
X277834Y98551D03*
X269553Y92874D03*
X271580Y107649D03*
Y104249D03*
X276146Y147540D03*
X279918Y141247D03*
X268602Y162368D03*
X271202D03*
X278302Y162793D03*
Y165393D03*
Y167993D03*
Y170493D03*
X277299Y181426D03*
X280124Y184012D03*
X277507Y184221D03*
X269913Y210713D03*
X273985Y208695D03*
X276785D03*
X273985Y211695D03*
X276485D03*
X269913Y208213D03*
Y213213D03*
Y215713D03*
X265286Y264180D03*
X280162Y265701D03*
X276980Y267526D03*
Y270026D03*
X271680Y267526D03*
X274480D03*
Y270026D03*
X271680D03*
X281797Y281716D03*
X277575Y395084D03*
X274425Y381500D03*
X278784Y435158D03*
X278529Y440489D03*
X274949Y442606D03*
X278827Y444841D03*
X282230Y458572D03*
X265011Y453881D03*
X280220Y448493D03*
X274866Y446606D03*
X265011Y446595D03*
X275873Y463479D03*
X276344Y467367D03*
X274096Y820725D03*
X274697Y830951D03*
X275123Y847874D03*
X269700Y853100D03*
X275400Y864400D03*
X278400Y890839D03*
X275400Y899400D03*
X279261Y926339D03*
X278739Y936439D03*
X289797Y36735D03*
X290113Y23188D03*
X284666Y34068D03*
X289631Y28281D03*
X293930Y76587D03*
Y72615D03*
X295369Y100625D03*
X288388Y97475D03*
X280729Y111223D03*
Y114623D03*
X281384Y103783D03*
X288319Y106186D03*
X280729Y125396D03*
X291131Y121735D03*
X280729Y128796D03*
X291131Y118335D03*
Y132509D03*
Y135909D03*
X295948Y141247D03*
X287385Y143740D03*
X284765Y148277D03*
X285807Y172190D03*
X280510Y181366D03*
X283305Y181009D03*
X288480Y168697D03*
X285226Y177616D03*
X289568Y191941D03*
X297622Y192490D03*
X291577Y206767D03*
X294077D03*
X296577D03*
X285246Y213132D03*
X281543Y211359D03*
Y213859D03*
X296707Y221708D03*
X292822Y228221D03*
Y231021D03*
X294207Y221708D03*
X291122Y224421D03*
X291707Y221708D03*
X285246Y215632D03*
X293373Y236189D03*
X295873D03*
X293314Y248765D03*
X295814D03*
X285490Y256303D03*
X290265Y266114D03*
X285249Y265896D03*
X296011Y270695D03*
X293511D03*
Y268195D03*
X296011D03*
X287738Y281982D03*
X286940Y315039D03*
X297719Y339559D03*
X291396Y350223D03*
X292520Y384410D03*
X292358Y393858D03*
X298000Y391496D03*
X295699Y382047D03*
X296000Y403500D03*
X298000Y409000D03*
X294000Y398583D03*
X295253Y440869D03*
Y438269D03*
X292453D03*
Y440869D03*
Y435669D03*
Y430469D03*
Y433069D03*
X295253D03*
Y430469D03*
Y435669D03*
X293307Y451677D03*
X295807D03*
X293307Y454177D03*
X295807D03*
X295011Y460218D03*
Y463618D03*
X281980Y953926D03*
X312256Y37543D03*
X305610Y55513D03*
X301835Y68581D03*
X310817Y60393D03*
X307916Y60529D03*
X301848Y80581D03*
X305978Y88801D03*
X312844Y94279D03*
X308895Y94351D03*
X308338Y85731D03*
X311892Y86046D03*
X312088Y116594D03*
X299742Y112083D03*
X304031Y103621D03*
X312088Y119594D03*
X312522Y124283D03*
X300435Y143518D03*
X299535Y152373D03*
X310929Y161306D03*
X302685Y152562D03*
X308180Y157370D03*
X312264Y176665D03*
Y168665D03*
X303377Y183834D03*
X303550Y172665D03*
X303487Y178560D03*
X304363Y186629D03*
X302897Y190185D03*
X312264Y196665D03*
Y192665D03*
X303667Y200864D03*
X312377Y186778D03*
X300814Y192859D03*
X312296Y204864D03*
Y208864D03*
X303756Y212455D03*
X303690Y207037D03*
X301057Y221642D03*
X307937Y219379D03*
X308565Y228631D03*
X298373Y236189D03*
X298314Y248765D03*
X302471Y265897D03*
X304971D03*
X298811Y270695D03*
Y268195D03*
X315079Y314890D03*
X312263Y324518D03*
X301943Y328867D03*
X308952Y356875D03*
X312316Y356747D03*
X299000Y377912D03*
Y386500D03*
X299088Y397912D03*
X322847Y19806D03*
X321840Y14408D03*
X322113Y26187D03*
X316751Y86012D03*
Y94374D03*
X324057Y116594D03*
X318031Y110784D03*
X323031D03*
X324057Y119594D03*
X327591Y125107D03*
X322610Y124663D03*
X317588Y124879D03*
X329064Y142862D03*
X330105Y148717D03*
X323954Y138838D03*
X317345Y218085D03*
X320145D03*
X323945Y216385D03*
X326658Y216970D03*
Y219470D03*
X326724Y226320D03*
X326658Y221970D03*
X329685Y228646D03*
X328642Y232971D03*
X322672Y249108D03*
X325292Y244571D03*
X314053Y248371D03*
X327032Y303962D03*
X314855Y311740D03*
X318508Y324322D03*
X315944Y332584D03*
X316067Y347937D03*
X321416Y348015D03*
X317333Y353470D03*
X318500Y356519D03*
X315310Y356712D03*
X320993Y467306D03*
Y470706D03*
Y481479D03*
Y484879D03*
Y514839D03*
Y511439D03*
Y525613D03*
Y529013D03*
X318660Y539315D03*
X320785Y553287D03*
X327456Y550065D03*
X320993Y564879D03*
Y561479D03*
Y575652D03*
Y579052D03*
Y603999D03*
Y593225D03*
Y589825D03*
Y607399D03*
X321119Y622912D03*
X330905Y15806D03*
Y19806D03*
Y27806D03*
X333674Y97667D03*
X342134Y103411D03*
X342528Y97667D03*
X337924Y95111D03*
X342774Y111255D03*
Y114655D03*
X329330Y102495D03*
X342293Y106561D03*
X335474Y118342D03*
Y132515D03*
X342774Y125428D03*
X335474Y121742D03*
X342774Y128828D03*
X335474Y135915D03*
X336205Y143762D03*
X335153Y195176D03*
X332653D03*
X336671Y199248D03*
X337653Y195176D03*
X340153D03*
X339671Y199248D03*
X336671Y201748D03*
X334507Y206806D03*
X337007D03*
X335234Y210509D03*
X332734D03*
X339671Y202048D03*
X343271Y230117D03*
X338681Y227824D03*
X334426Y230556D03*
X339287Y238714D03*
X333411Y242078D03*
X338768Y246874D03*
X340988Y244297D03*
X332635Y256394D03*
X347058Y399918D03*
X339072Y416888D03*
Y419488D03*
Y422088D03*
X345050Y454334D03*
X331395Y474418D03*
Y488591D03*
Y477818D03*
Y491991D03*
Y518552D03*
Y521952D03*
Y536125D03*
Y532725D03*
X337078Y551381D03*
X335399Y544718D03*
X331395Y568591D03*
Y571991D03*
Y586165D03*
Y582765D03*
Y600338D03*
Y596938D03*
Y611111D03*
Y614511D03*
X333985Y1017945D03*
X341077Y1018056D03*
X339251Y1138130D03*
X336755Y1143489D03*
X340500Y1147500D03*
X335190Y1173065D03*
X341266Y1171956D03*
X330800Y1174500D03*
X343121Y1188412D03*
X342009Y1176100D03*
X339776Y1187962D03*
X335502Y1188222D03*
X339540Y1196894D03*
X358636Y90615D03*
X353324Y90650D03*
X362957Y99961D03*
X353074Y95236D03*
X359376Y290592D03*
X348351Y319372D03*
X348806Y315427D03*
X351132Y322202D03*
X349120Y336100D03*
X351136Y372334D03*
X350486Y377173D03*
X358491D03*
X347591Y391533D03*
X359486Y385123D03*
X349311Y385644D03*
X354486Y385123D03*
X357655Y405889D03*
Y408489D03*
X358248Y403300D03*
X353894Y406060D03*
X354155Y421489D03*
Y418889D03*
Y416289D03*
X350163Y412106D03*
X357655Y413689D03*
Y416289D03*
Y421489D03*
Y418889D03*
Y424089D03*
Y411089D03*
X358042Y432718D03*
X357655Y426689D03*
X358042Y435518D03*
X358754Y450091D03*
X356241Y447001D03*
X359241D03*
X353320Y454214D03*
X353663Y449045D03*
X353367Y459330D03*
X358754Y462060D03*
X353670Y473571D03*
Y481071D03*
Y478571D03*
Y476071D03*
X360242Y477053D03*
X357742D03*
X358207Y836462D03*
X346366Y1134729D03*
X361621D03*
X349748D03*
X357748D03*
X353748D03*
X352545Y1142666D03*
X360877Y1157404D03*
X354420Y1157544D03*
X352931Y1167768D03*
X357950D03*
X357057Y1179542D03*
X357796Y1188058D03*
X357083Y1185205D03*
X361792Y1187310D03*
X348432Y1187215D03*
X348125Y1180175D03*
X358368Y1201043D03*
X354398D03*
X350402D03*
X346387Y1199256D03*
X360523Y1192282D03*
X349276Y1217228D03*
X351940Y1219895D03*
X362332Y1230265D03*
X355215Y1223170D03*
X360273Y1228226D03*
X358062Y1226016D03*
X371871Y85193D03*
Y82593D03*
Y79993D03*
Y77393D03*
Y74793D03*
X371915Y92874D03*
X363007Y95236D03*
X373942Y104249D03*
Y107649D03*
X370964Y162368D03*
X373564D03*
X372275Y208213D03*
X379147Y208695D03*
X376347D03*
Y211695D03*
X372275Y210713D03*
Y213213D03*
X361819Y207978D03*
Y212978D03*
Y215478D03*
Y210478D03*
X372275Y215713D03*
X367648Y264180D03*
X365148D03*
X365073Y258880D03*
X374042Y270026D03*
X376842D03*
X374042Y267526D03*
X376842D03*
X371417Y353820D03*
X365559Y354300D03*
X377237Y371060D03*
X373264Y379429D03*
X378875Y379088D03*
X366526Y377173D03*
X370486D03*
X362486Y385123D03*
X366486D03*
X370160Y391569D03*
X368587Y401066D03*
X378927Y406739D03*
X367919Y439318D03*
X375919Y442118D03*
Y439318D03*
X367919Y442118D03*
X361754Y450091D03*
X367564Y456034D03*
Y461034D03*
X373546Y470001D03*
X376046D03*
X361754Y462060D03*
X373971Y489036D03*
X371832Y485580D03*
X374332D03*
X376832D03*
X366420Y479986D03*
Y477486D03*
X363686Y478668D03*
Y476168D03*
X376207Y492836D03*
Y495636D03*
X376881Y518564D03*
X363015Y710365D03*
X365887Y710329D03*
X372400Y746300D03*
X372300Y750000D03*
X373500Y767300D03*
X376300D03*
X370415Y766108D03*
X373703Y782555D03*
X365850Y773950D03*
X371436Y791188D03*
X365691Y815127D03*
X371507Y815303D03*
X362042Y814772D03*
X368067Y925136D03*
X370214Y943812D03*
X368626Y931346D03*
X368964Y937738D03*
X372858Y935136D03*
X366761Y934550D03*
X363893Y946863D03*
X379928Y949774D03*
X379245Y956643D03*
X378875Y961862D03*
X370214Y947812D03*
X370101Y953699D03*
X370214Y963812D03*
Y971812D03*
X378928Y967812D03*
X372501Y1123695D03*
X365748Y1134325D03*
X368657Y1150087D03*
X366133Y1170767D03*
X366429Y1185238D03*
X366222Y1180235D03*
X362402Y1201039D03*
X366402Y1200969D03*
X366521Y1208993D03*
X370202Y1314764D03*
Y1311364D03*
X383612Y33768D03*
X388612Y31168D03*
X387948Y27288D03*
X380196Y98551D03*
X390750Y97475D03*
X383091Y111223D03*
Y114623D03*
X383746Y103783D03*
X390681Y106186D03*
X393493Y118335D03*
X383091Y125396D03*
Y128796D03*
X393493Y132509D03*
Y121735D03*
Y135909D03*
X380664Y165393D03*
Y162793D03*
Y167993D03*
Y170493D03*
X387588Y177616D03*
X382872Y181366D03*
X379661Y181426D03*
X385667Y181009D03*
X390842Y168697D03*
X388169Y172190D03*
X391930Y191941D03*
X382486Y184012D03*
X379869Y184221D03*
X393939Y206767D03*
X383905Y211359D03*
X387608Y213132D03*
X378847Y211695D03*
X383905Y213859D03*
X394069Y221708D03*
X393484Y224421D03*
X387608Y215632D03*
X387852Y256303D03*
X387611Y265896D03*
X382524Y265701D03*
X392627Y266114D03*
X379342Y270026D03*
Y267526D03*
X384159Y281716D03*
X390100Y281982D03*
X391737Y377581D03*
X384173Y379028D03*
X381237Y371076D03*
X394237Y379591D03*
X391940Y383817D03*
Y388817D03*
Y386317D03*
X385864Y398278D03*
X383364D03*
X378927Y409539D03*
X381927D03*
Y407039D03*
X381591Y401981D03*
X384091D03*
X378210Y424067D03*
X380710D03*
X385710D03*
X383210D03*
X378445Y413611D03*
X380945D03*
X385945D03*
X383445D03*
X385584Y438293D03*
Y441093D03*
Y443893D03*
X393646Y474382D03*
X385634Y472020D03*
X393662Y470382D03*
X385694Y477318D03*
X385293Y466409D03*
X387141Y484882D03*
X385131Y487382D03*
X391470Y732865D03*
X380963Y731000D03*
X381875Y740341D03*
X379800Y769200D03*
X380331Y782627D03*
X380607Y786932D03*
X392415Y792725D03*
X389015D03*
X387958Y813700D03*
X381631Y814147D03*
X384666Y814103D03*
X383391Y804000D03*
X386589Y864408D03*
X383462Y860535D03*
X392584Y875845D03*
X382675Y870151D03*
X391614Y930676D03*
X384856Y947987D03*
X378119Y953696D03*
X392910Y948536D03*
X393998Y971780D03*
X378790Y1001083D03*
X380280Y1006071D03*
X383710Y1007283D03*
X382465Y1012430D03*
X378410Y1131573D03*
X380261Y1129692D03*
X385091Y1297453D03*
Y1300853D03*
X386415Y1321645D03*
X391691Y1326715D03*
X392234Y1369579D03*
Y1364501D03*
X391757Y1383480D03*
X391852Y1389931D03*
X393951Y1447455D03*
X381900Y1544800D03*
X389700Y1536900D03*
X391740Y1545629D03*
Y1540529D03*
X382017Y1559700D03*
X395296Y1561024D03*
X391740Y1550729D03*
Y1555829D03*
X410789Y22627D03*
X408680Y37530D03*
X396680Y37543D03*
X400714Y45448D03*
X404686D03*
X397731Y100625D03*
X402104Y112083D03*
X406393Y103621D03*
X405912Y172665D03*
X405739Y183834D03*
X405849Y178560D03*
X406725Y186629D03*
X399984Y192490D03*
X405259Y190185D03*
X406029Y200864D03*
X395942Y192300D03*
X398939Y206767D03*
X396439D03*
X406118Y212455D03*
X406052Y207037D03*
X395184Y228221D03*
X399069Y221708D03*
X396569D03*
X403419Y221642D03*
X395184Y231021D03*
X410299Y219379D03*
X410927Y228631D03*
X400735Y236189D03*
X398235D03*
X395735D03*
X400676Y248765D03*
X398176D03*
X395676D03*
X407333Y265897D03*
X404833D03*
X401173Y268195D03*
Y270695D03*
X398373Y268195D03*
X395873D03*
Y270695D03*
X398373D03*
X405843Y315158D03*
X403343D03*
X394883Y341777D03*
Y338377D03*
X410086Y336795D03*
X409655Y331589D03*
X410688Y344736D03*
X400993Y331589D03*
Y335589D03*
X400728Y353152D03*
X411007Y356743D03*
X406421Y387151D03*
Y382151D03*
Y384651D03*
X398453Y387702D03*
X401253D03*
X394653Y389402D03*
X395577Y438293D03*
Y441093D03*
Y443893D03*
X397315Y471560D03*
X405801Y475560D03*
X405301Y467560D03*
X397315Y475560D03*
X406200Y741300D03*
X397223Y796792D03*
X400023D03*
X397900Y789000D03*
X407000Y784700D03*
X404468Y864407D03*
X396306Y864409D03*
X406770Y869767D03*
X405466Y881299D03*
X397431Y870654D03*
X401108Y878487D03*
X401121Y929686D03*
X409121D03*
X401121Y932186D03*
X409121D03*
X405179Y959051D03*
X404971Y956256D03*
X402354Y956465D03*
X401968Y959111D03*
X399173Y959468D03*
X397252Y962861D03*
X404176Y977684D03*
Y975084D03*
Y969984D03*
Y972484D03*
X396671Y968287D03*
X406954Y982970D03*
X409554D03*
X404354D03*
X407547Y1058097D03*
X410047D03*
X405047D03*
X407547Y1060697D03*
X410047D03*
X405047D03*
X408989Y1082501D03*
X409015Y1087705D03*
Y1085205D03*
X408847Y1090956D03*
Y1093956D03*
X406895Y1107997D03*
X402695D03*
Y1110897D03*
X407780Y1113648D03*
X409231Y1118801D03*
X406995Y1110597D03*
X404895Y1112397D03*
X404795Y1109397D03*
X402695Y1113797D03*
X408961Y1162384D03*
Y1164884D03*
Y1167384D03*
Y1169884D03*
Y1172384D03*
X403263Y1160834D03*
X408961Y1174884D03*
X406319Y1186709D03*
Y1184209D03*
Y1181709D03*
Y1179209D03*
X404004Y1192621D03*
Y1190121D03*
X397063Y1221428D03*
X401063D03*
X405063D03*
X409063D03*
X397063Y1233428D03*
Y1229428D03*
Y1225428D03*
X401063Y1237428D03*
Y1233428D03*
Y1229428D03*
Y1225428D03*
X405063Y1237428D03*
Y1233428D03*
Y1229428D03*
Y1225428D03*
X409063Y1237428D03*
Y1233428D03*
Y1229428D03*
Y1225428D03*
X401063Y1241428D03*
X405063Y1245428D03*
Y1241428D03*
X409063Y1245428D03*
Y1241428D03*
X404324Y1271889D03*
Y1275889D03*
X407767Y1292198D03*
X403678Y1295426D03*
X398584Y1313443D03*
X401011Y1307258D03*
X402967Y1319815D03*
X409220Y1315516D03*
X404583Y1316131D03*
X404921Y1321819D03*
X408787Y1321795D03*
X399959Y1352153D03*
X408159Y1349072D03*
X404759D03*
X395112Y1395690D03*
X398340Y1399779D03*
X395770Y1389817D03*
X410172Y1402446D03*
X402489Y1417275D03*
X405889D03*
X407970Y1449751D03*
X404500Y1452500D03*
X395888Y1450022D03*
X395199Y1482223D03*
X395380Y1485778D03*
X397266Y1514647D03*
X398747Y1500959D03*
X395370Y1501022D03*
X397266Y1518047D03*
X408964Y1531149D03*
X394391Y1537786D03*
Y1535286D03*
X399373Y1555855D03*
X405496Y1561024D03*
X400396D03*
X410596D03*
X397461Y1569560D03*
X401461D03*
X416900Y33400D03*
X422473Y22627D03*
X422450Y30483D03*
X422378Y26534D03*
X414145Y27486D03*
X413904Y32569D03*
X426147Y147540D03*
X414626Y176665D03*
Y168665D03*
Y196665D03*
Y192665D03*
X414739Y186778D03*
X414658Y204864D03*
Y208864D03*
X423651Y307470D03*
X419177Y304470D03*
X415777D03*
X422988Y323627D03*
X415129Y325181D03*
X412671Y333418D03*
X412812Y330617D03*
X426830Y359026D03*
X426138Y355079D03*
X416574Y357528D03*
X421413Y359053D03*
X412318Y367903D03*
X420422Y367859D03*
X418997Y382210D03*
Y384710D03*
Y387210D03*
X422215Y424939D03*
Y427439D03*
X414924Y435321D03*
Y438121D03*
X412124Y435321D03*
Y438121D03*
X414924Y440921D03*
X412124D03*
X414924Y443721D03*
X412124D03*
X426647Y452987D03*
X421267Y452799D03*
X414910Y448931D03*
X415433Y459170D03*
X425673Y461607D03*
X424876Y471334D03*
X418801Y474513D03*
X414275Y492469D03*
X424731Y492704D03*
X414275Y497469D03*
Y499969D03*
X427693Y498943D03*
X424731Y497704D03*
Y495204D03*
Y500204D03*
X414275Y494969D03*
X419340Y549990D03*
X419140Y547390D03*
Y544790D03*
X419340Y552590D03*
Y555190D03*
X423963Y625778D03*
X426607Y712360D03*
Y709760D03*
X424993Y728291D03*
X423700Y795500D03*
X426300Y797400D03*
X421200Y786400D03*
X411267Y829193D03*
Y831693D03*
X416267D03*
X413767D03*
Y829193D03*
X416267D03*
X425062Y883981D03*
X417121Y929686D03*
X425121D03*
X417121Y932186D03*
X425121D03*
X411960Y962261D03*
X414560D03*
X417160D03*
X411276Y978109D03*
X416476D03*
X413876D03*
X415047Y1058097D03*
X412547D03*
X415047Y1060697D03*
X412547D03*
X411989Y1082501D03*
X412015Y1085205D03*
X414989Y1082501D03*
X415015Y1085205D03*
Y1088205D03*
X412015D03*
X412297Y1091227D03*
X425060Y1101917D03*
X420782Y1105552D03*
X423340Y1104335D03*
X424995Y1106897D03*
X416988Y1104792D03*
X418495Y1106867D03*
X414580Y1113648D03*
X412080D03*
X411461Y1162384D03*
Y1164884D03*
Y1167384D03*
Y1169884D03*
Y1172384D03*
X420619Y1179421D03*
Y1181921D03*
Y1184421D03*
Y1186921D03*
X411461Y1174884D03*
X422934Y1192621D03*
Y1190121D03*
X417469Y1192621D03*
Y1190121D03*
X413063Y1221428D03*
X417063D03*
X421063D03*
X425063D03*
X413063Y1237428D03*
Y1233428D03*
Y1229428D03*
Y1225428D03*
X417063Y1237428D03*
Y1233428D03*
Y1229428D03*
Y1225428D03*
X421063Y1237428D03*
Y1233428D03*
Y1229428D03*
Y1225428D03*
X425063Y1237428D03*
Y1233428D03*
Y1229428D03*
Y1225428D03*
X413063Y1245428D03*
Y1241428D03*
X417063Y1245428D03*
Y1241428D03*
X421063Y1245428D03*
Y1241428D03*
X425063Y1245428D03*
Y1241428D03*
X425702Y1257160D03*
X422702Y1260160D03*
Y1257160D03*
X425702Y1260160D03*
X419702Y1257160D03*
Y1260160D03*
X413526Y1288938D03*
X419977Y1288843D03*
X413640Y1292856D03*
X419545Y1317722D03*
X413127Y1318011D03*
X425283Y1364023D03*
X417305Y1359169D03*
X425855Y1360495D03*
X425912Y1357141D03*
X416029Y1371572D03*
X420636Y1383912D03*
X418610Y1371590D03*
X423400Y1394500D03*
X423200Y1397500D03*
X418430Y1394237D03*
X422729Y1400490D03*
X420925Y1390330D03*
X419045Y1398874D03*
X421300Y1415400D03*
X419100Y1402200D03*
X421200Y1417900D03*
X411000Y1463500D03*
Y1460500D03*
Y1457500D03*
Y1454500D03*
Y1451000D03*
X413934Y1477101D03*
X417334D03*
X415202Y1496118D03*
Y1499518D03*
X417153Y1516886D03*
X413753D03*
X419619Y1539978D03*
X421454Y1544625D03*
X422539Y1534361D03*
X426701Y1541947D03*
X418151Y1552470D03*
X417461Y1569584D03*
X429919Y141247D03*
X437386Y143740D03*
X434766Y148277D03*
X431525Y304470D03*
X434925D03*
X427051Y307470D03*
X441296Y325061D03*
X436666Y322583D03*
X427713Y321965D03*
X430361Y323187D03*
X443424Y332988D03*
X440538Y355372D03*
X428420Y353578D03*
X435886Y353867D03*
X431524Y370309D03*
X434924D03*
X428637Y408104D03*
X431437D03*
X434237D03*
X428354Y420375D03*
X431154D03*
X433954D03*
X438098Y442114D03*
X437835Y435101D03*
X432270Y431112D03*
X432440Y440101D03*
X432075Y452718D03*
X438086Y452601D03*
X438078Y447121D03*
X433673Y461607D03*
X429673D03*
X435789Y501525D03*
X427568Y502003D03*
X435831Y498923D03*
X438644Y500461D03*
X428740Y549990D03*
X442804Y546990D03*
Y544390D03*
X428740Y546990D03*
Y544390D03*
Y555190D03*
Y552590D03*
X431384D03*
Y555190D03*
Y544390D03*
Y546990D03*
Y549990D03*
X443144Y628667D03*
X441162Y638313D03*
X439290Y712399D03*
X436790D03*
X439290Y709799D03*
X436790D03*
X434290Y712399D03*
Y709799D03*
X429290D03*
X431790Y712399D03*
X429290D03*
X431790Y709799D03*
X429253Y759847D03*
X432303Y785067D03*
X434100Y797400D03*
X430600D03*
X443091Y1026266D03*
X432678Y1016186D03*
X429878D03*
X427078D03*
X427052Y1019384D03*
X429852D03*
X432652D03*
X433378Y1091816D03*
Y1089316D03*
X430878Y1084316D03*
Y1086816D03*
X433378D03*
Y1084316D03*
X436244Y1090288D03*
X433378Y1081816D03*
X430878D03*
X429677Y1106955D03*
X439023Y1107997D03*
X436244Y1093088D03*
X434823Y1107997D03*
X431476Y1115896D03*
X427810Y1110092D03*
X439908Y1113648D03*
X441359Y1116101D03*
Y1118801D03*
X439123Y1110597D03*
X434823Y1113797D03*
Y1110897D03*
X437023Y1112397D03*
X436923Y1109397D03*
X431476Y1118396D03*
X429348Y1129092D03*
X432838Y1128821D03*
X436789Y1167384D03*
Y1164884D03*
Y1162384D03*
Y1172384D03*
Y1169884D03*
X439289Y1167384D03*
Y1164884D03*
Y1162384D03*
X427231D03*
X429731D03*
Y1164884D03*
Y1167384D03*
Y1169884D03*
Y1172384D03*
X427231D03*
Y1169884D03*
Y1167384D03*
Y1164884D03*
X439289Y1172384D03*
Y1169884D03*
X437132Y1158266D03*
X433249Y1186709D03*
Y1184209D03*
Y1181709D03*
Y1179209D03*
X429731Y1174884D03*
X427231D03*
X436789D03*
X439289D03*
X430934Y1190121D03*
Y1192621D03*
X429063Y1221428D03*
X433063D03*
X429063Y1237428D03*
Y1233428D03*
Y1229428D03*
Y1225428D03*
X433063Y1237428D03*
Y1233428D03*
Y1229428D03*
Y1225428D03*
X429063Y1245428D03*
Y1241428D03*
X433063Y1245428D03*
Y1241428D03*
X440702Y1260160D03*
Y1257160D03*
X437702Y1260160D03*
Y1257160D03*
X428702D03*
X431702Y1260160D03*
Y1257160D03*
X434702Y1260160D03*
Y1257160D03*
X428702Y1260160D03*
X434424Y1286274D03*
X430527Y1289198D03*
X440906D03*
X431867Y1315696D03*
X431885Y1313115D03*
X439434Y1322369D03*
X429530Y1325051D03*
X445949Y141247D03*
X450436Y143518D03*
X449536Y152373D03*
X452686Y152562D03*
X458181Y157370D03*
X443508Y337713D03*
X446566Y337917D03*
X443480Y344014D03*
X450852Y372054D03*
X455885Y367702D03*
X448391Y382641D03*
X448323Y379643D03*
X451144Y468809D03*
X459414Y468689D03*
X459757Y463520D03*
X459461Y473805D03*
X459929Y491669D03*
X450942Y506449D03*
X448442D03*
X445942D03*
X460537Y501905D03*
X459952Y496842D03*
X459645Y509486D03*
X446025Y511512D03*
X448525D03*
X446025Y519699D03*
X448525D03*
X452404Y549790D03*
X443004Y549890D03*
X452404Y546990D03*
Y544390D03*
X443004Y555090D03*
X452404Y552390D03*
Y554990D03*
X443004Y552490D03*
X455009Y554912D03*
Y552312D03*
Y544312D03*
Y546912D03*
Y549712D03*
X447279Y637031D03*
X447921Y630789D03*
X453552Y631779D03*
X446987Y643360D03*
X456469Y638302D03*
X460498Y870334D03*
X458120Y974701D03*
X451460Y974695D03*
X450591Y1004766D03*
X453270Y1003763D03*
X459360Y1012325D03*
X443591Y1019766D03*
X459885Y1018860D03*
X451140Y1021793D03*
X447091Y1019766D03*
X450875Y1028416D03*
X443091Y1034266D03*
X452091Y1039880D03*
X459700Y1032266D03*
X455468Y1104335D03*
X457188Y1101917D03*
X452910Y1105552D03*
X457123Y1106897D03*
X449116Y1104792D03*
X450623Y1106867D03*
X444208Y1113648D03*
X446708D03*
X457559Y1169884D03*
Y1167384D03*
Y1164884D03*
Y1162384D03*
X455059D03*
Y1164884D03*
Y1167384D03*
Y1169884D03*
Y1172384D03*
X457559D03*
X455059Y1174884D03*
X457559D03*
X447549Y1179421D03*
Y1181921D03*
Y1184421D03*
Y1186921D03*
X449864Y1190121D03*
Y1192621D03*
X449702Y1260160D03*
Y1257160D03*
X443702Y1260160D03*
X446702D03*
Y1257160D03*
X443702D03*
X451304Y1297045D03*
X454385Y1301845D03*
Y1305245D03*
X444288Y1314391D03*
X462089Y116594D03*
X474058D03*
X473032Y110784D03*
X468032D03*
X462089Y119594D03*
X474058D03*
X477592Y125107D03*
X462523Y124283D03*
X467589Y124879D03*
X472611Y124663D03*
X473955Y138838D03*
X460930Y161306D03*
X467346Y218085D03*
X470146D03*
X473946Y216385D03*
X475293Y244571D03*
X472673Y249108D03*
X464054Y248371D03*
X460950Y328185D03*
Y324785D03*
X463950Y332659D03*
Y336059D03*
X460950Y343933D03*
Y340533D03*
X472810Y347995D03*
X472913Y360089D03*
X472608Y352495D03*
X467335Y359944D03*
X463950Y351807D03*
Y348407D03*
X472913Y369089D03*
Y373589D03*
X469530Y366754D03*
X472913Y387089D03*
Y391589D03*
Y382589D03*
Y378089D03*
X470796Y394592D03*
X464848Y464566D03*
X467848D03*
X465126Y460435D03*
X462126D03*
X473658Y470509D03*
Y475509D03*
X467848Y476535D03*
X464848D03*
X468558Y495669D03*
Y499669D03*
Y516609D03*
X464199Y510184D03*
X468850Y545586D03*
X469300Y799500D03*
X459245Y807152D03*
X473654Y821234D03*
X472399Y839566D03*
X463404Y846870D03*
X465492Y861970D03*
X471726Y883705D03*
X474540Y927341D03*
X471110Y921577D03*
X471876Y937236D03*
X471068Y930235D03*
X473992Y952546D03*
X475018Y992568D03*
X467345Y996480D03*
X459360Y1004680D03*
X464795Y1000647D03*
X462185Y1016825D03*
X459860Y1015825D03*
X464385Y1038534D03*
X471558Y1029482D03*
X471755Y1038665D03*
X470610Y1033783D03*
X475588Y1043055D03*
X473639Y1030952D03*
X459700Y1035716D03*
X470978Y1046591D03*
X474348Y1090171D03*
X462913Y1106365D03*
X474277Y1093048D03*
X472482Y1107997D03*
X468282D03*
X459938Y1110092D03*
X463604Y1115896D03*
X473367Y1113648D03*
X474818Y1116101D03*
Y1118801D03*
X472582Y1110597D03*
X470482Y1112397D03*
X468282Y1110897D03*
Y1113797D03*
X470382Y1109397D03*
X463604Y1118396D03*
X462687Y1160834D03*
X474548Y1172384D03*
Y1169884D03*
Y1167384D03*
Y1164884D03*
Y1162384D03*
X468850Y1160834D03*
X474548Y1174884D03*
X465785Y1197471D03*
X461285Y1193471D03*
Y1197471D03*
X465785Y1193471D03*
X474647Y1260160D03*
Y1257160D03*
X471647D03*
Y1260160D03*
X459290Y1297035D03*
X463290D03*
X492135Y103411D03*
X492529Y97667D03*
X483675D03*
X487925Y95111D03*
X479331Y102495D03*
X485475Y118342D03*
Y121742D03*
Y132515D03*
Y135915D03*
X479065Y142862D03*
X486206Y143762D03*
X480106Y148717D03*
X487654Y195176D03*
X489672Y199248D03*
X485154Y195176D03*
X482654D03*
X486672Y199248D03*
X490154Y195176D03*
X485235Y210509D03*
X482735D03*
X489672Y202048D03*
X486672Y201748D03*
X484508Y206806D03*
X487008D03*
X476659Y216970D03*
Y219470D03*
X476725Y226320D03*
X476659Y221970D03*
X493272Y230117D03*
X484427Y230556D03*
X488682Y227824D03*
X479686Y228646D03*
X483412Y242078D03*
X478643Y232971D03*
X488769Y246874D03*
X489288Y238714D03*
X490989Y244297D03*
X482636Y256394D03*
X492817Y357111D03*
X491843Y351089D03*
X481724Y373589D03*
Y369089D03*
X490885Y373589D03*
X491053Y365423D03*
X491289Y391589D03*
X481724Y382589D03*
Y378089D03*
X490885Y382570D03*
X490985Y412342D03*
X488438Y418417D03*
X485485Y439903D03*
X489485D03*
X481485Y439900D03*
Y431917D03*
X489485Y431417D03*
X492736Y491982D03*
X482836Y534249D03*
X491818Y534909D03*
X491445Y541135D03*
X482905Y527726D03*
Y548726D03*
Y544726D03*
X491534Y552726D03*
X491511Y546553D03*
X487209Y611071D03*
X484772Y621311D03*
X493392Y622285D03*
X493580Y616905D03*
X484772Y629311D03*
Y625311D03*
X493661Y627713D03*
X493778Y633724D03*
X481165Y646036D03*
X483059Y662649D03*
X488765Y667224D03*
X481742Y657477D03*
X486837Y701306D03*
Y704706D03*
X489406Y797558D03*
X489572Y822805D03*
X479448Y828594D03*
X479700Y847600D03*
X477574Y860815D03*
X490706Y859339D03*
X491616Y938771D03*
X476475Y952249D03*
X479613Y952189D03*
X489163Y977163D03*
X487091Y989550D03*
X480711Y999941D03*
X477857Y1004375D03*
X488041Y1020440D03*
X485678Y1039880D03*
X485633Y1036155D03*
X477765Y1093432D03*
X477607Y1089942D03*
X491503Y1086796D03*
Y1084296D03*
X478517Y1086724D03*
Y1084224D03*
Y1081724D03*
X476017D03*
Y1084224D03*
Y1086724D03*
X486369Y1105552D03*
X490647Y1101917D03*
X488927Y1104335D03*
X490582Y1106897D03*
X482575Y1104792D03*
X484082Y1106867D03*
X480167Y1113648D03*
X477667D03*
X477048Y1172384D03*
Y1169884D03*
Y1167384D03*
Y1164884D03*
Y1162384D03*
X479521Y1179209D03*
Y1181709D03*
Y1184209D03*
Y1186709D03*
X477048Y1174884D03*
X490671Y1192621D03*
Y1190121D03*
X477206Y1192621D03*
Y1190121D03*
X489647Y1260160D03*
Y1257160D03*
X486647D03*
Y1260160D03*
X480647Y1257160D03*
X477647D03*
Y1260160D03*
X480647D03*
X483647Y1257160D03*
Y1260160D03*
X490100Y1302100D03*
X487600D03*
X503325Y90650D03*
X508637Y90615D03*
X503075Y95236D03*
X492775Y114655D03*
Y111255D03*
X492294Y106561D03*
X492775Y128828D03*
Y125428D03*
X496023Y362913D03*
X497048Y369450D03*
X495750Y377531D03*
X506500Y379687D03*
X495203Y386890D03*
X503729Y439919D03*
X503682Y448419D03*
X500729Y469905D03*
X496729Y470419D03*
X504729Y469905D03*
X496729Y461919D03*
X504729Y461419D03*
X505476Y485128D03*
X497095Y481467D03*
X501224Y492050D03*
X501649Y482165D03*
X501887Y504825D03*
X499387D03*
X496887D03*
X500890Y500202D03*
X502493Y495917D03*
X492736Y495982D03*
X501828Y517401D03*
X499328D03*
X496828D03*
X502379Y522569D03*
X495444Y531948D03*
X503494Y531882D03*
X502379Y525369D03*
X500994Y531882D03*
X498494D03*
X504079Y529169D03*
X503729Y555194D03*
X500929D03*
Y571194D03*
X503729D03*
Y563194D03*
X500929D03*
X505286Y581222D03*
X502486D03*
X505286Y591215D03*
X502486D03*
X505458Y610562D03*
X502658D03*
Y607762D03*
X505458D03*
X497448Y610548D03*
X504265Y633736D03*
X499258Y633716D03*
X506278Y628078D03*
X494465Y657772D03*
X502755Y657694D03*
X496070Y665976D03*
X499528Y657843D03*
X504966Y678098D03*
X498284Y681453D03*
Y678953D03*
X500714Y708755D03*
X502832Y720491D03*
X504895Y770457D03*
X501495D03*
X504508Y783817D03*
X506166Y793224D03*
X504641Y789139D03*
X507095Y814784D03*
X494677Y830468D03*
X509665Y824512D03*
X495073Y835586D03*
X495470Y844271D03*
X495700Y849389D03*
X503383Y863025D03*
X498507Y865392D03*
X508248Y873319D03*
X509791Y881932D03*
X509017Y905295D03*
X494315Y941212D03*
X503144Y957934D03*
X504088Y985171D03*
X506888D03*
X506702Y978947D03*
X493091Y989550D03*
X503933Y981392D03*
X498435Y1008766D03*
X506566D03*
Y996766D03*
X498524Y997590D03*
X498585Y1016266D03*
X506566Y1012266D03*
X503177Y1058097D03*
X495677D03*
X493177D03*
X498177D03*
X500677D03*
X503177Y1060697D03*
X495677D03*
X493177D03*
X498177D03*
X500677D03*
X494003Y1086796D03*
X496503D03*
X499003D03*
X501503D03*
Y1084296D03*
X499003D03*
X496503D03*
X494003D03*
X501831Y1090288D03*
X496372Y1106298D03*
X504610Y1107997D03*
X501831Y1093088D03*
X500410Y1107997D03*
X497063Y1115896D03*
X505495Y1113648D03*
X506946Y1116101D03*
Y1118801D03*
X504710Y1110597D03*
X500410Y1113797D03*
X502610Y1112397D03*
X500410Y1110897D03*
X502510Y1109397D03*
X493397Y1110092D03*
X497063Y1118396D03*
X498727Y1128759D03*
X495236Y1129094D03*
X502376Y1172384D03*
Y1169884D03*
Y1167384D03*
Y1164884D03*
Y1162384D03*
X504876Y1172384D03*
Y1169884D03*
Y1167384D03*
Y1164884D03*
Y1162384D03*
X492818D03*
Y1164884D03*
Y1167384D03*
Y1169884D03*
Y1172384D03*
X495318D03*
Y1169884D03*
Y1167384D03*
Y1164884D03*
Y1162384D03*
X502562Y1158200D03*
X506451Y1179209D03*
Y1181709D03*
Y1184209D03*
Y1186709D03*
X504876Y1174884D03*
X493821Y1186921D03*
Y1184421D03*
Y1181921D03*
Y1179421D03*
X492818Y1174884D03*
X495318D03*
X502376D03*
X504136Y1190121D03*
Y1192621D03*
X496136Y1190121D03*
Y1192621D03*
X506562Y1222194D03*
X502562D03*
X498562D03*
X494562D03*
X506562Y1226194D03*
Y1230194D03*
Y1234194D03*
Y1238194D03*
X502562Y1226194D03*
Y1230194D03*
Y1234194D03*
Y1238194D03*
X498562Y1226194D03*
Y1230194D03*
Y1234194D03*
Y1238194D03*
X494562Y1226194D03*
Y1230194D03*
Y1234194D03*
Y1238194D03*
Y1246194D03*
Y1242194D03*
X506562D03*
Y1246194D03*
X502562Y1242194D03*
Y1246194D03*
X498562Y1242194D03*
Y1246194D03*
X504647Y1257160D03*
X507347D03*
X501647D03*
Y1260160D03*
X495647D03*
X492647D03*
Y1257160D03*
X495647D03*
X498647D03*
Y1260160D03*
X507347D03*
X504647D03*
X521872Y82593D03*
Y85193D03*
Y74793D03*
Y77393D03*
Y79993D03*
X521916Y92874D03*
X512958Y99961D03*
X513008Y95236D03*
X523943Y107649D03*
Y104249D03*
X520965Y162368D03*
X523565D03*
X511820Y207978D03*
Y210478D03*
Y215478D03*
Y212978D03*
X522276Y208213D03*
Y213213D03*
Y210713D03*
Y215713D03*
X515149Y264180D03*
X517649D03*
X515074Y258880D03*
X524043Y270026D03*
Y267526D03*
X514769Y312953D03*
X519638Y314346D03*
X511790Y313804D03*
X512943Y443071D03*
X520823Y442603D03*
X511753Y454339D03*
Y456839D03*
X509253D03*
Y454339D03*
X518240Y459371D03*
X509253Y459339D03*
X511753D03*
X512210Y475825D03*
X517310Y470045D03*
X513310Y462004D03*
X522756Y461818D03*
X508325Y485138D03*
X512210Y478625D03*
X513910Y482425D03*
X513325Y485138D03*
X510825D03*
X519786Y491214D03*
X523489Y492987D03*
X519786Y493714D03*
X523489Y495487D03*
X509955Y537958D03*
X513658Y539731D03*
X518716Y541895D03*
X521216Y544895D03*
Y541895D03*
X513658Y542231D03*
X518416Y544895D03*
X509955Y540458D03*
X521494Y582747D03*
X508086Y581222D03*
X520945Y590801D03*
X508086Y591215D03*
X520770Y597130D03*
X524770Y605637D03*
X518940Y620653D03*
Y617853D03*
X511058Y610562D03*
Y607762D03*
X508258Y610562D03*
Y607762D03*
X520770Y605443D03*
X516770D03*
X523616Y625013D03*
X515267Y627908D03*
X511278Y633473D03*
X521778Y642184D03*
X521868Y666577D03*
X518812Y662874D03*
X510425Y683246D03*
X522200Y677613D03*
X521540Y686319D03*
X515484Y695757D03*
X515504Y701351D03*
X521159Y706388D03*
X515649D03*
X512530Y718301D03*
X514531Y716398D03*
X523929Y706388D03*
X518389D03*
X521131Y741071D03*
X517731D03*
X511724Y741035D03*
X508324D03*
X520549Y761982D03*
X509096Y753072D03*
X515422Y753455D03*
X513504Y755804D03*
X513278Y783286D03*
X520833Y773389D03*
X513551Y773203D03*
X522697Y797102D03*
X519891Y795848D03*
X518157Y803973D03*
X518565Y811973D03*
X520741Y805149D03*
X522481Y824661D03*
X517702Y826600D03*
X514682Y834590D03*
X511741Y846649D03*
X524741Y845149D03*
X520870Y874694D03*
X525159Y913818D03*
X521572Y901500D03*
X516902Y910251D03*
X520146Y939241D03*
X523289Y939195D03*
X521353Y952266D03*
X522544Y992854D03*
X512232Y985172D03*
X514566Y1000766D03*
X514690Y996766D03*
Y1004766D03*
X514566Y1016266D03*
X514649Y1020266D03*
X514843Y1030766D03*
X519500Y1028377D03*
X518497Y1105552D03*
X522775Y1101917D03*
X521055Y1104335D03*
X514703Y1104792D03*
X522710Y1106897D03*
X516210Y1106867D03*
X509795Y1113648D03*
X512295D03*
X520646Y1169884D03*
Y1167384D03*
Y1164884D03*
Y1162384D03*
X523146D03*
Y1164884D03*
Y1167384D03*
Y1169884D03*
Y1172384D03*
X520646D03*
X520751Y1186921D03*
Y1184421D03*
Y1181921D03*
Y1179421D03*
X523146Y1174884D03*
X520646D03*
X523066Y1190121D03*
Y1192621D03*
X522562Y1222194D03*
X518562D03*
X514562D03*
X510562D03*
X522562Y1226194D03*
X518562D03*
Y1230194D03*
Y1234194D03*
X514562Y1226194D03*
Y1230194D03*
Y1234194D03*
Y1238194D03*
X510562Y1226194D03*
Y1230194D03*
Y1234194D03*
Y1238194D03*
X514562Y1242194D03*
Y1246194D03*
X510562Y1242194D03*
Y1246194D03*
X530197Y98551D03*
X540751Y97475D03*
X533092Y114623D03*
Y111223D03*
X533747Y103783D03*
X533092Y128796D03*
Y125396D03*
X532281Y141247D03*
X528509Y147540D03*
X539748Y143740D03*
X537128Y148277D03*
X530665Y162793D03*
Y165393D03*
Y170493D03*
Y167993D03*
X538170Y172190D03*
X535668Y181009D03*
X529662Y181426D03*
X532873Y181366D03*
X537589Y177616D03*
X529870Y184221D03*
X532487Y184012D03*
X533906Y211359D03*
Y213859D03*
X528848Y211695D03*
X537609Y213132D03*
X526348Y208695D03*
X529148D03*
X526348Y211695D03*
X537609Y215632D03*
X537853Y256303D03*
X532525Y265701D03*
X537612Y265896D03*
X526843Y270026D03*
X529343D03*
X526843Y267526D03*
X529343D03*
X534160Y281716D03*
X540101Y281982D03*
X532659Y359557D03*
X526388Y351301D03*
X531612Y354272D03*
X531636Y349057D03*
X528812Y369164D03*
X533211Y364746D03*
X533115Y371856D03*
X530144Y376062D03*
X531953Y380749D03*
X542034Y392209D03*
X541706Y386223D03*
X533189Y390723D03*
X531953Y385749D03*
X531992Y397552D03*
X526216Y456652D03*
X528716D03*
X526216Y459152D03*
Y461652D03*
X528716Y459152D03*
Y461652D03*
X535119Y491133D03*
X531047Y498151D03*
X535119Y493633D03*
Y496133D03*
Y498633D03*
X531047Y495151D03*
X528547D03*
X528247Y498151D03*
X525288Y537877D03*
X535219Y555897D03*
Y553297D03*
X533488Y548344D03*
X525288Y540377D03*
Y545377D03*
Y542877D03*
X528488Y548344D03*
X525988D03*
X530988D03*
X535219Y561097D03*
Y563697D03*
Y566797D03*
Y558497D03*
X532009Y570478D03*
X529214Y570686D03*
X529423Y573303D03*
X532069Y573689D03*
X532426Y576484D03*
X535819Y578405D03*
X541245Y578986D03*
X524770Y597232D03*
X534820Y596782D03*
X540770Y596729D03*
X529601Y596089D03*
X526756Y613913D03*
Y616713D03*
Y619513D03*
X538826Y614158D03*
Y616958D03*
Y619758D03*
X536770Y605443D03*
X537664Y661556D03*
X534264D03*
X529664Y664056D03*
X526264D03*
X538316Y687357D03*
X535738Y687489D03*
X536087Y702364D03*
X529469Y706230D03*
X526699Y706388D03*
X535585Y736593D03*
X538985D03*
X530985Y741593D03*
X527585D03*
X524598Y753387D03*
X539449Y782389D03*
X537578Y772428D03*
X532304Y806649D03*
X531313Y812850D03*
Y826630D03*
X532316Y833649D03*
X534000Y843000D03*
X537300Y842900D03*
X530741Y845149D03*
X534632Y849830D03*
X525718Y873821D03*
X533468Y878533D03*
X538468Y888033D03*
X530968Y888283D03*
X528975Y898346D03*
X537279Y897943D03*
X533143Y897910D03*
X531076Y913190D03*
X527879Y952189D03*
X530473Y961728D03*
X528500Y1106365D03*
X529191Y1115896D03*
X525525Y1110092D03*
X529191Y1118396D03*
X528274Y1160834D03*
X554198Y68581D03*
X554211Y80581D03*
X546293Y76587D03*
Y72615D03*
X547732Y100625D03*
X540682Y106186D03*
X552105Y112083D03*
X556394Y103621D03*
X543494Y121735D03*
Y132509D03*
Y118335D03*
Y135909D03*
X548311Y141247D03*
X552798Y143518D03*
X551898Y152373D03*
X555048Y152562D03*
X540843Y168697D03*
X555850Y178560D03*
X555913Y172665D03*
X555740Y183834D03*
X541931Y191941D03*
X555260Y190185D03*
X549985Y192490D03*
X556030Y200864D03*
X548940Y206767D03*
X546440D03*
X543940D03*
X556119Y212455D03*
X556053Y207037D03*
X549070Y221708D03*
X546570D03*
X553420Y221642D03*
X545185Y231021D03*
Y228221D03*
X544070Y221708D03*
X543485Y224421D03*
X550736Y236189D03*
X548236D03*
X545736D03*
X550677Y248765D03*
X548177D03*
X545677D03*
X542628Y266114D03*
X545874Y268195D03*
X548374D03*
X551174Y270695D03*
X554834Y265897D03*
X551174Y268195D03*
X548374Y270695D03*
X545874D03*
X551536Y359223D03*
Y354723D03*
Y350223D03*
Y345723D03*
Y377223D03*
Y372723D03*
Y368223D03*
Y363723D03*
Y381723D03*
X551620Y390723D03*
X553563Y384987D03*
X544738Y581659D03*
X544770Y605443D03*
X551475Y661504D03*
X547227Y678299D03*
X547276Y675521D03*
X543101Y698772D03*
X540379Y719785D03*
X557751Y750851D03*
X549168Y781600D03*
X545768D03*
X550420Y793743D03*
X556326D03*
X540578Y793889D03*
X544515Y793875D03*
X544741Y809649D03*
X544878Y816309D03*
X546855Y829949D03*
X550087Y829836D03*
X556326Y829989D03*
X556741Y820149D03*
X544741Y823149D03*
X546241Y843149D03*
X557836Y851669D03*
X548665Y850399D03*
X540968Y878360D03*
X546940Y871389D03*
X548327Y905295D03*
X552238Y959102D03*
X552923Y988813D03*
X542793Y998507D03*
X544719Y1007522D03*
X551485Y1006648D03*
X551673Y1023900D03*
X548852Y1018307D03*
X545094Y1013678D03*
X545566Y1023731D03*
X554696Y1018469D03*
X556493Y1118351D03*
X557584Y1543411D03*
X560573Y60513D03*
X563433Y60438D03*
X557973Y55513D03*
X569114Y86012D03*
X558341Y88801D03*
X569114Y94374D03*
X561258Y94351D03*
X565207Y94279D03*
X560701Y85731D03*
X564255Y86046D03*
X564451Y116594D03*
X570394Y110784D03*
X564451Y119594D03*
X574973Y124663D03*
X564885Y124283D03*
X569951Y124879D03*
X563292Y161306D03*
X560543Y157370D03*
X564627Y176665D03*
Y168665D03*
X556726Y186629D03*
X564627Y196665D03*
Y192665D03*
X564740Y186778D03*
X564659Y204864D03*
Y208864D03*
X569708Y218085D03*
X572508D03*
X560300Y219379D03*
X560928Y228631D03*
X575035Y249108D03*
X566416Y248371D03*
X557334Y265897D03*
X573479Y374705D03*
X569938Y378317D03*
X559070Y684809D03*
Y700809D03*
Y688209D03*
X561570Y696209D03*
Y692809D03*
X559070Y716809D03*
X561570Y708809D03*
Y712209D03*
X559070Y704209D03*
Y720209D03*
X558616Y732530D03*
X562001Y732834D03*
X562374Y721593D03*
X567428Y750145D03*
X557847Y744599D03*
X563200Y739600D03*
X571493Y763090D03*
X570038Y752339D03*
X564362Y757979D03*
X560263Y782207D03*
X567126Y779066D03*
X571984Y784507D03*
X561001Y806889D03*
X567559Y803008D03*
Y824661D03*
X562400Y818900D03*
X560813Y840574D03*
X568990Y844721D03*
X572476Y845535D03*
X559295Y874267D03*
X559887Y877196D03*
X561134Y869291D03*
X559260Y891043D03*
X559214Y897425D03*
X564165Y894411D03*
X567827Y884000D03*
X562328Y957307D03*
X566303Y951807D03*
X569403D03*
X563103D03*
X570603Y957207D03*
X560923Y980443D03*
X556923Y980523D03*
X564923Y988813D03*
X560923D03*
X556923D03*
X568923D03*
X558112Y1009655D03*
X560912D03*
X567484Y1024003D03*
X571857Y1016827D03*
X559057Y1030563D03*
X562057D03*
X568057Y1030672D03*
X565057D03*
X571857Y1029427D03*
X566058Y1109564D03*
X560211D03*
X566058Y1122164D03*
X560211D03*
X566058Y1134764D03*
X560211D03*
X566058Y1147364D03*
X560211D03*
X566058Y1159964D03*
X560211D03*
X566058Y1172564D03*
X560211D03*
X566058Y1185164D03*
X560211D03*
X568532Y1200001D03*
X575620Y1207737D03*
X569135Y1214372D03*
X564890Y1218169D03*
X570796Y1530309D03*
X567324Y1528151D03*
X572432Y1521462D03*
X565400Y1535100D03*
X563968Y1541445D03*
X568279Y1538438D03*
X572507Y1541375D03*
X586037Y97667D03*
X581693Y102495D03*
X576420Y116594D03*
X575394Y110784D03*
X587837Y118342D03*
Y121742D03*
Y132515D03*
X576420Y119594D03*
X579954Y125107D03*
X587837Y135915D03*
X581427Y142862D03*
X588568Y143762D03*
X582468Y148717D03*
X576317Y138838D03*
X587516Y195176D03*
X585016D03*
X589034Y199248D03*
X587597Y210509D03*
X585097D03*
X589034Y201748D03*
X586870Y206806D03*
X576308Y216385D03*
X579021Y216970D03*
Y219470D03*
X579087Y226320D03*
X579021Y221970D03*
X586789Y230556D03*
X591044Y227824D03*
X582048Y228646D03*
X585774Y242078D03*
X581005Y232971D03*
X577655Y244571D03*
X584998Y256394D03*
X578193Y336391D03*
X584679Y336285D03*
X576556Y728219D03*
X575979Y732517D03*
X573778Y747437D03*
X577638Y769772D03*
X578271Y763556D03*
X583102Y767137D03*
X587183Y785008D03*
X578204Y775137D03*
X585912Y778470D03*
X588345Y798030D03*
X588659Y790336D03*
X582100Y787600D03*
X586060Y793145D03*
X581001Y810973D03*
X588377Y807536D03*
X588272Y804601D03*
X588231Y801520D03*
X577501Y829069D03*
X588001Y829624D03*
X582737Y819831D03*
X581158Y823473D03*
X573300Y829600D03*
X579827Y888000D03*
X580327Y892000D03*
X586136Y908935D03*
X583065Y903294D03*
X573103Y941307D03*
X585703D03*
X586103Y961807D03*
X573895Y965319D03*
X584923Y988813D03*
X576923D03*
X580923D03*
X588923D03*
X572923D03*
X577704Y1029427D03*
Y1016827D03*
X587880Y1034834D03*
X581967Y1105091D03*
X587467D03*
X582012Y1102091D03*
X587467Y1117691D03*
X581967D03*
X582012Y1127291D03*
Y1114691D03*
X587467Y1130291D03*
X581967D03*
X587467Y1142891D03*
X582012Y1139891D03*
X581967Y1155491D03*
X587467D03*
X581967Y1142891D03*
X582012Y1152491D03*
X581967Y1168091D03*
X587467D03*
X582012Y1165091D03*
X581967Y1180691D03*
X587467D03*
X582012Y1177691D03*
X586502Y1227300D03*
X583520Y1230407D03*
X581803Y1493687D03*
X578859Y1497758D03*
X588859Y1490895D03*
X590826Y1495688D03*
X588507Y1514141D03*
X582027Y1502800D03*
X581803Y1509687D03*
X577931Y1505687D03*
X575809Y1532912D03*
X572849Y1518702D03*
X587809Y1528389D03*
X583809Y1533025D03*
X579809Y1528163D03*
X587809Y1545854D03*
X583809Y1541607D03*
X577571Y1544013D03*
X594497Y103411D03*
X594891Y97667D03*
X605687Y90650D03*
X590287Y95111D03*
X595137Y111255D03*
Y114655D03*
X594656Y106561D03*
X595137Y125428D03*
Y128828D03*
X590016Y195176D03*
X592516D03*
X592034Y199248D03*
Y202048D03*
X589370Y206806D03*
X595634Y230117D03*
X591131Y246874D03*
X591650Y238714D03*
X593351Y244297D03*
X592900Y309871D03*
X605147Y378600D03*
Y382600D03*
X597776Y401513D03*
Y398113D03*
X595376Y412287D03*
Y426460D03*
Y415687D03*
Y440633D03*
Y429860D03*
X605262Y458711D03*
X595376Y444033D03*
X602462Y458711D03*
X595376Y469387D03*
Y472787D03*
X604606Y463600D03*
X595376Y483560D03*
Y486960D03*
X598462Y504684D03*
X595376Y513521D03*
Y516921D03*
Y531094D03*
Y527694D03*
X599110Y552466D03*
X605011Y603600D03*
Y619600D03*
Y623600D03*
X592272Y877262D03*
X592110Y895611D03*
X601084Y913544D03*
X604715Y914640D03*
X589203Y941407D03*
X591403Y938807D03*
Y936007D03*
X591754Y956979D03*
X597556Y965829D03*
X602484Y965764D03*
X600923Y988813D03*
X592923D03*
X604923D03*
X596923D03*
X599113Y1012354D03*
X593658Y1009354D03*
X593613Y1012354D03*
X599113Y1024954D03*
X593613D03*
X593658Y1021954D03*
X606434Y1041904D03*
X603682Y1053457D03*
X594183Y1220068D03*
X593519Y1224472D03*
X592885Y1229402D03*
X592634Y1234921D03*
X591487Y1501687D03*
X591481Y1509313D03*
X595809Y1532133D03*
X591872Y1518071D03*
X595809Y1546214D03*
X591809Y1542407D03*
X610999Y90615D03*
X615370Y95236D03*
X615320Y99961D03*
X605437Y95236D03*
X620727Y162368D03*
X614182Y210478D03*
Y215478D03*
Y212978D03*
Y207978D03*
X617511Y264180D03*
X620011D03*
X617436Y258880D03*
X605778Y391001D03*
Y405174D03*
Y394401D03*
Y408574D03*
Y422747D03*
Y419347D03*
Y433521D03*
Y436921D03*
X607789Y453682D03*
X606026Y455921D03*
X605778Y479899D03*
Y490673D03*
Y476499D03*
Y494073D03*
Y520633D03*
Y524033D03*
Y534806D03*
Y538206D03*
X609133Y941137D03*
X605733D03*
X608965Y966414D03*
X616923Y988813D03*
X608923D03*
X612923Y997860D03*
X618878Y1011914D03*
X621479Y1030482D03*
X607993Y1036920D03*
X610780Y1051037D03*
X617634Y1049283D03*
X617894Y1043955D03*
X612955Y1062941D03*
X622736Y1151870D03*
Y1159350D03*
X613738Y1546507D03*
X624234Y74793D03*
Y82593D03*
Y85193D03*
Y77393D03*
Y79993D03*
X624278Y92874D03*
X632559Y98551D03*
X635454Y114623D03*
Y111223D03*
X636109Y103783D03*
X626305Y104249D03*
Y107649D03*
X635454Y128796D03*
Y125396D03*
X630871Y147540D03*
X634643Y141247D03*
X639490Y148277D03*
X625927Y162368D03*
X623327D03*
X633027Y165393D03*
Y162793D03*
Y170493D03*
Y167993D03*
X639951Y177616D03*
X632024Y181426D03*
X635235Y181366D03*
X632232Y184221D03*
X634849Y184012D03*
X628710Y211695D03*
Y208695D03*
X631510D03*
X624638Y208213D03*
X636268Y211359D03*
Y213859D03*
X631210Y211695D03*
X624638Y213213D03*
Y210713D03*
Y215713D03*
X639974Y265896D03*
X634887Y265701D03*
X629205Y267526D03*
X626405D03*
X631705D03*
X629205Y270026D03*
X626405D03*
X631705D03*
X636522Y281716D03*
X632009Y541863D03*
Y545263D03*
X630201Y553407D03*
X632701D03*
X630201Y550907D03*
X632701D03*
X634185Y569426D03*
X634471Y566929D03*
X628425Y572070D03*
X629772Y569928D03*
X632119Y570962D03*
X631862Y568475D03*
X621592Y1033862D03*
X626476Y1155610D03*
X621727Y1556800D03*
X648655Y76587D03*
Y72615D03*
X650094Y100625D03*
X643113Y97475D03*
X643044Y106186D03*
X645856Y118335D03*
Y132509D03*
Y121735D03*
Y135909D03*
X650673Y141247D03*
X655160Y143518D03*
X642110Y143740D03*
X654260Y152373D03*
X640532Y172190D03*
X638030Y181009D03*
X643205Y168697D03*
X644293Y191941D03*
X652347Y192490D03*
X646302Y206767D03*
X651302D03*
X648802D03*
X639971Y213132D03*
X648932Y221708D03*
X647547Y228221D03*
X645847Y224421D03*
X647547Y231021D03*
X646432Y221708D03*
X651432D03*
X639971Y215632D03*
X650598Y236189D03*
X648098D03*
X653098D03*
X653039Y248765D03*
X650539D03*
X648039D03*
X640215Y256303D03*
X644990Y266114D03*
X650736Y268195D03*
X653536Y270695D03*
Y268195D03*
X650736Y270695D03*
X648236D03*
Y268195D03*
X642463Y281982D03*
X642414Y545528D03*
X651149Y577716D03*
X648211Y610400D03*
X650958Y668153D03*
X662935Y60513D03*
X665795Y60438D03*
X657507Y58013D03*
X656560Y68581D03*
X671476Y86012D03*
X656573Y80581D03*
X660703Y88801D03*
X663620Y94351D03*
X667569Y94279D03*
X663063Y85731D03*
X666617Y86046D03*
X658756Y103621D03*
X666813Y116594D03*
X654467Y112083D03*
X666813Y119594D03*
X667247Y124283D03*
X672313Y124879D03*
X665654Y161306D03*
X657410Y152562D03*
X662905Y157370D03*
X666989Y176665D03*
Y168665D03*
X658275Y172665D03*
X658212Y178560D03*
X658102Y183834D03*
X659088Y186629D03*
X657622Y190185D03*
X658392Y200864D03*
X666989Y196665D03*
Y192665D03*
X667102Y186778D03*
X667021Y204864D03*
Y208864D03*
X658481Y212455D03*
X658415Y207037D03*
X655782Y221642D03*
X662662Y219379D03*
X663290Y228631D03*
X668886Y248371D03*
X657196Y265897D03*
X659696D03*
X670066Y390995D03*
X661761Y382109D03*
X670066Y405168D03*
X662766Y398082D03*
X670066Y408568D03*
Y394395D03*
X662766Y401482D03*
X670066Y422741D03*
Y419341D03*
X662766Y415655D03*
Y426428D03*
Y412255D03*
Y440602D03*
X670066Y433515D03*
X662766Y429828D03*
X670066Y436915D03*
X662766Y444002D03*
X670066Y469381D03*
Y472781D03*
X662766Y476468D03*
Y490641D03*
X670066Y483554D03*
Y486954D03*
X662766Y479868D03*
Y494041D03*
X670066Y516915D03*
X662766Y520602D03*
Y524002D03*
X670066Y513515D03*
Y527688D03*
X662766Y534775D03*
X670066Y531088D03*
X662766Y538175D03*
X661760Y551683D03*
Y561420D03*
Y558917D03*
X657581Y577937D03*
X660586Y606929D03*
X665086Y604567D03*
X665586Y595500D03*
X660827Y612592D03*
X666244Y610072D03*
X660546Y618400D03*
X666180Y616317D03*
X665643Y646055D03*
X658233Y646449D03*
X658064Y650119D03*
X657967Y662981D03*
X662092Y666275D03*
X659209Y691851D03*
X661018Y707592D03*
X688399Y97667D03*
X671476Y94374D03*
X678782Y116594D03*
X684055Y102495D03*
X677756Y110784D03*
X672756D03*
X678782Y119594D03*
X682316Y125107D03*
X677335Y124663D03*
X683789Y142862D03*
X684830Y148717D03*
X678679Y138838D03*
X674870Y218085D03*
X681383Y219470D03*
Y216970D03*
X678670Y216385D03*
X681383Y221970D03*
X681449Y226320D03*
X672070Y218085D03*
X684410Y228646D03*
X683367Y232971D03*
X677397Y249108D03*
X680017Y244571D03*
X682857Y339477D03*
X687055Y376456D03*
X685353Y396718D03*
X678461Y455981D03*
X675237Y465611D03*
X682586Y530000D03*
X682086Y540500D03*
X681086Y547075D03*
X681286Y549800D03*
X680586Y568000D03*
X681126Y558800D03*
X681190Y562800D03*
X696859Y103411D03*
X697253Y97667D03*
X692649Y95111D03*
X697499Y114655D03*
Y111255D03*
X697018Y106561D03*
X690199Y132515D03*
X697499Y125428D03*
Y128828D03*
X690199Y121742D03*
Y118342D03*
Y135915D03*
X690930Y143762D03*
X691396Y199248D03*
X687378Y195176D03*
X689878D03*
X694396Y199248D03*
X694878Y195176D03*
X692378D03*
X691396Y201748D03*
X689232Y206806D03*
X687459Y210509D03*
X689959D03*
X694396Y202048D03*
X691732Y206806D03*
X697996Y230117D03*
X689151Y230556D03*
X693406Y227824D03*
X694012Y238714D03*
X688136Y242078D03*
X693493Y246874D03*
X695713Y244297D03*
X690504Y253198D03*
X689486Y339583D03*
X702448Y546712D03*
Y542712D03*
X699188Y656321D03*
X702086Y678462D03*
X692478Y730641D03*
X702691Y762971D03*
Y756971D03*
X692356Y764614D03*
X691991Y759581D03*
X702677Y780659D03*
Y775159D03*
X692155Y778974D03*
X692221Y773449D03*
X690449Y814406D03*
X708049Y90650D03*
X713361Y90615D03*
X717732Y95236D03*
X717682Y99961D03*
X707799Y95236D03*
X716544Y215478D03*
Y210478D03*
Y207978D03*
Y212978D03*
X718338Y305272D03*
X712692Y356779D03*
X717105Y410964D03*
X717420Y404334D03*
X709781Y442956D03*
X720996Y442856D03*
X711598Y438323D03*
X719051Y458455D03*
X719612Y451108D03*
X710643Y456335D03*
X711764Y445873D03*
X706211Y465874D03*
X713791Y474424D03*
Y488597D03*
Y477824D03*
Y491997D03*
Y518558D03*
Y521958D03*
Y536131D03*
Y532731D03*
X711463Y546712D03*
X713791Y571997D03*
Y568597D03*
Y582771D03*
Y586171D03*
Y596944D03*
Y600344D03*
Y611117D03*
Y614517D03*
X704364Y618288D03*
X711328Y653821D03*
X705390Y655789D03*
X705776Y678519D03*
X713200Y699676D03*
X716623Y702463D03*
X703600Y702212D03*
X703680Y697094D03*
X715802Y706446D03*
X710196Y707562D03*
X717434Y782500D03*
X710275Y786131D03*
X713222Y793312D03*
Y790812D03*
X712901Y821600D03*
X726596Y74793D03*
Y77393D03*
Y79993D03*
Y85193D03*
Y82593D03*
X726640Y92874D03*
X734921Y98551D03*
X728667Y104249D03*
Y107649D03*
X733233Y147540D03*
X728289Y162368D03*
X725689D03*
X734386Y181426D03*
X734594Y184221D03*
X727000Y213213D03*
Y208213D03*
X733872Y208695D03*
X731072D03*
X733572Y211695D03*
X731072D03*
X727000Y210713D03*
Y215713D03*
X722373Y264180D03*
X719873D03*
X719798Y258880D03*
X737249Y265701D03*
X731567Y267526D03*
X728767D03*
X734067D03*
Y270026D03*
X731567D03*
X728767D03*
X723404Y379657D03*
X721900Y384500D03*
X723440Y391496D03*
X734661Y393633D03*
X731511Y381113D03*
X723440Y398583D03*
X732035Y442606D03*
X722097Y453881D03*
X731952Y446606D03*
X722097Y446595D03*
X721091Y470737D03*
Y467337D03*
X732959Y463479D03*
X733430Y467367D03*
X721091Y484910D03*
Y481510D03*
X724362Y504731D03*
X721091Y514871D03*
Y511471D03*
Y525644D03*
Y529044D03*
Y561510D03*
Y564910D03*
Y579084D03*
Y575684D03*
Y593257D03*
Y604030D03*
Y589857D03*
Y607430D03*
X722473Y693718D03*
X723656Y705858D03*
X720985Y711658D03*
X725667Y732161D03*
X723177Y728219D03*
X721163Y738981D03*
X733000Y816000D03*
X730880Y828924D03*
X733680Y828977D03*
X732713Y853890D03*
X722600Y869600D03*
X728503Y891692D03*
X736452Y890548D03*
X728692Y886653D03*
X724707Y893143D03*
X719661Y904900D03*
X722789Y927095D03*
X722400Y942500D03*
X725194Y942073D03*
X720271Y931730D03*
X732306Y942682D03*
X728846Y948331D03*
X733798Y950186D03*
X727116Y959326D03*
X732825Y1604100D03*
X736067Y1611892D03*
X729600Y1625165D03*
X732268Y1618260D03*
X751017Y76587D03*
Y72615D03*
X752456Y100625D03*
X745475Y97475D03*
X737816Y114623D03*
Y111223D03*
X745406Y106186D03*
X738471Y103783D03*
X748218Y118335D03*
X737816Y128796D03*
X748218Y132509D03*
Y121735D03*
X737816Y125396D03*
X748218Y135909D03*
X737005Y141247D03*
X744472Y143740D03*
X741852Y148277D03*
X735389Y165393D03*
Y162793D03*
Y170493D03*
Y167993D03*
X740392Y181009D03*
X737597Y181366D03*
X745567Y168697D03*
X742894Y172190D03*
X742313Y177616D03*
X746655Y191941D03*
X737211Y184012D03*
X750667Y192300D03*
X751164Y206767D03*
X748664D03*
X738630Y213859D03*
Y211359D03*
X742333Y213132D03*
X749909Y228221D03*
Y231021D03*
X751294Y221708D03*
X748209Y224421D03*
X748794Y221708D03*
X742333Y215632D03*
X750460Y236189D03*
X750401Y248765D03*
X742577Y256303D03*
X747352Y266114D03*
X742336Y265896D03*
X750598Y268195D03*
Y270695D03*
X744825Y281982D03*
X738884Y281716D03*
X741051Y316389D03*
X749444Y393858D03*
X749606Y384410D03*
X752785Y382047D03*
X753086Y403500D03*
X751086Y398583D03*
X749539Y438269D03*
Y440869D03*
Y435669D03*
Y430469D03*
Y433069D03*
X735599Y449961D03*
X739316Y458572D03*
X750393Y451677D03*
Y454177D03*
X741992Y763480D03*
X742000Y768137D03*
X743428Y772418D03*
X741993Y775909D03*
X736000Y864266D03*
X742407Y988452D03*
X743062Y1004460D03*
X749439Y1458777D03*
X740530Y1524113D03*
X747140Y1581335D03*
X749786Y1590517D03*
X738775Y1597866D03*
X737892Y1602340D03*
X749704Y1608631D03*
X744924Y1617709D03*
X743331Y1627871D03*
X741705Y1622015D03*
X738325Y1634485D03*
X762697Y55513D03*
X758922Y68581D03*
X765297Y60513D03*
X758935Y80581D03*
X763065Y88801D03*
X765982Y94351D03*
X769931Y94279D03*
X765425Y85731D03*
X756829Y112083D03*
X761118Y103621D03*
X769609Y124283D03*
X753035Y141247D03*
X757522Y143518D03*
X756622Y152373D03*
X759772Y152562D03*
X765267Y157370D03*
X760637Y172665D03*
X760464Y183834D03*
X760574Y178560D03*
X761450Y186629D03*
X754709Y192490D03*
X759984Y190185D03*
X760754Y200864D03*
X753182Y198671D03*
X753664Y206767D03*
X769383Y208864D03*
X760843Y212455D03*
X760777Y207037D03*
X753794Y221708D03*
X758144Y221642D03*
X765024Y219379D03*
X763653Y224536D03*
X752960Y236189D03*
X755460D03*
X755401Y248765D03*
X752901D03*
X753098Y268195D03*
X755898D03*
X753098Y270695D03*
X755898D03*
X759558Y265897D03*
X762058D03*
X769349Y324518D03*
X759029Y328867D03*
X754805Y339559D03*
X759624Y353961D03*
X756086Y377912D03*
X766344D03*
X755086Y391496D03*
X756086Y386500D03*
X766344Y381912D03*
X756174Y397912D03*
X755086Y409000D03*
X766344Y397912D03*
X752339Y438269D03*
Y433069D03*
Y430469D03*
Y435669D03*
Y440869D03*
X752893Y451677D03*
Y454177D03*
X752097Y460218D03*
Y463618D03*
X755035Y1443524D03*
X765713Y1437365D03*
X760398Y1440276D03*
X755187Y1580821D03*
X759802Y1590864D03*
X763542Y1590186D03*
X768361Y1610083D03*
X762671Y1619367D03*
X756358Y1613767D03*
X768157Y60438D03*
X773838Y86012D03*
Y94374D03*
X768979Y86046D03*
X781144Y116594D03*
X769175D03*
X775118Y110784D03*
X780118D03*
X781144Y119594D03*
X769175D03*
X784678Y125107D03*
X779697Y124663D03*
X774675Y124879D03*
X781041Y138838D03*
X768016Y161306D03*
X769351Y176665D03*
Y168665D03*
Y192665D03*
X769464Y186778D03*
X769383Y204864D03*
X774432Y218085D03*
X777232D03*
X783745Y216970D03*
X781032Y216385D03*
X783745Y221970D03*
X783811Y226320D03*
X783745Y219470D03*
X782379Y244571D03*
X779759Y249108D03*
X771140Y248371D03*
X772165Y314890D03*
X784118Y303962D03*
X771941Y311740D03*
X772162Y332584D03*
X778502Y348015D03*
X772859Y347937D03*
X774419Y353470D03*
X784902Y428653D03*
X778079Y467306D03*
Y470706D03*
Y481479D03*
Y484879D03*
Y514839D03*
Y511439D03*
Y529013D03*
Y525613D03*
X775746Y539315D03*
X777708Y553287D03*
X781429Y545017D03*
X778079Y561479D03*
Y564879D03*
Y575652D03*
Y579052D03*
Y589825D03*
Y593225D03*
Y603999D03*
Y607399D03*
X778860Y626912D03*
X778205Y622912D03*
X783694Y1410977D03*
X778685Y1416198D03*
X780162Y1412848D03*
X777749Y1431432D03*
X783469Y1424655D03*
X771557Y1446818D03*
X768910Y1437741D03*
X777749Y1435432D03*
Y1439432D03*
X777260Y1446237D03*
X778428Y1455156D03*
X777725Y1450193D03*
X783620Y1460108D03*
X768812Y1453306D03*
X781124Y1583553D03*
X781110Y1595254D03*
X777059Y1608982D03*
X784046Y1600438D03*
X778045Y1619395D03*
X778358Y1627418D03*
X771383Y1616917D03*
X799221Y103411D03*
X799615Y97667D03*
X790761D03*
X795011Y95111D03*
X799861Y114655D03*
Y111255D03*
X786417Y102495D03*
X799380Y106561D03*
X792561Y132515D03*
Y118342D03*
X799861Y128828D03*
X792561Y121742D03*
X799861Y125428D03*
X792561Y135915D03*
X786151Y142862D03*
X793292Y143762D03*
X787192Y148717D03*
X796758Y199248D03*
X797240Y195176D03*
X794740D03*
X789740D03*
X792240D03*
X793758Y199248D03*
X794094Y206806D03*
X791594D03*
X789821Y210509D03*
X792321D03*
X793758Y201748D03*
X796758Y202048D03*
X800358Y230117D03*
X795768Y227824D03*
X791513Y230556D03*
X786772Y228646D03*
X796374Y238714D03*
X790498Y242078D03*
X785729Y232971D03*
X795855Y246874D03*
X798075Y244297D03*
X789722Y256394D03*
X786461Y293028D03*
X790280Y287421D03*
X800155Y337368D03*
X800029Y333368D03*
X797141Y350368D03*
X795445Y356950D03*
X789581Y405011D03*
X793893Y409502D03*
X784804Y425371D03*
X794173Y450510D03*
X802136Y448334D03*
X788481Y474418D03*
Y477818D03*
Y488591D03*
Y491991D03*
Y518552D03*
Y521952D03*
Y532725D03*
Y536125D03*
X796000Y553101D03*
X788481Y571991D03*
Y568591D03*
Y586165D03*
Y582765D03*
Y600338D03*
Y596938D03*
Y614511D03*
Y611111D03*
X788600Y1006923D03*
X799631Y1025440D03*
X795631D03*
X789050Y1026150D03*
X796338Y1138130D03*
X793842Y1143384D03*
X797160Y1146609D03*
X792277Y1173065D03*
X799020Y1175975D03*
X798353Y1172011D03*
X787887Y1174500D03*
X798542Y1188345D03*
X792382Y1191664D03*
X794533Y1195766D03*
X794983Y1334030D03*
Y1331230D03*
X793548Y1397690D03*
X795296Y1416995D03*
X792848Y1414718D03*
X793459Y1429165D03*
X789647Y1427518D03*
X788648Y1422044D03*
X785820Y1425993D03*
X798601Y1431673D03*
X793288Y1450918D03*
X793744Y1437159D03*
X786787Y1433800D03*
X787694Y1442749D03*
X800607Y1440760D03*
X790361Y1447895D03*
X790754Y1441399D03*
X793994Y1441499D03*
X799057Y1449158D03*
X797083Y1467883D03*
X799057Y1456016D03*
X794005Y1464178D03*
X790296Y1463459D03*
X787038Y1460533D03*
X786591Y1452803D03*
X790989Y1455695D03*
X799314Y1475693D03*
X797318Y1471242D03*
X810411Y90650D03*
X815723Y90615D03*
X810161Y95236D03*
X805952Y301675D03*
X817456Y305368D03*
Y313368D03*
X809490Y305368D03*
X809466Y310604D03*
X801097Y325858D03*
X817100Y319600D03*
X809457Y330459D03*
X809490Y325368D03*
Y317368D03*
X809489Y313830D03*
X809490Y321368D03*
Y333368D03*
X816177Y441442D03*
X813456Y441474D03*
X810749Y443045D03*
X815840Y444091D03*
Y456060D03*
X810453Y453330D03*
X810406Y448214D03*
X810756Y471071D03*
Y468571D03*
X814580Y468806D03*
X814828Y472053D03*
X810756Y473571D03*
Y476071D03*
X813902Y730738D03*
X813678Y740979D03*
X813653Y746856D03*
X817584Y764219D03*
X813635Y762000D03*
X818000Y797000D03*
X817845Y817879D03*
X818500Y810135D03*
X813000Y805000D03*
X813548Y814000D03*
X813009Y819734D03*
X815500Y824000D03*
X815863Y830097D03*
X814299Y840877D03*
X813887Y835146D03*
X816037Y845578D03*
X812440Y862306D03*
X814080Y864464D03*
X812575Y880834D03*
X812219Y883586D03*
X817884Y915425D03*
X803673Y1025440D03*
X803453Y1134729D03*
X814835D03*
X806835D03*
X809632Y1142666D03*
X817964Y1157404D03*
X811507Y1157544D03*
X810018Y1167768D03*
X815037D03*
X814160Y1178240D03*
X814170Y1185205D03*
X805212Y1180175D03*
X805519Y1187215D03*
X815455Y1201043D03*
X811485D03*
X807489D03*
X804452Y1199814D03*
X804458Y1193112D03*
X809027Y1219895D03*
X807020Y1217900D03*
X812302Y1223170D03*
X815149Y1226016D03*
X810148Y1374884D03*
X806148Y1383715D03*
Y1375208D03*
X810204Y1401661D03*
X804654Y1404769D03*
X812901Y1432804D03*
X815901D03*
X810059Y1432778D03*
X812104Y1426483D03*
X809986Y1438785D03*
X812986D03*
X815986D03*
X809986Y1441485D03*
X812986D03*
X815986D03*
X812901Y1435504D03*
X815901D03*
X810001D03*
X803057Y1449158D03*
X801057Y1447158D03*
X805569Y1441519D03*
X803057Y1456016D03*
X801057Y1458016D03*
X802684Y1465549D03*
X801354Y1478681D03*
X807576Y1469584D03*
X804919Y1489247D03*
X828958Y79993D03*
Y77393D03*
Y74793D03*
Y85193D03*
Y82593D03*
X829002Y92874D03*
X820094Y95236D03*
X820044Y99961D03*
X831029Y104249D03*
Y107649D03*
X830651Y162368D03*
X828051D03*
X829362Y213213D03*
X818906Y207978D03*
Y212978D03*
Y215478D03*
Y210478D03*
X829362Y208213D03*
Y210713D03*
Y215713D03*
X822235Y264180D03*
X824735D03*
X822160Y258880D03*
X831129Y267526D03*
Y270026D03*
X822477Y309368D03*
X825971Y345101D03*
X829485D03*
X822626Y348066D03*
X818840Y444091D03*
X825103Y430358D03*
Y435558D03*
Y432958D03*
X831378Y433086D03*
Y435686D03*
Y430486D03*
X818840Y456060D03*
X824650Y455034D03*
Y450034D03*
X817328Y472053D03*
X820810Y471243D03*
X817380Y468806D03*
X823544Y475061D03*
Y472561D03*
X820810Y473743D03*
X828918Y480580D03*
X831418D03*
X831057Y484036D03*
X834282Y536085D03*
X828272Y535462D03*
X827291Y533100D03*
X829496Y676793D03*
X829784Y716589D03*
Y705489D03*
X823890Y703415D03*
X823670Y710542D03*
X824387Y726246D03*
X818307Y724144D03*
X821582Y727140D03*
X826484Y747127D03*
X827500Y750000D03*
X819788Y739634D03*
X830484Y738750D03*
X824500Y760500D03*
X830075Y769000D03*
X822151Y752283D03*
X824500Y756000D03*
X817365Y756827D03*
X824500Y778500D03*
Y774000D03*
Y782500D03*
X830075Y787000D03*
X824500Y796500D03*
X824342Y792315D03*
X824500Y800500D03*
X830075Y805000D03*
X824500Y814500D03*
X830075Y823000D03*
X829946Y829788D03*
X825721Y839816D03*
X830014Y833046D03*
X829757Y842672D03*
X822608Y848526D03*
X822916Y852576D03*
X823540Y857956D03*
X831654Y864494D03*
X831583Y853454D03*
X822938Y863298D03*
X826209Y866052D03*
X823234Y870830D03*
X833194Y873561D03*
X827992Y874107D03*
X826070Y893014D03*
X817152Y896380D03*
X817139Y890330D03*
X830063Y898500D03*
X819918Y889365D03*
X823900Y882083D03*
X824804Y898395D03*
X834465Y884538D03*
X829848Y914211D03*
X818031Y907747D03*
X825336Y916774D03*
X831057Y916745D03*
X834751Y922368D03*
X823552Y930700D03*
X829617Y939583D03*
X824414Y939655D03*
X816519Y931147D03*
X824168Y949538D03*
X825670Y964671D03*
X832423Y964669D03*
X828964Y977780D03*
X830356Y1116251D03*
X827856D03*
X825335Y1137129D03*
X819449Y1134534D03*
X819026Y1128137D03*
X825744Y1150087D03*
X823220Y1170767D03*
X818879Y1187310D03*
X823309Y1180235D03*
X823516Y1185238D03*
X819489Y1201039D03*
X823489Y1200969D03*
X823608Y1208993D03*
X819419Y1230265D03*
X817360Y1228226D03*
X816648Y1380758D03*
X824901Y1427404D03*
X827901D03*
X821901D03*
X818901Y1430104D03*
X821901D03*
X830901D03*
X827901D03*
X824901D03*
Y1432804D03*
X827901D03*
X830901D03*
X821901D03*
X818901D03*
X824901Y1435504D03*
X827901D03*
X821901D03*
X818901D03*
X821986Y1441485D03*
X818986D03*
Y1438785D03*
X821986D03*
X826204Y1444689D03*
Y1440689D03*
X826341Y1451236D03*
X826365Y1458974D03*
X826219Y1455244D03*
X837283Y98551D03*
X847837Y97475D03*
X840178Y114623D03*
Y111223D03*
X840833Y103783D03*
X847768Y106186D03*
X840178Y128796D03*
Y125396D03*
X837751Y165393D03*
Y162793D03*
Y170493D03*
Y167993D03*
X842754Y181009D03*
X839959Y181366D03*
X836748Y181426D03*
X847929Y168697D03*
X844675Y177616D03*
X845256Y172190D03*
X839573Y184012D03*
X836956Y184221D03*
X836234Y208695D03*
X833434D03*
X835934Y211695D03*
X840992Y213859D03*
Y211359D03*
X833434Y211695D03*
X844695Y213132D03*
Y215632D03*
X844939Y256303D03*
X844698Y265896D03*
X839611Y265701D03*
X849714Y266114D03*
X836429Y267526D03*
X833929D03*
Y270026D03*
X836429D03*
X841246Y281716D03*
X847187Y281982D03*
X842240Y324854D03*
X848879Y360849D03*
X845435Y356172D03*
X846098Y408715D03*
X849591Y411388D03*
X842515Y461382D03*
X850732Y469382D03*
X842779Y473076D03*
X842916Y467009D03*
X833293Y490636D03*
Y487836D03*
X833918Y480580D03*
X834215Y484138D03*
X844227Y479882D03*
X842476Y482382D03*
X833269Y506683D03*
X833953Y530621D03*
X848444Y657756D03*
X837272Y663910D03*
X839636Y666533D03*
X842352Y659243D03*
X842640Y662814D03*
X838152Y700215D03*
X845784Y705489D03*
Y716589D03*
X845850Y710969D03*
X845784Y708089D03*
X836078Y709619D03*
X835987Y713745D03*
X838484Y746701D03*
X846484Y738750D03*
X836713Y738751D03*
X842661Y769521D03*
X846000Y772079D03*
X840136Y830903D03*
X836839Y831301D03*
X836894Y824401D03*
X848224Y823502D03*
X835626Y843629D03*
X838189Y843459D03*
Y847490D03*
X835215Y847719D03*
X848384Y843459D03*
X846239Y847490D03*
X835553Y835119D03*
X848384Y839459D03*
Y835459D03*
X838194Y836962D03*
X848739Y847459D03*
X837183Y855459D03*
X840234Y851459D03*
X847138Y859459D03*
X839530Y859408D03*
X848384Y863459D03*
X846336Y855459D03*
X845820Y863413D03*
X848384Y851459D03*
X843574Y859423D03*
X837434Y851459D03*
X833327Y855560D03*
X837383Y879530D03*
X837396Y871459D03*
X840234Y875459D03*
X836999Y867413D03*
X845876Y879459D03*
X848384Y867459D03*
X845820Y867413D03*
X848384Y879459D03*
Y871459D03*
Y875459D03*
X837290Y887490D03*
X842827Y895443D03*
X835346Y891346D03*
X848322Y888421D03*
X848792Y896472D03*
X836066Y894955D03*
X847098Y891213D03*
X845633Y883492D03*
X845964Y887490D03*
X837276Y883459D03*
X848200Y883400D03*
X841329Y926602D03*
X841274Y914060D03*
X843315Y916612D03*
X836909Y916618D03*
Y914018D03*
X833683Y939579D03*
X836243D03*
X833683Y949105D03*
X836243D03*
X842856Y949146D03*
X836423Y964669D03*
X835431Y977775D03*
X840935Y1011499D03*
X844058Y1011738D03*
X848045Y1019310D03*
X848070Y1022190D03*
X839744Y1444959D03*
Y1440859D03*
Y1448959D03*
X836704Y1448849D03*
Y1440849D03*
X836744Y1444849D03*
X845306Y1438269D03*
X846844Y1454334D03*
X837685Y1453196D03*
X839744Y1457959D03*
X835474Y1457397D03*
X846044Y1451459D03*
X839744Y1461959D03*
X834475Y1460059D03*
X865059Y55513D03*
X861284Y68581D03*
X861297Y80581D03*
X853379Y76587D03*
Y72615D03*
X854818Y100625D03*
X859191Y112083D03*
X863480Y103621D03*
X850580Y118335D03*
Y132509D03*
Y121735D03*
Y135909D03*
X862826Y183834D03*
X862999Y172665D03*
X862936Y178560D03*
X849017Y191941D03*
X863812Y186629D03*
X857071Y192490D03*
X862346Y190185D03*
X863116Y200864D03*
X853029Y192300D03*
X853526Y206767D03*
X856026D03*
X851026D03*
X863205Y212455D03*
X863139Y207037D03*
X860506Y221642D03*
X852271Y228221D03*
Y231021D03*
X853656Y221708D03*
X856156D03*
X850571Y224421D03*
X851156Y221708D03*
X866015Y224536D03*
X852822Y236189D03*
X855322D03*
X857822D03*
X852763Y248765D03*
X855263D03*
X857763D03*
X852960Y268195D03*
Y270695D03*
X855460D03*
X864420Y265897D03*
X858260Y268195D03*
Y270695D03*
X861920Y265897D03*
X855460Y268195D03*
X863430Y309368D03*
Y316970D03*
X863114Y324505D03*
X863040Y330140D03*
X861770Y343006D03*
X852569Y356712D03*
X856069Y356426D03*
X854086Y374500D03*
X858586D03*
X863086D03*
X860586Y383000D03*
X861235Y394000D03*
X854086Y392999D03*
X864086Y384000D03*
X855017Y411969D03*
X861413Y417071D03*
X858827Y419896D03*
X858410Y413890D03*
X858767Y416685D03*
X861622Y419688D03*
X862882Y458991D03*
X854882D03*
X862882Y461791D03*
X854882D03*
X850748Y465382D03*
X861468Y483303D03*
Y487303D03*
X858169Y495032D03*
X853989Y630453D03*
Y632953D03*
X861663Y646653D03*
X855300Y646819D03*
X853982Y657506D03*
X859441Y678015D03*
X849680Y694789D03*
X858186Y701170D03*
X855646Y692710D03*
X864029Y688970D03*
X867455Y710611D03*
X858002Y707244D03*
X857986Y722670D03*
X854484Y746701D03*
X859199Y744517D03*
X854484Y738633D03*
X859000Y756000D03*
X849500Y758500D03*
Y763500D03*
X863443Y753254D03*
X859000Y764000D03*
Y760000D03*
Y774000D03*
X849500Y776500D03*
Y781500D03*
X861425Y770500D03*
X859000Y781000D03*
Y778000D03*
X853282Y789887D03*
X857632Y789385D03*
X859000Y792000D03*
X849500Y794500D03*
Y799500D03*
X861425Y788500D03*
X859000Y800000D03*
Y796000D03*
X861425Y806500D03*
X859000Y810000D03*
X849500Y812500D03*
X859000Y814000D03*
X850496Y831469D03*
X861425Y824500D03*
X849500Y817500D03*
X859000Y818000D03*
X851184Y839459D03*
Y835459D03*
X859165Y848728D03*
X851239Y847459D03*
X851184Y843459D03*
Y863459D03*
X862114Y859479D03*
X851184Y851459D03*
X859603Y863570D03*
X859461Y859459D03*
X851184Y867459D03*
Y871459D03*
Y875459D03*
X859234Y879600D03*
X859463Y866125D03*
X851184Y879459D03*
X849267Y892567D03*
X859614Y883800D03*
Y887846D03*
X850900Y888359D03*
X850800Y883500D03*
X858988Y898307D03*
X855524Y898505D03*
X864253Y918042D03*
X856628D03*
X849600Y918028D03*
X849205Y924129D03*
X867096Y935963D03*
X858601Y934505D03*
X853030Y934690D03*
X851925Y951350D03*
X850686Y1006923D03*
X853449Y1007048D03*
X863334Y1009393D03*
X861047Y1018909D03*
X860887Y1023208D03*
Y1026762D03*
X863956Y1020763D03*
X863689Y1024974D03*
X863944Y1432359D03*
Y1429359D03*
X860944Y1432359D03*
X857944Y1429359D03*
X860944D03*
Y1426359D03*
X857944D03*
X863944D03*
X857944Y1432359D03*
X863944Y1435359D03*
Y1441359D03*
Y1438359D03*
X860944Y1441359D03*
X857944Y1435359D03*
X860944D03*
X857944Y1441359D03*
Y1438359D03*
X860944D03*
X850544Y1447559D03*
X853514Y1457510D03*
X850644Y1457359D03*
X870519Y60438D03*
X867659Y60513D03*
X876200Y86012D03*
X867787Y85731D03*
X865427Y88801D03*
X876200Y94374D03*
X872293Y94279D03*
X868344Y94351D03*
X871341Y86046D03*
X871713Y168665D03*
Y176665D03*
Y196665D03*
Y192665D03*
X871826Y186778D03*
X871745Y204864D03*
Y208864D03*
X867386Y219379D03*
X883118Y262687D03*
X876622Y293721D03*
X872050Y302644D03*
X873262Y300030D03*
X869924Y305368D03*
X879112Y302369D03*
X877977Y305368D03*
Y309368D03*
X869924Y313368D03*
X877977D03*
Y325368D03*
Y317368D03*
Y321368D03*
X869924D03*
Y328722D03*
X874005Y344917D03*
X870413Y342791D03*
X869924Y333722D03*
X877977Y333368D03*
Y329368D03*
X872158Y359962D03*
X868086Y373750D03*
X876736Y383125D03*
X877909Y391731D03*
X880736Y383125D03*
X882925Y391099D03*
X872736Y391754D03*
X867586Y393000D03*
Y385000D03*
X869342Y407627D03*
X868586Y398500D03*
X877253Y420380D03*
X876917Y415322D03*
X879417D03*
X881190Y411619D03*
X878690D03*
X874253Y422880D03*
Y420080D03*
X877253Y422880D03*
X881271Y426952D03*
X878771D03*
X873536Y437408D03*
X876036D03*
X881036D03*
X878536D03*
X873771Y426952D03*
X876271D03*
X870882Y458991D03*
X880910Y454634D03*
Y457434D03*
Y460234D03*
X870882Y461791D03*
X869454Y479303D03*
X869954Y487303D03*
X882954Y486256D03*
X882195Y539204D03*
X867093Y554703D03*
X866938Y549771D03*
X878382Y554942D03*
X874649Y545296D03*
X876949Y571419D03*
X867093Y586828D03*
Y574703D03*
X881476Y588202D03*
X881131Y577349D03*
X875290Y578703D03*
X876351Y605023D03*
Y608523D03*
X879135Y632552D03*
X872862Y666859D03*
X878881Y667156D03*
X876286Y690970D03*
X868919Y700894D03*
X876286Y694970D03*
Y698970D03*
X881157Y749148D03*
X874142Y748914D03*
X879875Y753612D03*
X873728Y752692D03*
X875473Y742056D03*
X878670Y742841D03*
X869325Y761259D03*
X870017Y757313D03*
X867000Y774000D03*
X870000Y780000D03*
X879887Y784719D03*
X880040Y792851D03*
X867000Y792000D03*
X876402Y797415D03*
X874925Y800746D03*
X870035Y801032D03*
X867000Y810000D03*
X879916Y808965D03*
X877407Y828017D03*
X877818Y824214D03*
X876475Y830372D03*
X871600Y898584D03*
X872628Y918042D03*
X876628Y915242D03*
X880628Y918042D03*
X876628D03*
X872126Y934766D03*
X865830Y961600D03*
X870209Y949384D03*
X865973Y978187D03*
X874066Y977928D03*
X875391Y993796D03*
X872183Y993980D03*
X878976Y994020D03*
X871069Y1023114D03*
X878927Y1022387D03*
X878783Y1018751D03*
X872845Y1018988D03*
X866906Y1018751D03*
X866887Y1023208D03*
X875887D03*
X878887Y1026762D03*
X872887D03*
X866887D03*
X869741Y1025895D03*
X873824Y1071604D03*
X871224D03*
X876424D03*
Y1074104D03*
X871224D03*
X873824D03*
X868624Y1071604D03*
Y1074104D03*
X870057Y1091604D03*
X875257D03*
Y1089104D03*
X870057D03*
X872657D03*
X880115Y1084666D03*
X867457Y1091604D03*
Y1089104D03*
X872657Y1091604D03*
X875375Y1107647D03*
X872675D03*
X870075D03*
X867475D03*
X871364Y1120636D03*
X873964D03*
X876564D03*
X879264D03*
X875376Y1110175D03*
X872676D03*
X870076D03*
X867476D03*
X871364Y1139336D03*
X868664D03*
X879264Y1130336D03*
X876564D03*
X873964D03*
X871364D03*
X870522Y1148080D03*
X868022D03*
X875321Y1207654D03*
X872600Y1300833D03*
Y1298333D03*
X872944Y1432359D03*
Y1429359D03*
Y1426359D03*
X869944Y1432359D03*
Y1429359D03*
Y1426359D03*
X866944Y1432359D03*
Y1429359D03*
Y1426359D03*
X872944Y1435359D03*
Y1441359D03*
Y1438359D03*
X869944Y1435359D03*
X866944D03*
X869944Y1441359D03*
Y1438359D03*
X866944Y1441359D03*
Y1438359D03*
X881244Y1448859D03*
Y1440859D03*
X878244Y1451605D03*
X881244Y1464859D03*
Y1453059D03*
Y1456859D03*
X875744Y1453573D03*
X881244Y1476859D03*
X883233Y147540D03*
X887005Y141247D03*
X894472Y143740D03*
X891852Y148277D03*
X893284Y233339D03*
Y236739D03*
X895064Y250186D03*
X891383Y243203D03*
X896034Y243307D03*
X885884Y255118D03*
X897004Y257480D03*
X892484Y260860D03*
X887148Y249670D03*
X896953Y272012D03*
X886496Y268968D03*
X895140Y265236D03*
X886059Y284644D03*
X885918Y289500D03*
X885989Y309368D03*
Y305368D03*
Y317368D03*
X885953Y325368D03*
X885989Y313368D03*
X885953Y321368D03*
Y329368D03*
Y333368D03*
X896592Y358369D03*
Y354369D03*
X888812Y357372D03*
X883552Y357276D03*
X896592Y374369D03*
X891251Y387484D03*
X890553Y392038D03*
X887266Y400158D03*
Y405158D03*
Y402658D03*
X896579Y404043D03*
X893779D03*
X889979Y405743D03*
X890903Y454634D03*
Y457434D03*
Y460234D03*
X891454Y486303D03*
X892931Y534093D03*
X885931D03*
X891449Y547363D03*
X893949D03*
X886549Y553963D03*
X885556Y543664D03*
X887417Y566713D03*
X891673Y600049D03*
X891933Y618143D03*
X895933Y609696D03*
X883309Y666608D03*
X892461Y666671D03*
X886304Y666650D03*
X884903Y696678D03*
X884911Y690279D03*
X886836Y715970D03*
X893241Y704656D03*
X883686Y729778D03*
X889525Y722060D03*
X882098Y741565D03*
X884976Y740891D03*
X884463Y744757D03*
X881637Y744154D03*
X883126Y766124D03*
X883413Y759855D03*
X892040Y784511D03*
X889763Y788159D03*
X898737Y792289D03*
X889516Y792851D03*
X891916Y799605D03*
X884002Y797616D03*
X887916Y800815D03*
X895916Y808965D03*
X883916D03*
X887916D03*
X895829Y800660D03*
X883916Y800815D03*
X890326Y828548D03*
X895050D03*
X889178Y905619D03*
X884628Y915242D03*
Y918042D03*
X896553D03*
X892628Y915242D03*
X888628D03*
Y918042D03*
X882763Y933472D03*
X891367Y941126D03*
X888400Y994579D03*
X894660Y994330D03*
X891343Y994378D03*
X885099Y1021685D03*
X881887Y1023208D03*
X888743Y1019931D03*
X895394Y1026985D03*
X893147Y1020025D03*
X893887Y1023208D03*
X887887D03*
X890887Y1026762D03*
X884887D03*
X882779Y1074104D03*
Y1071604D03*
X887979Y1074104D03*
X885379D03*
X890579D03*
Y1071604D03*
X885379D03*
X887979D03*
X882615Y1084666D03*
X887862Y1088067D03*
X894004Y1081231D03*
X892856Y1102760D03*
X894249Y1114103D03*
X891549D03*
X888949D03*
X886349D03*
Y1123803D03*
X888949D03*
X891549D03*
X894249D03*
X895275Y1132870D03*
X892575D03*
X895547Y1145169D03*
X894713Y1210419D03*
X898878Y1214182D03*
X899286Y1219469D03*
X892532Y1220112D03*
X897169Y1225259D03*
X886888Y1263058D03*
X889388D03*
X891888D03*
X889388Y1260558D03*
X886888D03*
X891888D03*
X886926Y1298712D03*
X889729Y1295516D03*
X891107Y1314305D03*
X887342Y1314990D03*
X889244Y1444859D03*
X892244Y1449636D03*
Y1440859D03*
X889944Y1457959D03*
X889244Y1460859D03*
X895244Y1457510D03*
X889336Y1452554D03*
X893919Y1462132D03*
X889244Y1472859D03*
Y1468859D03*
X903035Y141247D03*
X907522Y143518D03*
X906622Y152373D03*
X909772Y152562D03*
X899573Y158195D03*
X910977Y243307D03*
Y248032D03*
Y262205D03*
X898048Y269387D03*
X913057Y311046D03*
X915653Y307438D03*
X899352Y308560D03*
Y311960D03*
X909298Y302347D03*
X905898D03*
X898533Y334498D03*
X908521Y356708D03*
X908625Y359317D03*
X905483Y355262D03*
X905000Y362158D03*
X898869Y351114D03*
X906161Y367191D03*
X913288Y372752D03*
X910646Y376084D03*
X906344Y372524D03*
X911072Y386992D03*
X897736Y383125D03*
X901747Y398492D03*
Y403492D03*
Y400992D03*
X910250Y457262D03*
Y454462D03*
X907450D03*
Y457262D03*
X910250Y451662D03*
X907450D03*
X910250Y460062D03*
X907450D03*
X910236Y465272D03*
X910759Y475511D03*
X899931Y534093D03*
X899530Y530753D03*
X914296Y558143D03*
X913728Y550495D03*
X899407Y560019D03*
X908846Y560124D03*
X910789Y598726D03*
X898207Y599891D03*
X900676Y621536D03*
X904076D03*
X909508Y621616D03*
X912908D03*
X900753Y656925D03*
X912462Y683770D03*
X909265Y677795D03*
X912462Y687770D03*
X906886Y702285D03*
X902236Y689332D03*
Y694332D03*
X908699Y709387D03*
X913247Y714204D03*
X902841Y703665D03*
X910836Y721570D03*
X913858Y721289D03*
X907866Y795572D03*
X911028Y796598D03*
X909785Y810778D03*
X903916Y810809D03*
X913716Y811954D03*
X899916Y808965D03*
X902641Y800748D03*
X907884Y829866D03*
X908920Y905630D03*
X900628Y918042D03*
X912628Y915242D03*
X908628Y918042D03*
X900628Y915242D03*
X912628Y918042D03*
X904838D03*
X908628Y915242D03*
X900983Y940895D03*
X903759Y951358D03*
X909811Y962400D03*
X913005Y969605D03*
X912690Y994350D03*
X897825Y994413D03*
X909166Y994188D03*
X897717Y1019915D03*
X899887Y1023208D03*
Y1026762D03*
X908422Y1023103D03*
X908856Y1017677D03*
X902389Y1081764D03*
X908799Y1093659D03*
Y1088659D03*
X908278Y1083484D03*
X908799Y1096659D03*
Y1100659D03*
X902353Y1104333D03*
X898278Y1136426D03*
X898047Y1145169D03*
X903959Y1207823D03*
X906784Y1216607D03*
X913784Y1221057D03*
X910633Y1222799D03*
X906309Y1226647D03*
X909077Y1232724D03*
X899699Y1283872D03*
X910788Y1299456D03*
X906506Y1299188D03*
X902908Y1299828D03*
X911117Y1314130D03*
X902875Y1309301D03*
X905740Y1309264D03*
X908700Y1316300D03*
X911135Y1345560D03*
X904177Y1359955D03*
X899944Y1432359D03*
X908944Y1426359D03*
Y1429359D03*
Y1432359D03*
X911944Y1426359D03*
Y1429359D03*
Y1432359D03*
X905944Y1426359D03*
X899944D03*
X902944D03*
Y1429359D03*
X899944D03*
X902944Y1432359D03*
X905944Y1429359D03*
Y1432359D03*
X902944Y1438359D03*
X899944D03*
Y1441359D03*
X902944Y1435359D03*
X899944D03*
X908944Y1438359D03*
Y1441359D03*
X911944Y1438359D03*
Y1441359D03*
X902944D03*
X905944Y1438359D03*
Y1441359D03*
X908944Y1435359D03*
X911944D03*
X905944D03*
X919175Y116594D03*
X930118Y110784D03*
X925118D03*
X919175Y119594D03*
X924675Y124879D03*
X929697Y124663D03*
X919609Y124283D03*
X931041Y138838D03*
X918016Y161306D03*
X915267Y157370D03*
X916453Y167975D03*
X927898Y203256D03*
X925098D03*
X919577Y240945D03*
Y250394D03*
Y271654D03*
X919616Y268462D03*
X919577Y264567D03*
X923732Y304585D03*
X917882Y328216D03*
Y324816D03*
X915954Y344150D03*
X916229Y336333D03*
X919354Y344150D03*
X919629Y336333D03*
X927964Y344041D03*
X924564D03*
X923311Y349959D03*
X929943Y372600D03*
X921343Y376888D03*
X916330Y377748D03*
X929947Y376821D03*
X915072Y386992D03*
X914323Y398551D03*
Y403551D03*
Y401051D03*
X927563Y424445D03*
X924763D03*
X921963D03*
X927280Y436716D03*
X921680D03*
X924480D03*
X917541Y441280D03*
Y443780D03*
X927766Y456442D03*
X927596Y447453D03*
X921973Y469328D03*
X927401Y469059D03*
X916593Y469140D03*
X928999Y477948D03*
X920999D03*
X924999D03*
X917811Y544325D03*
X923453Y569578D03*
X923642Y561578D03*
X919080Y587640D03*
X921507Y578791D03*
X919038Y579378D03*
X923599Y581578D03*
X921217Y589216D03*
X913998Y597103D03*
X925949Y612363D03*
Y608863D03*
X922626Y633772D03*
X915800Y629700D03*
X918300D03*
X929690Y666593D03*
X920090Y666714D03*
X928353Y686342D03*
X928704Y680261D03*
X921061Y715386D03*
X926961Y723797D03*
X914202Y797460D03*
X923872Y798271D03*
X922352Y800809D03*
X917803Y811365D03*
X927916Y800909D03*
X929790Y828603D03*
X927916Y817015D03*
X925228Y816934D03*
X929181Y895029D03*
X921451Y903800D03*
X920628Y918042D03*
X916628D03*
X924628D03*
X928628D03*
X924628Y915242D03*
X920628D03*
X928628D03*
X916628D03*
X914193Y945318D03*
X928227Y951125D03*
X921364Y951251D03*
X918265Y969745D03*
X923289Y965780D03*
X926796Y966297D03*
X929741Y967006D03*
X916932Y994405D03*
X924956Y994321D03*
X924864Y1026762D03*
Y1023208D03*
X925024Y1018909D03*
X927861Y1024768D03*
X916749Y1084659D03*
X916992Y1076659D03*
X916749Y1092664D03*
X916875Y1098643D03*
X916749Y1104659D03*
X914637Y1210568D03*
Y1214838D03*
X930754Y1310564D03*
X924650Y1327819D03*
Y1324419D03*
X914033Y1345613D03*
X927193Y1361547D03*
X931159Y1379427D03*
X920360Y1387039D03*
X920255Y1383264D03*
X931199Y1371951D03*
X931159Y1390827D03*
Y1406027D03*
X914944Y1426359D03*
Y1429359D03*
Y1432359D03*
Y1438359D03*
Y1441359D03*
Y1435359D03*
X921498Y1446692D03*
X925697Y1460109D03*
X917744Y1453573D03*
X920244Y1451605D03*
X919285Y1456226D03*
X924803Y1474743D03*
X925435Y1478114D03*
X940761Y97667D03*
X945011Y95111D03*
X931144Y116594D03*
X936417Y102495D03*
X931144Y119594D03*
X942561Y118342D03*
Y132515D03*
Y121742D03*
X934678Y125107D03*
X942561Y135915D03*
X936151Y142862D03*
X943292Y143762D03*
X937192Y148717D03*
X945406Y180347D03*
X940406D03*
X942906D03*
X947424Y184419D03*
X944424Y186919D03*
X944760Y191977D03*
X942260D03*
X940487Y195680D03*
X942987D03*
X944424Y184419D03*
X934411Y202141D03*
X931698Y201556D03*
X934411Y207141D03*
X934477Y211491D03*
X934411Y204641D03*
X946234Y213390D03*
X942179Y215727D03*
X937438Y213817D03*
X936395Y218142D03*
X933403Y245507D03*
X936962Y249807D03*
X944248Y239844D03*
X945018Y276051D03*
X943183Y281652D03*
X930727Y302571D03*
X937000Y312284D03*
Y315684D03*
X942731Y324044D03*
X939331D03*
X940997Y331912D03*
Y335312D03*
X942700Y346363D03*
X939300D03*
X934128Y355168D03*
X934464Y358618D03*
X944238Y360828D03*
X934047Y369160D03*
X936175Y364823D03*
X931072Y386992D03*
X941872Y440942D03*
X933424Y458455D03*
X933161Y451442D03*
X933404Y463462D03*
X933412Y468942D03*
X936653Y526836D03*
X944351Y534211D03*
X948532Y541135D03*
X939992Y527726D03*
Y548726D03*
Y544726D03*
X948598Y546553D03*
X948621Y552726D03*
X931627Y557641D03*
Y569578D03*
Y581578D03*
Y577578D03*
Y573578D03*
X933725Y585936D03*
X933741Y598087D03*
Y594687D03*
X933725Y589336D03*
X944296Y611071D03*
X941859Y621311D03*
Y629311D03*
X943181Y632536D03*
X945434Y634325D03*
X941859Y625311D03*
X946128Y666522D03*
X935281Y680945D03*
X936026Y727450D03*
X933974Y719371D03*
X942676Y789286D03*
X933201Y798297D03*
X946970Y786366D03*
X944916Y808965D03*
X938357Y808856D03*
X931916Y817015D03*
X942858Y819430D03*
X945736Y819397D03*
X935124Y831382D03*
X940100Y830700D03*
X935262Y825135D03*
X932418D03*
X940716Y840074D03*
X944297Y839975D03*
X933021Y840893D03*
X933054Y843804D03*
X937200Y841000D03*
X936450Y858327D03*
X937551Y860801D03*
X932770Y878233D03*
X935765Y878317D03*
X934928Y871727D03*
X932319Y871626D03*
X938729Y874396D03*
X945982Y886737D03*
X932300Y890200D03*
X942194Y891216D03*
X930800Y904840D03*
X941592Y900908D03*
X936628Y915242D03*
X940628D03*
X932628D03*
X936628Y918042D03*
X932628D03*
X936371Y951484D03*
X940716Y951733D03*
X946363Y951179D03*
X935255Y962725D03*
X945671Y982191D03*
X940015Y1020176D03*
X934911Y1023579D03*
X945864Y1023208D03*
X930864Y1026762D03*
X936864D03*
X942864D03*
X939864Y1023208D03*
X930864D03*
X930883Y1018751D03*
X936822Y1018988D03*
X942760Y1018751D03*
X943093Y1021769D03*
X932289Y1074182D03*
Y1071682D03*
X937489Y1074182D03*
X934889D03*
X940089D03*
Y1071682D03*
X934889D03*
X937489D03*
X944092Y1084666D03*
X931628Y1091409D03*
Y1088909D03*
X936828Y1091409D03*
X934228D03*
X939428D03*
Y1088909D03*
X934228D03*
X936828D03*
X943241Y1120636D03*
X940541D03*
X937941D03*
X935341D03*
X937941Y1130336D03*
X940541D03*
X943241D03*
X932641Y1139336D03*
X935341Y1130336D03*
Y1139336D03*
X934500Y1147708D03*
X932000D03*
X939298Y1207654D03*
X943891Y1306608D03*
X944207Y1320739D03*
X947308Y1325035D03*
X931137Y1375878D03*
X931159Y1383227D03*
X939559Y1398427D03*
X931159Y1394627D03*
Y1387027D03*
Y1398427D03*
Y1402227D03*
X939559D03*
X944235Y1406262D03*
X943725Y1430744D03*
Y1427744D03*
X934725Y1430744D03*
X940725Y1427744D03*
Y1430744D03*
X934725Y1427744D03*
X937725D03*
Y1430744D03*
X943725Y1433744D03*
Y1439744D03*
Y1436744D03*
X940725Y1433744D03*
Y1439744D03*
Y1436744D03*
X934725Y1433744D03*
X937725D03*
X934725Y1439744D03*
X937725D03*
X934725Y1436744D03*
X937725D03*
X937671Y1492139D03*
Y1488139D03*
X949221Y103411D03*
X949615Y97667D03*
X960411Y90650D03*
X960161Y95236D03*
X949861Y111255D03*
Y114655D03*
X949380Y106561D03*
X949861Y125428D03*
Y128828D03*
X947906Y180347D03*
X947424Y187219D03*
X950177Y215730D03*
X947040Y223885D03*
X948741Y229468D03*
X948785Y242464D03*
X951278Y250583D03*
X946482Y255940D03*
X949974Y291554D03*
X947733Y319680D03*
X950953Y317947D03*
X960376Y392807D03*
X962769Y451419D03*
X959816Y472905D03*
X955816Y473419D03*
Y464919D03*
X963816Y464419D03*
X962563Y485128D03*
X954182Y481467D03*
X958124Y492354D03*
X958736Y482165D03*
X958974Y504825D03*
X956474D03*
X953974D03*
X949823Y491982D03*
X959600Y496486D03*
X949823Y495982D03*
X957977Y500202D03*
X958915Y517401D03*
X956415D03*
X953915D03*
X959466Y522569D03*
Y525369D03*
X958081Y531882D03*
X955581D03*
X961166Y529169D03*
X952531Y531948D03*
X960581Y531882D03*
X948905Y534909D03*
X958016Y555194D03*
X960816D03*
X958016Y563194D03*
X960816D03*
Y571194D03*
X958016D03*
X959573Y581222D03*
X962373D03*
X959573Y591215D03*
X962373D03*
X962545Y607762D03*
X959745D03*
Y610562D03*
X962545D03*
X950479Y622285D03*
X954535Y610548D03*
X950667Y616905D03*
X963365Y628078D03*
X961352Y633736D03*
X950865Y633724D03*
X950748Y627713D03*
X956345Y633716D03*
X949137Y666660D03*
X954526Y666671D03*
X947556Y699550D03*
X956023Y706907D03*
X951151Y730111D03*
X963869Y725057D03*
X955950Y734178D03*
X957763Y725336D03*
X959950Y734178D03*
X957579Y744168D03*
X953837Y763025D03*
X950699Y779711D03*
X956017Y770300D03*
X957500Y780800D03*
X955076Y784861D03*
X950475Y789361D03*
X955225Y788984D03*
X949609Y796051D03*
X957487Y798553D03*
X951461Y812223D03*
X951791Y808121D03*
X957379Y826586D03*
X954760Y826734D03*
X951708Y818894D03*
X955712Y833988D03*
X956239Y829577D03*
X960100Y846665D03*
X954700Y837700D03*
X961175Y838525D03*
X955343Y866850D03*
X955850Y862902D03*
X957900Y856300D03*
X950300Y877800D03*
X953240Y876834D03*
X949382Y886737D03*
X954567Y927654D03*
X964280Y927777D03*
X958567Y927654D03*
X947029Y915242D03*
X959545Y918306D03*
X951863Y936168D03*
X957235Y936398D03*
X962329Y936229D03*
X957671Y977921D03*
X949671D03*
X961671Y991564D03*
X953671D03*
X949671D03*
X953671Y982191D03*
X954937Y1021998D03*
X948864Y1026762D03*
X954864D03*
X951864Y1023208D03*
X957864D03*
X957678Y1018555D03*
X961208Y1018592D03*
X960636Y1021917D03*
X959371Y1026985D03*
X948975Y1021325D03*
X951956Y1071604D03*
X949356D03*
X954556D03*
Y1074104D03*
X949356D03*
X951956D03*
X946756Y1071604D03*
Y1074104D03*
X946592Y1084666D03*
X957981Y1081231D03*
X951839Y1088067D03*
X956833Y1102760D03*
X950326Y1114103D03*
Y1123803D03*
X952926D03*
X955526D03*
Y1114103D03*
X958226D03*
X952926D03*
X958226Y1123803D03*
X956552Y1132870D03*
X959252D03*
X962255Y1136426D03*
X962024Y1145169D03*
X959524D03*
X958690Y1210419D03*
X963263Y1219469D03*
X962855Y1214182D03*
X956509Y1220112D03*
X961146Y1225259D03*
X950865Y1263058D03*
X953365D03*
X955865D03*
X953365Y1260558D03*
X950865D03*
X955865D03*
X948259Y1295965D03*
X948832Y1371654D03*
X951832D03*
X952561Y1383465D03*
X952417Y1379528D03*
X949469D03*
X949385Y1375591D03*
X952385D03*
X952514Y1391339D03*
X952395Y1395276D03*
X952716Y1387402D03*
X952180Y1407087D03*
X950239Y1409555D03*
X948235Y1406262D03*
X946725Y1427744D03*
Y1430744D03*
X949725D03*
Y1427744D03*
X960883Y1427997D03*
Y1430997D03*
X946725Y1433744D03*
X949725D03*
X946725Y1439744D03*
X949725D03*
X946725Y1436744D03*
X949725D03*
X960883Y1433997D03*
Y1436997D03*
Y1439997D03*
X952695Y1444139D03*
X979002Y92874D03*
X965723Y90615D03*
X970094Y95236D03*
X970044Y99961D03*
X978051Y162368D03*
X968906Y207978D03*
Y212978D03*
Y215478D03*
Y210478D03*
X970865Y264068D03*
X973365D03*
X972160Y258880D03*
X977150Y331972D03*
Y338972D03*
X975631Y343112D03*
Y346612D03*
X971721Y407762D03*
X968348Y402369D03*
X971826Y430187D03*
X966694Y427599D03*
X968462Y429368D03*
X970840Y457339D03*
X968340D03*
X962816Y442919D03*
X972030Y446071D03*
X979910Y445603D03*
X970840Y459839D03*
Y462339D03*
X968340D03*
Y459839D03*
X963816Y472905D03*
X976397Y473045D03*
X972397Y465004D03*
X977327Y462371D03*
X965412Y485138D03*
X969297Y478625D03*
Y475825D03*
X970997Y482425D03*
X970412Y485138D03*
X967912D03*
X976873Y491214D03*
Y493714D03*
X970745Y539731D03*
X967042Y537658D03*
X970745Y542231D03*
X978303Y541895D03*
X975803D03*
X967042Y540458D03*
X975503Y544895D03*
X978303D03*
X978581Y582747D03*
X965173Y581222D03*
X978032Y590801D03*
X965173Y591215D03*
X977857Y597130D03*
X976027Y620653D03*
Y617853D03*
X968145Y610562D03*
X965345Y607762D03*
Y610562D03*
X968145Y607762D03*
X977857Y605443D03*
X973857D03*
X972354Y627908D03*
X968365Y633473D03*
X978865Y642184D03*
X966797Y667653D03*
X970197D03*
X965774Y706907D03*
X973712Y722064D03*
X968589Y722434D03*
X970839Y729923D03*
X965042Y722234D03*
X971081Y722637D03*
X978352Y730766D03*
X963950Y734178D03*
X973450Y747280D03*
X965983Y763567D03*
X966127Y776382D03*
X968094Y799792D03*
X976186Y789819D03*
X967562Y802982D03*
X978978Y817618D03*
X978214Y821224D03*
X967337Y828901D03*
X970040Y842903D03*
X969309Y839334D03*
X974437Y849140D03*
X973510Y834991D03*
X967842Y864801D03*
X970299Y853773D03*
X978880Y869552D03*
X967510Y868971D03*
X966813Y904556D03*
X973988Y910038D03*
X968507Y937615D03*
X971443Y938828D03*
X965671Y991564D03*
Y982191D03*
X963864Y1026762D03*
Y1023208D03*
X966366Y1081764D03*
X972776Y1093659D03*
X972255Y1083484D03*
X972776Y1088659D03*
Y1096659D03*
X966330Y1104333D03*
X972776Y1100659D03*
X967936Y1207823D03*
X978614Y1210568D03*
X970761Y1216607D03*
X978614Y1214838D03*
X978169Y1221268D03*
X974985Y1290950D03*
X979996Y1386100D03*
X963883Y1430997D03*
Y1427997D03*
X966883Y1430997D03*
Y1427997D03*
X969883D03*
Y1430997D03*
X975883Y1427997D03*
Y1430997D03*
X972883D03*
Y1427997D03*
X963883Y1433997D03*
X966883D03*
X969883D03*
X963883Y1436997D03*
Y1439997D03*
X966883Y1436997D03*
Y1439997D03*
X969883Y1436997D03*
Y1439997D03*
X975883Y1433997D03*
X972883D03*
X975883Y1436997D03*
X972883D03*
X975883Y1439997D03*
X972883D03*
X977547Y1546081D03*
X974547D03*
X971547D03*
X978958Y85193D03*
Y82593D03*
Y77393D03*
Y74793D03*
Y79993D03*
X987283Y98551D03*
X990178Y114623D03*
Y111223D03*
X990833Y103783D03*
X981029Y104249D03*
Y107649D03*
X990178Y128796D03*
Y125396D03*
X985595Y147540D03*
X989367Y141247D03*
X996834Y143740D03*
X994214Y148277D03*
X980651Y162368D03*
X987751Y162793D03*
Y165393D03*
Y167993D03*
Y170493D03*
X995256Y172190D03*
X994675Y177616D03*
X989959Y181366D03*
X986748Y181426D03*
X992754Y181009D03*
X986956Y184221D03*
X989573Y184012D03*
X994695Y213132D03*
X979362Y208213D03*
Y210713D03*
Y213213D03*
X986234Y208695D03*
X983434D03*
X985934Y211695D03*
X990992Y213859D03*
Y211359D03*
X983434Y211695D03*
X979362Y215713D03*
X994695Y215632D03*
X994939Y256303D03*
X989611Y265701D03*
X994698Y265896D03*
X986429Y270026D03*
X983929D03*
X981129D03*
X983929Y267526D03*
X986429D03*
X981129D03*
X991246Y281716D03*
X997187Y281982D03*
X987517Y314092D03*
X993552Y318175D03*
X990420Y340454D03*
Y337954D03*
X989630Y343862D03*
X983717Y341665D03*
X983956Y346652D03*
X993026Y353813D03*
X981719Y352217D03*
X988631Y349496D03*
X980045Y366559D03*
X986373Y370467D03*
X991392Y409230D03*
X985303Y464652D03*
Y462152D03*
Y459652D03*
X987803Y464652D03*
Y462152D03*
Y459652D03*
X981843Y464818D03*
X992206Y491133D03*
Y498633D03*
X988134Y495151D03*
X985634D03*
X980576Y492987D03*
X985334Y498151D03*
X980576Y495487D03*
X988134Y498151D03*
X992206Y493633D03*
Y496133D03*
X982375Y537877D03*
X992306Y555897D03*
Y553297D03*
X989888Y548366D03*
X987388D03*
X982388D03*
X984888D03*
X982375Y542877D03*
Y545377D03*
Y540377D03*
X992306Y561097D03*
Y563697D03*
Y566797D03*
Y558497D03*
X986301Y570686D03*
X989096Y570478D03*
X989513Y576484D03*
X989156Y573689D03*
X986510Y573303D03*
X992906Y578405D03*
X981857Y597232D03*
X991907Y596782D03*
X986688Y596089D03*
X983843Y619513D03*
Y616713D03*
Y613913D03*
X993857Y605443D03*
X981857Y605637D03*
X980703Y625013D03*
X986600Y717641D03*
X987461Y745796D03*
X981876Y745179D03*
X988371Y764143D03*
X983786Y765647D03*
X984357Y777555D03*
X997051Y778833D03*
X990699Y778630D03*
X987990Y774005D03*
X987394Y787490D03*
X987501Y812573D03*
X985921Y805135D03*
X994051Y810871D03*
X996385Y816141D03*
X979203Y829159D03*
X994094Y829000D03*
X982300Y821200D03*
X987702Y829159D03*
X989700Y846500D03*
X987202Y846395D03*
X987319Y843589D03*
X979203Y833159D03*
X989800Y843900D03*
X987200Y848940D03*
X987703Y837159D03*
X990457Y852043D03*
X983269Y853883D03*
X981700Y856300D03*
X979891Y876589D03*
X992441Y870398D03*
X988054Y888283D03*
X990300Y897500D03*
X979592Y902849D03*
X982783Y909995D03*
X979498Y907500D03*
X989311Y920364D03*
X983227Y968565D03*
X988240Y1020015D03*
Y1016923D03*
Y1023968D03*
X984909Y1081071D03*
X983751Y1078675D03*
X980969Y1076659D03*
X980726Y1084659D03*
X980852Y1098643D03*
X980726Y1104659D03*
Y1092664D03*
X986645Y1108465D03*
X989513Y1097683D03*
X995009Y1131223D03*
X991763Y1140378D03*
Y1128378D03*
Y1134378D03*
X984558Y1140774D03*
X988112Y1137774D03*
X984558Y1128774D03*
Y1134774D03*
X987804Y1131619D03*
X984817Y1303297D03*
X979001Y1288925D03*
X990613Y1324248D03*
Y1327048D03*
X993413Y1324248D03*
Y1327048D03*
X990501Y1320756D03*
X988784Y1361974D03*
X980139Y1381496D03*
X980166Y1373622D03*
X980203Y1377559D03*
X980047Y1397245D03*
X985448Y1398271D03*
X980092Y1389370D03*
X980139Y1393308D03*
X984136Y1401636D03*
X987136D03*
X986949Y1430997D03*
Y1427997D03*
X983949D03*
X989949Y1430997D03*
Y1427997D03*
X983949Y1430997D03*
X992949Y1427997D03*
Y1430997D03*
X986949Y1433997D03*
X983949D03*
X989949D03*
X992949D03*
X986949Y1436997D03*
X983949D03*
X986949Y1439997D03*
X983949D03*
X989949Y1436997D03*
Y1439997D03*
X992949Y1436997D03*
Y1439997D03*
X978934Y1444392D03*
X978987Y1489832D03*
X982241Y1489637D03*
X986773Y1546081D03*
X983773D03*
X980773D03*
X1011187Y-33526D03*
Y-30126D03*
X1011284Y68581D03*
X1011297Y80581D03*
X1003379Y72615D03*
Y76587D03*
X1004818Y100625D03*
X997837Y97475D03*
X1013480Y103621D03*
X997768Y106186D03*
X1009191Y112083D03*
X1000580Y121735D03*
Y118335D03*
Y132509D03*
Y135909D03*
X1005397Y141247D03*
X1009884Y143518D03*
X1008984Y152373D03*
X1012936Y178560D03*
X997929Y168697D03*
X1012826Y183834D03*
X1012999Y172665D03*
X999017Y191941D03*
X1003029Y192300D03*
X1012346Y190185D03*
X1007071Y192490D03*
X1013116Y200864D03*
X1003526Y206767D03*
X1006026D03*
X1001026D03*
X1010291Y199582D03*
X1013139Y207037D03*
X1013205Y212455D03*
X1002271Y228221D03*
Y231021D03*
X1010506Y221642D03*
X1003656Y221708D03*
X1006156D03*
X1000571Y224421D03*
X1001156Y221708D03*
X1002822Y236189D03*
X1005322D03*
X1007822D03*
X1002763Y248765D03*
X1005263D03*
X1007763D03*
X999714Y266114D03*
X1008260Y268195D03*
X1005460D03*
X1002960D03*
X1008260Y270695D03*
X1002960D03*
X1005460D03*
X1000698Y300276D03*
X1002580Y309619D03*
X1010499Y309062D03*
X1003181Y323057D03*
X1001105Y318006D03*
X1009770Y344486D03*
X997020Y345354D03*
X1003076Y332496D03*
X1000420Y353954D03*
X996024Y352132D03*
X1001825Y581659D03*
X998332Y578986D03*
X997857Y596729D03*
X995913Y619758D03*
Y616958D03*
Y614158D03*
X1001857Y605443D03*
X1003900Y628700D03*
X1001605Y627605D03*
X1005800Y637600D03*
X1002883Y622521D03*
X1001676Y678015D03*
X1011185Y724519D03*
X1009562Y722438D03*
X1003990Y765899D03*
X1007990D03*
X1002751Y757169D03*
X999990Y764566D03*
X1013151Y756726D03*
X1012695Y776728D03*
X999990Y774671D03*
X1013319Y785929D03*
X1007027Y792973D03*
X998376Y810970D03*
X1006054Y810969D03*
X1010699Y803454D03*
X1002699Y819475D03*
X1011144Y844340D03*
X1010977Y841737D03*
X1012703Y837659D03*
X1001187Y850084D03*
X1004577Y853679D03*
X1004713Y871389D03*
X998313Y888295D03*
X1005413Y905295D03*
X1004953Y923995D03*
X1008935Y924007D03*
X1004994Y955372D03*
X1007919Y948822D03*
X1011019D03*
X1004719D03*
X1012219Y954222D03*
X1006222Y980337D03*
X1009564Y988874D03*
X999879Y998507D03*
X1001805Y1007522D03*
X1008571Y1006648D03*
X1008759Y1023900D03*
X1002180Y1013678D03*
X1002652Y1023731D03*
X1005938Y1018307D03*
X995317Y1137378D03*
X996213Y1324248D03*
Y1327048D03*
X1009333Y1346693D03*
Y1343293D03*
X998600Y1369200D03*
X1008387Y1380797D03*
X998600Y1373400D03*
X997401Y1381200D03*
X999283Y1377400D03*
X1007850Y1368835D03*
X998643Y1398271D03*
X1008138Y1407186D03*
Y1409986D03*
X1005338Y1407186D03*
Y1409986D03*
X1008138Y1415586D03*
Y1412786D03*
X1005338Y1415586D03*
Y1412786D03*
X1008138Y1418386D03*
X1005338D03*
X998949Y1427997D03*
Y1430997D03*
X995949D03*
Y1427997D03*
X1009981Y1431097D03*
Y1428097D03*
X1006981D03*
Y1431097D03*
X998949Y1433997D03*
X995949D03*
X998949Y1436997D03*
X995949D03*
X998949Y1439997D03*
X995949D03*
X1009981Y1434097D03*
X1006981D03*
X1009981Y1437097D03*
X1006981D03*
X1009981Y1440097D03*
X1006981D03*
X1002194Y1444392D03*
X1015059Y55513D03*
X1020519Y60438D03*
X1017659Y60513D03*
X1026200Y86012D03*
X1017787Y85731D03*
X1026200Y94374D03*
X1015427Y88801D03*
X1022293Y94279D03*
X1018344Y94351D03*
X1021341Y86046D03*
X1021537Y116594D03*
X1027480Y110784D03*
X1021537Y119594D03*
X1021971Y124283D03*
X1027037Y124879D03*
X1020378Y161306D03*
X1012134Y152562D03*
X1017629Y157370D03*
X1021713Y176665D03*
Y168665D03*
X1013812Y186629D03*
X1021713Y196665D03*
X1021826Y186778D03*
X1021713Y192665D03*
X1021745Y204864D03*
Y208864D03*
X1026794Y218085D03*
X1017386Y219379D03*
X1018014Y228631D03*
X1023502Y248371D03*
X1014420Y265897D03*
X1011920D03*
X1027216Y289440D03*
X1022604Y290262D03*
X1016635Y300276D03*
X1012635D03*
X1025749D03*
X1020635D03*
X1022435Y312865D03*
X1021848Y310396D03*
X1020406Y350772D03*
X1012188Y443421D03*
X1015659Y679654D03*
Y683054D03*
X1021885Y698974D03*
X1022937Y691421D03*
X1014641Y724436D03*
X1012851Y722417D03*
X1026916Y719769D03*
X1018015Y751565D03*
X1013486Y750773D03*
X1024684Y756485D03*
X1017664Y779101D03*
X1014064Y793660D03*
X1018071Y798490D03*
X1013821Y813520D03*
X1014781Y810319D03*
X1017955Y812097D03*
X1021895Y818974D03*
X1020703Y837659D03*
X1013918Y851306D03*
X1017800Y867065D03*
X1016973Y877196D03*
X1016574Y874537D03*
X1016798Y890299D03*
X1021408Y895008D03*
X1024913Y884000D03*
X1012842Y910685D03*
X1022346Y917669D03*
X1029570Y917718D03*
X1018419Y917575D03*
X1014719Y938322D03*
X1027319D03*
X1027719Y958822D03*
X1014009Y980356D03*
X1018009D03*
X1014009Y988813D03*
X1018009D03*
X1021924Y980456D03*
X1026009Y988813D03*
X1022009D03*
X1017998Y1009655D03*
X1015198D03*
X1024570Y1024003D03*
X1011782Y1016591D03*
X1022143Y1030672D03*
X1019143D03*
X1016143D03*
X1025143D03*
X1023144Y1109564D03*
X1017297D03*
X1023144Y1122164D03*
X1017297D03*
X1023144Y1134764D03*
X1017297D03*
X1023144Y1147364D03*
X1017297D03*
X1023144Y1159964D03*
X1017297D03*
Y1172564D03*
X1023162Y1174445D03*
X1023139Y1184856D03*
X1017297Y1185164D03*
X1026221Y1214372D03*
X1021976Y1218169D03*
X1023358Y1363921D03*
X1013991Y1360842D03*
X1019391Y1377061D03*
X1012981Y1431097D03*
Y1428097D03*
X1015981D03*
Y1431097D03*
X1021981Y1428097D03*
Y1431097D03*
X1018981D03*
Y1428097D03*
X1012981Y1434097D03*
X1015981D03*
X1012981Y1437097D03*
Y1440097D03*
X1015981Y1437097D03*
Y1440097D03*
X1021981Y1434097D03*
X1018981D03*
X1021981Y1437097D03*
X1018981D03*
X1021981Y1440097D03*
X1018981D03*
X1025615Y1444492D03*
X1020023Y1489637D03*
X1016769Y1489832D03*
X1043123Y97667D03*
X1033506Y116594D03*
X1038779Y102495D03*
X1032480Y110784D03*
X1033506Y119594D03*
X1037040Y125107D03*
X1032059Y124663D03*
X1038513Y142862D03*
X1045654Y143762D03*
X1039554Y148717D03*
X1033403Y138838D03*
X1042102Y195176D03*
X1042183Y210509D03*
X1029594Y218085D03*
X1036107Y221970D03*
X1036173Y226320D03*
X1036107Y219470D03*
Y216970D03*
X1033394Y216385D03*
X1043875Y230556D03*
X1039134Y228646D03*
X1042860Y242078D03*
X1038091Y232971D03*
X1034741Y244571D03*
X1032121Y249108D03*
X1042084Y256394D03*
X1037290Y296293D03*
X1033890D03*
X1045650Y300093D03*
X1029639Y300141D03*
X1041783Y321114D03*
X1030220Y313554D03*
X1042948Y333696D03*
X1043106Y340230D03*
X1031259Y350427D03*
X1029885Y711762D03*
X1033200Y731700D03*
X1035619Y755809D03*
X1038344Y756476D03*
X1043016Y782161D03*
X1038678Y776750D03*
X1039251Y812340D03*
X1042414Y801443D03*
X1043425Y830800D03*
X1043626Y836563D03*
X1041100Y838500D03*
X1037527Y836486D03*
X1031813Y850273D03*
X1046045Y841217D03*
X1040822Y841339D03*
X1044390Y861210D03*
X1035185Y862793D03*
X1037685Y862789D03*
X1038363Y875288D03*
X1037709Y886209D03*
X1038010Y902565D03*
X1033019Y933022D03*
Y935822D03*
X1030819Y938422D03*
X1033370Y953994D03*
X1038009Y988813D03*
X1030009D03*
X1042009D03*
X1034009D03*
X1028943Y1016827D03*
X1034790D03*
X1028943Y1029427D03*
X1034790D03*
X1039499Y1098758D03*
X1039053Y1105091D03*
X1044553D03*
X1039098Y1102091D03*
X1039053Y1117691D03*
X1044553D03*
X1039098Y1114691D03*
Y1127291D03*
X1039053Y1130291D03*
X1044553D03*
Y1142891D03*
X1039098Y1139891D03*
X1039053Y1142891D03*
Y1155491D03*
X1044553D03*
X1039098Y1152491D03*
X1044553Y1168091D03*
X1039053D03*
X1039098Y1165091D03*
X1044553Y1180691D03*
X1039053D03*
X1039098Y1177691D03*
X1032831Y1207950D03*
X1029797Y1220921D03*
X1040606Y1230407D03*
X1043588Y1227300D03*
X1032867Y1431213D03*
Y1428213D03*
X1029867D03*
X1035867Y1431213D03*
Y1428213D03*
X1029867Y1431213D03*
X1038867Y1428213D03*
Y1431213D03*
X1041867D03*
Y1428213D03*
X1032867Y1434213D03*
X1029867D03*
X1035867D03*
X1038867D03*
X1032867Y1437213D03*
X1029867D03*
X1032867Y1440213D03*
X1029867D03*
X1035867Y1437213D03*
Y1440213D03*
X1038867Y1437213D03*
Y1440213D03*
X1041867Y1434213D03*
Y1437213D03*
Y1440213D03*
X1051583Y103411D03*
X1051977Y97667D03*
X1047373Y95111D03*
X1052223Y111255D03*
Y114655D03*
X1051742Y106561D03*
X1044923Y118342D03*
X1052223Y125428D03*
Y128828D03*
X1044923Y132515D03*
Y121742D03*
Y135915D03*
X1047102Y195176D03*
X1046120Y199248D03*
X1044602Y195176D03*
X1049120Y199248D03*
X1049602Y195176D03*
X1046120Y201748D03*
X1049120Y202048D03*
X1044683Y210509D03*
X1046456Y206806D03*
X1043956D03*
X1052720Y230117D03*
X1048130Y227824D03*
X1048736Y238714D03*
X1048217Y246874D03*
X1050437Y244297D03*
X1045364Y279895D03*
X1051796Y279965D03*
X1050164Y302748D03*
X1050076Y305512D03*
X1061387Y343509D03*
X1060679Y356151D03*
X1054863Y401513D03*
Y398113D03*
X1052463Y412287D03*
Y415687D03*
Y426460D03*
Y440633D03*
Y429860D03*
Y444033D03*
X1059549Y458711D03*
X1052463Y469387D03*
Y472787D03*
Y486960D03*
Y483560D03*
Y513521D03*
Y516921D03*
Y531094D03*
Y527694D03*
X1055885Y554555D03*
X1046068Y792742D03*
X1046930Y796557D03*
X1048314Y833102D03*
X1053392Y832788D03*
X1051550Y823146D03*
X1055700Y840900D03*
X1053913Y837718D03*
X1050358Y837793D03*
X1052500Y841200D03*
X1049087Y856033D03*
X1053909Y855472D03*
X1045300Y872352D03*
X1054900Y879321D03*
X1058155Y887635D03*
X1050295Y891100D03*
X1054009Y988813D03*
X1046009D03*
X1050009D03*
X1058009D03*
X1056199Y1012354D03*
X1050744Y1009354D03*
X1056199Y1024954D03*
X1050699D03*
Y1012354D03*
X1050744Y1021954D03*
X1046485Y1034538D03*
X1057212Y1040356D03*
X1049930Y1221407D03*
X1050605Y1224472D03*
X1049770Y1229402D03*
X1049720Y1234921D03*
X1052660Y1293257D03*
X1050002Y1293283D03*
X1049204Y1337377D03*
X1049670Y1347462D03*
X1046075Y1350650D03*
X1049493Y1350694D03*
X1044867Y1428213D03*
Y1431213D03*
Y1434213D03*
Y1437213D03*
Y1440213D03*
X1048403Y1444608D03*
X1062773Y90650D03*
X1068085Y90615D03*
X1072456Y95236D03*
X1072406Y99961D03*
X1062523Y95236D03*
X1071268Y207978D03*
Y212978D03*
Y215478D03*
Y210478D03*
X1074597Y264180D03*
X1074522Y258880D03*
X1076571Y310574D03*
X1060679Y368276D03*
X1062865Y391001D03*
X1062234Y378600D03*
Y382600D03*
X1062865Y408574D03*
Y405174D03*
Y394401D03*
Y422747D03*
Y419347D03*
Y436921D03*
Y433521D03*
X1062349Y458711D03*
X1064876Y453682D03*
X1063113Y455921D03*
X1061693Y463600D03*
X1062865Y476499D03*
Y479899D03*
Y490673D03*
Y494073D03*
Y520633D03*
Y524033D03*
Y534806D03*
Y538206D03*
X1062098Y603600D03*
X1061342Y610269D03*
X1061496Y612786D03*
X1062098Y619600D03*
X1063642Y634190D03*
X1062098Y623600D03*
X1066931Y645389D03*
X1060698Y931619D03*
X1069685Y933391D03*
X1066878Y931909D03*
X1070009Y988813D03*
X1069607Y980131D03*
X1066009Y980330D03*
X1062009Y988813D03*
X1065823Y988773D03*
X1074009Y988813D03*
X1070009Y997860D03*
X1073525Y1012428D03*
X1076110Y1029535D03*
X1065079Y1036920D03*
X1076577Y1041332D03*
X1074232Y1055836D03*
X1067866Y1051037D03*
X1060768Y1053457D03*
X1074650Y1070006D03*
X1069642Y1445541D03*
X1068861Y1451311D03*
X1081187Y-72706D03*
Y-69306D03*
X1081320Y85193D03*
Y82593D03*
Y79993D03*
Y77393D03*
Y74793D03*
X1089645Y98551D03*
X1081364Y92874D03*
X1092540Y111223D03*
Y114623D03*
X1083391Y104249D03*
Y107649D03*
X1092540Y128796D03*
Y125396D03*
X1087957Y147540D03*
X1091729Y141247D03*
X1083013Y162368D03*
X1090113Y165393D03*
Y162793D03*
X1080413Y162368D03*
X1090113Y170493D03*
Y167993D03*
X1092321Y181366D03*
X1089110Y181426D03*
X1091935Y184012D03*
X1089318Y184221D03*
X1081724Y208213D03*
X1085796Y208695D03*
Y211695D03*
X1081724Y210713D03*
Y213213D03*
X1088596Y208695D03*
X1088296Y211695D03*
X1081724Y215713D03*
X1077097Y264180D03*
X1091973Y265701D03*
X1083491Y267526D03*
X1088791D03*
X1086291D03*
X1083491Y270026D03*
X1086291D03*
X1088791D03*
X1093608Y281716D03*
X1080351Y328256D03*
X1079748Y322743D03*
Y319343D03*
X1080351Y331656D03*
X1082297Y340770D03*
X1092554Y340318D03*
X1085615Y339815D03*
X1092561Y353374D03*
X1082787Y348501D03*
X1091031Y374810D03*
X1089788Y550907D03*
X1087288D03*
X1089788Y553407D03*
X1087288D03*
X1089096Y541863D03*
Y545263D03*
X1091558Y566929D03*
X1091272Y569426D03*
X1088949Y568475D03*
X1089206Y570962D03*
X1086859Y569928D03*
X1085512Y572070D03*
X1078920Y856700D03*
X1090375Y899047D03*
X1076800Y1012900D03*
X1078755Y1031518D03*
X1079178Y1037884D03*
X1076868Y1047293D03*
X1079910Y1045264D03*
X1079822Y1151870D03*
X1083562Y1155610D03*
X1079822Y1159350D03*
X1083283Y1526583D03*
X1084000Y1529600D03*
X1091529Y1528718D03*
X1091525Y1546300D03*
X1090876Y1554183D03*
X1091569Y1561300D03*
X1092527Y1579422D03*
X1086469Y1588435D03*
X1090469D03*
X1083900Y1593206D03*
X1082176Y1600598D03*
X1090904Y1599047D03*
X1088021Y1606949D03*
X1093778Y1599574D03*
X1086904Y1599004D03*
X1090093Y1628297D03*
X1085474Y1629028D03*
X1089474Y1638213D03*
X1105741Y76587D03*
Y72615D03*
X1100199Y97475D03*
X1107180Y100625D03*
X1100130Y106186D03*
X1093195Y103783D03*
X1102942Y118335D03*
Y132509D03*
Y121735D03*
Y135909D03*
X1107759Y141247D03*
X1099196Y143740D03*
X1096576Y148277D03*
X1095116Y181009D03*
X1100291Y168697D03*
X1097618Y172190D03*
X1109903Y171523D03*
X1097037Y177616D03*
X1101379Y191941D03*
X1109433Y192490D03*
X1105888Y206767D03*
X1108388D03*
X1103388D03*
X1093354Y213859D03*
Y211359D03*
X1097057Y213132D03*
X1104633Y228221D03*
X1106018Y221708D03*
X1108518D03*
X1102933Y224421D03*
X1103518Y221708D03*
X1104633Y231021D03*
X1097057Y215632D03*
X1105184Y236189D03*
X1107684D03*
X1105125Y248765D03*
X1107625D03*
X1097301Y256303D03*
X1102076Y266114D03*
X1097060Y265896D03*
X1107822Y268195D03*
X1105322D03*
Y270695D03*
X1107822D03*
X1099549Y281982D03*
X1093478Y310305D03*
X1108779Y327705D03*
X1103432Y340544D03*
X1097976Y340477D03*
X1105012Y353504D03*
X1098845Y353404D03*
X1093841Y371335D03*
X1099501Y545528D03*
X1108236Y577716D03*
X1105298Y610400D03*
X1108045Y668153D03*
X1092769Y936975D03*
X1095080Y1513398D03*
X1096780Y1526700D03*
X1101402Y1531702D03*
X1095250Y1531600D03*
X1098617Y1546183D03*
X1096780Y1535400D03*
X1100876Y1554183D03*
X1099371Y1561153D03*
X1100476Y1579318D03*
X1102904Y1566668D03*
X1093682Y1582433D03*
X1098498Y1590435D03*
X1104233Y1587983D03*
X1100233Y1588000D03*
X1107620Y1603602D03*
X1098904Y1602138D03*
X1101946Y1614709D03*
X1096941Y1627905D03*
X1105474Y1629450D03*
X1101474Y1637820D03*
X1093474Y1638213D03*
X1105474Y1638426D03*
X1097474Y1637753D03*
X1114781Y58013D03*
X1113646Y68581D03*
X1120021Y60513D03*
X1122881Y60438D03*
X1113659Y80581D03*
X1120149Y85731D03*
X1117789Y88801D03*
X1123703Y86046D03*
X1120706Y94351D03*
X1124655Y94279D03*
X1115842Y103621D03*
X1123899Y116594D03*
X1111553Y112083D03*
X1123899Y119594D03*
X1124333Y124283D03*
X1112246Y143518D03*
X1111346Y152373D03*
X1122740Y161306D03*
X1114496Y152562D03*
X1119991Y157370D03*
X1124075Y168665D03*
Y176665D03*
X1115188Y183834D03*
X1115298Y178560D03*
X1115361Y172665D03*
X1116174Y186629D03*
X1124075Y192665D03*
Y196665D03*
X1115478Y200864D03*
X1114708Y190185D03*
X1124188Y186778D03*
X1124107Y204864D03*
X1115501Y207037D03*
X1115567Y212455D03*
X1124107Y208864D03*
X1112868Y221642D03*
X1119748Y219379D03*
X1120376Y228631D03*
X1110184Y236189D03*
X1110125Y248765D03*
X1116782Y265897D03*
X1114282D03*
X1110622Y268195D03*
Y270695D03*
X1115000Y329000D03*
Y334000D03*
Y339000D03*
X1118848Y382109D03*
X1119853Y398082D03*
Y401482D03*
Y412255D03*
Y426428D03*
Y415655D03*
Y440602D03*
Y429828D03*
Y444002D03*
Y490641D03*
Y476468D03*
Y479868D03*
Y494041D03*
Y524002D03*
Y520602D03*
Y538175D03*
Y534775D03*
X1118847Y551683D03*
Y561420D03*
Y558917D03*
X1122705Y588515D03*
X1114668Y577937D03*
X1117673Y606929D03*
X1122673Y595500D03*
X1122173Y604567D03*
X1122705Y591015D03*
X1123331Y610072D03*
X1123267Y616317D03*
X1117633Y618400D03*
X1117914Y612592D03*
X1115151Y650119D03*
X1115320Y646449D03*
X1115054Y662981D03*
X1116296Y691851D03*
X1111785Y686971D03*
X1118105Y707592D03*
X1128562Y86012D03*
Y94374D03*
X1135868Y116594D03*
X1141141Y102495D03*
X1129842Y110784D03*
X1134842D03*
X1135868Y119594D03*
X1139402Y125107D03*
X1129399Y124879D03*
X1134421Y124663D03*
X1140875Y142862D03*
X1141916Y148717D03*
X1135765Y138838D03*
X1129156Y218085D03*
X1131956D03*
X1138469Y221970D03*
X1138535Y226320D03*
X1138469Y219470D03*
Y216970D03*
X1135756Y216385D03*
X1141496Y228646D03*
X1140453Y232971D03*
X1137103Y244571D03*
X1134483Y249108D03*
X1125864Y248371D03*
X1137830Y336230D03*
X1127153Y390995D03*
Y408568D03*
Y405168D03*
Y394395D03*
Y422741D03*
Y419341D03*
Y436915D03*
Y433515D03*
X1135548Y455804D03*
X1127153Y472781D03*
Y469381D03*
X1134629Y465551D03*
X1127153Y486954D03*
Y483554D03*
X1126622Y506256D03*
X1127153Y516915D03*
Y513515D03*
Y527688D03*
Y531088D03*
X1139673Y530000D03*
X1139173Y540500D03*
X1138373Y549800D03*
X1138173Y547075D03*
X1137673Y568000D03*
X1138213Y558800D03*
X1138277Y562800D03*
X1129471Y732571D03*
X1153945Y103411D03*
X1145485Y97667D03*
X1154339D03*
X1149735Y95111D03*
X1154585Y114655D03*
Y111255D03*
X1154104Y106561D03*
X1154585Y128828D03*
X1147285Y118342D03*
Y121742D03*
Y132515D03*
X1154585Y125428D03*
X1147285Y135915D03*
X1148016Y143762D03*
X1149464Y195176D03*
X1148482Y199248D03*
X1151482D03*
X1144464Y195176D03*
X1146964D03*
X1151964D03*
X1151482Y202048D03*
X1146318Y206806D03*
X1144545Y210509D03*
X1147045D03*
X1148818Y206806D03*
X1148482Y201748D03*
X1146237Y230556D03*
X1155082Y230117D03*
X1150492Y227824D03*
X1151098Y238714D03*
X1145222Y242078D03*
X1150579Y246874D03*
X1152799Y244297D03*
X1147590Y253198D03*
X1145587Y339148D03*
X1142440Y396718D03*
X1157451Y618288D03*
X1156275Y656321D03*
X1155146Y699491D03*
X1152512Y728543D03*
X1148962Y747253D03*
X1152485Y764552D03*
X1147468Y766093D03*
X1154652Y791056D03*
X1145910Y803642D03*
X1153485Y813142D03*
X1154985Y802897D03*
X1153229Y848581D03*
X1170447Y90615D03*
X1165135Y90650D03*
X1174768Y99961D03*
X1164885Y95236D03*
X1173630Y207978D03*
Y210478D03*
Y212978D03*
Y215478D03*
X1173559Y304948D03*
X1171445Y422088D03*
X1166868Y442956D03*
X1168685Y438323D03*
X1168398Y456309D03*
X1168851Y445873D03*
X1163298Y465874D03*
X1170878Y474424D03*
Y477824D03*
Y488597D03*
Y491997D03*
Y518558D03*
Y521958D03*
Y532731D03*
Y536131D03*
X1159535Y546712D03*
Y542712D03*
X1165400Y553300D03*
X1167900D03*
X1170878Y571997D03*
Y568597D03*
Y586171D03*
Y582771D03*
Y596944D03*
Y600344D03*
Y614517D03*
Y611117D03*
X1161451Y618288D03*
X1160275Y656321D03*
X1164275D03*
X1162863Y678519D03*
X1159173Y678462D03*
X1170465Y677836D03*
X1157646Y699491D03*
X1162646D03*
X1160146D03*
X1169256Y694983D03*
X1163774Y713347D03*
X1166115Y718469D03*
X1171934Y733857D03*
X1173034Y765060D03*
X1169697Y791935D03*
X1164925Y791607D03*
X1164732Y802269D03*
X1173122Y802759D03*
X1163579Y850774D03*
X1161535Y844167D03*
X1159887Y869106D03*
X1174461Y914515D03*
X1183682Y85193D03*
Y82593D03*
Y74793D03*
Y79993D03*
Y77393D03*
X1183726Y92874D03*
X1174818Y95236D03*
X1185753Y107649D03*
Y104249D03*
X1182775Y162368D03*
X1185375D03*
X1188158Y211695D03*
X1184086Y210713D03*
Y213213D03*
Y208213D03*
X1190958Y208695D03*
X1188158D03*
X1184086Y215713D03*
X1176959Y264180D03*
X1179459D03*
X1177035Y257919D03*
X1185853Y267526D03*
X1188653D03*
X1185853Y270026D03*
X1188653D03*
X1179901Y306366D03*
X1181706Y310131D03*
X1178045Y312193D03*
X1181379Y316049D03*
X1174929Y319167D03*
X1179761Y336380D03*
X1187996Y331992D03*
X1191748Y392676D03*
X1188598Y381500D03*
X1178083Y442856D03*
X1189122Y442606D03*
X1176699Y451108D03*
X1176138Y458455D03*
X1179184Y453881D03*
Y446595D03*
X1188739Y446606D03*
X1178178Y467337D03*
Y470737D03*
X1190046Y463479D03*
X1178178Y484910D03*
Y481510D03*
Y511471D03*
Y514871D03*
Y529044D03*
Y525644D03*
Y564910D03*
Y561510D03*
Y579084D03*
Y575684D03*
Y604030D03*
Y593257D03*
Y589857D03*
Y607430D03*
X1174595Y771744D03*
X1176500Y784933D03*
X1185516Y844248D03*
X1190968Y848703D03*
X1184340Y851072D03*
X1183012Y856553D03*
X1190213Y856816D03*
X1187431Y868340D03*
X1180239Y868430D03*
X1179858Y883455D03*
X1179727Y886197D03*
X1181654Y894671D03*
X1185058Y883475D03*
X1187151Y921000D03*
X1182000Y936500D03*
X1189219Y940703D03*
X1192007Y98551D03*
X1202561Y97475D03*
X1194902Y114623D03*
Y111223D03*
X1195557Y103783D03*
X1202492Y106186D03*
X1205304Y118335D03*
Y121735D03*
X1194902Y128796D03*
X1205304Y132509D03*
X1194902Y125396D03*
X1205304Y135909D03*
X1190319Y147540D03*
X1194091Y141247D03*
X1201558Y143740D03*
X1198938Y148277D03*
X1192475Y165393D03*
Y162793D03*
Y167993D03*
Y170493D03*
X1199980Y172190D03*
X1194683Y181366D03*
X1191472Y181426D03*
X1197478Y181009D03*
X1202653Y168697D03*
X1199399Y177616D03*
X1203741Y191941D03*
X1194297Y184012D03*
X1191680Y184221D03*
X1205750Y206767D03*
X1195716Y211359D03*
Y213859D03*
X1199419Y213132D03*
X1190658Y211695D03*
X1205295Y224421D03*
X1205880Y221708D03*
X1199419Y215632D03*
X1199663Y256303D03*
X1199422Y265896D03*
X1204438Y266114D03*
X1194335Y265701D03*
X1191153Y267526D03*
Y270026D03*
X1201911Y281982D03*
X1195970Y281716D03*
X1201113Y315039D03*
X1190127Y324142D03*
X1195800Y324000D03*
X1206531Y393858D03*
X1208173Y398583D03*
X1192702Y440489D03*
X1192957Y435158D03*
X1193000Y444841D03*
X1192686Y449961D03*
X1196403Y458572D03*
X1192431Y868620D03*
X1192152Y884399D03*
X1192367Y903785D03*
X1190210Y900909D03*
X1191151Y936296D03*
X1193219Y940703D03*
X1197173Y940645D03*
X1196352Y951033D03*
X1191219Y967757D03*
X1191928Y987314D03*
X1198644Y985289D03*
X1195757Y988131D03*
X1203419Y1011161D03*
X1200008D03*
X1196300Y998600D03*
X1202028Y998349D03*
X1199700Y1013661D03*
X1201800Y1019431D03*
X1219783Y55513D03*
X1216008Y68581D03*
X1222383Y60513D03*
X1216021Y80581D03*
X1208103Y72615D03*
Y76587D03*
X1222511Y85731D03*
X1220151Y88801D03*
X1218204Y103621D03*
X1209542Y100625D03*
X1213915Y112083D03*
X1210121Y141247D03*
X1214608Y143518D03*
X1213708Y152373D03*
X1216858Y152562D03*
X1222353Y157370D03*
X1217550Y183834D03*
X1212265Y171523D03*
X1217723Y172665D03*
X1217660Y178560D03*
X1218536Y186629D03*
X1211795Y192490D03*
X1210268Y198671D03*
X1217840Y200864D03*
X1217070Y190185D03*
X1207753Y192300D03*
X1208250Y206767D03*
X1210750D03*
X1217863Y207037D03*
X1217929Y212455D03*
X1215230Y221642D03*
X1206995Y228221D03*
X1208380Y221708D03*
X1210880D03*
X1206995Y231021D03*
X1222110Y219379D03*
X1222738Y228631D03*
X1207546Y236189D03*
X1210046D03*
X1212546D03*
X1207487Y248765D03*
X1209987D03*
X1212487D03*
X1219144Y265897D03*
X1216644D03*
X1212984Y268195D03*
X1210184D03*
X1207684D03*
X1212984Y270695D03*
X1207684D03*
X1210184D03*
X1220723Y324466D03*
X1211892Y339559D03*
X1215776Y331072D03*
X1213173Y377912D03*
X1217177Y369925D03*
X1206693Y384410D03*
X1213173Y386500D03*
X1209872Y382047D03*
X1212173Y391496D03*
X1213261Y397912D03*
X1210173Y403500D03*
X1212173Y409000D03*
X1209426Y433069D03*
Y430469D03*
Y435669D03*
Y440869D03*
Y438269D03*
X1206626Y433069D03*
Y430469D03*
Y435669D03*
Y440869D03*
Y438269D03*
X1209980Y451677D03*
X1207480Y454177D03*
X1209980D03*
X1207480Y451677D03*
X1209184Y463618D03*
Y460218D03*
X1225405Y-72678D03*
Y-69278D03*
X1230761Y-33628D03*
Y-30228D03*
X1225243Y60438D03*
X1230924Y86012D03*
Y94374D03*
X1226065Y86046D03*
X1227017Y94279D03*
X1223068Y94351D03*
X1238230Y116594D03*
X1226261D03*
X1232204Y110784D03*
X1237204D03*
X1238230Y119594D03*
X1226261D03*
X1236783Y124663D03*
X1226695Y124283D03*
X1231761Y124879D03*
X1238127Y138838D03*
X1225102Y161306D03*
X1226437Y176665D03*
Y168665D03*
Y192665D03*
X1226550Y186778D03*
X1226469Y204864D03*
Y208864D03*
X1231518Y218085D03*
X1234318D03*
X1238118Y216385D03*
X1239465Y244571D03*
X1236845Y249108D03*
X1228226Y248371D03*
X1229252Y314890D03*
X1229028Y311740D03*
X1226436Y324518D03*
X1229922Y324550D03*
X1234904Y316942D03*
X1232197Y316964D03*
X1238293Y317296D03*
X1229438Y332584D03*
X1235589Y348015D03*
X1229942Y347937D03*
X1231506Y353470D03*
X1223431Y377912D03*
X1225755Y369391D03*
X1229122Y369355D03*
X1222601Y369251D03*
X1223431Y381912D03*
Y397912D03*
X1235166Y470706D03*
Y467306D03*
Y484879D03*
Y481479D03*
Y514839D03*
Y511439D03*
Y529013D03*
Y525613D03*
X1232833Y539315D03*
X1232149Y550137D03*
X1234941D03*
X1235166Y564879D03*
Y561479D03*
Y575652D03*
Y579052D03*
Y593225D03*
Y603999D03*
Y589825D03*
Y607399D03*
X1235930Y626229D03*
X1235292Y622912D03*
X1237500Y632405D03*
X1238034Y629961D03*
X1238695Y627313D03*
X1256307Y103411D03*
X1247847Y97667D03*
X1256701D03*
X1252097Y95111D03*
X1243503Y102495D03*
X1249647Y118342D03*
Y132515D03*
Y121742D03*
X1241764Y125107D03*
X1249647Y135915D03*
X1243237Y142862D03*
X1250378Y143762D03*
X1244278Y148717D03*
X1251826Y195176D03*
X1254326D03*
X1253844Y199248D03*
X1249326Y195176D03*
X1250844Y199248D03*
X1246826Y195176D03*
X1249407Y210509D03*
X1253844Y202048D03*
X1250844Y201748D03*
X1251180Y206806D03*
X1248680D03*
X1246907Y210509D03*
X1240831Y221970D03*
X1240897Y226320D03*
X1240831Y219470D03*
Y216970D03*
X1248599Y230556D03*
X1252854Y227824D03*
X1243858Y228646D03*
X1253460Y238714D03*
X1247584Y242078D03*
X1252941Y246874D03*
X1242815Y232971D03*
X1246808Y256394D03*
X1241205Y303962D03*
X1253245Y416888D03*
Y419488D03*
Y422088D03*
X1245568Y474418D03*
Y488591D03*
Y477818D03*
Y491991D03*
Y521952D03*
Y518552D03*
Y536125D03*
Y532725D03*
X1253087Y553101D03*
X1241629Y550065D03*
X1245568Y568591D03*
Y571991D03*
Y582765D03*
Y586165D03*
Y596938D03*
Y600338D03*
Y611111D03*
Y614511D03*
X1248106Y1004700D03*
X1245400Y1003700D03*
X1246000Y1014800D03*
X1252148Y1026223D03*
X1252500Y1014288D03*
X1246300Y1027800D03*
X1253424Y1138130D03*
X1250928Y1142828D03*
X1254200Y1146600D03*
X1249363Y1173065D03*
X1256218Y1175987D03*
X1249363Y1166065D03*
X1255439Y1172008D03*
X1255628Y1188345D03*
X1253056Y1194917D03*
X1254275Y1531334D03*
X1249894Y1527805D03*
X1253904Y1519645D03*
X1254275Y1539334D03*
X1250434Y1535334D03*
X1267497Y90650D03*
X1267247Y95236D03*
X1256947Y114655D03*
Y111255D03*
X1256466Y106561D03*
X1256947Y128828D03*
Y125428D03*
X1257444Y230117D03*
X1255161Y244297D03*
X1266962Y302167D03*
X1262665Y302730D03*
X1263328Y309003D03*
X1262075Y324075D03*
X1261659Y318258D03*
X1264088Y320382D03*
X1266616Y322456D03*
X1257000Y333500D03*
X1264215Y333215D03*
X1262500Y330655D03*
X1256000Y338000D03*
X1259991Y340691D03*
X1256000Y340500D03*
X1263500Y336000D03*
X1264659Y377173D03*
X1267944Y371767D03*
X1261764Y391533D03*
X1263484Y385644D03*
X1268659Y385123D03*
X1268067Y406060D03*
X1261231Y399918D03*
X1264336Y412106D03*
X1268328Y421489D03*
Y418889D03*
Y416289D03*
X1270397Y447081D03*
X1259223Y454334D03*
X1267540Y459330D03*
X1267493Y454214D03*
X1267836Y449045D03*
X1267843Y473571D03*
Y481071D03*
Y478571D03*
Y476071D03*
X1269629Y848124D03*
X1270892Y856343D03*
X1271121Y892513D03*
X1270276Y897062D03*
X1269221Y894760D03*
X1270586Y905324D03*
X1272661Y929858D03*
X1260539Y1134729D03*
X1267921D03*
X1266718Y1142666D03*
X1263921Y1134729D03*
X1268593Y1157544D03*
X1267104Y1167768D03*
X1272123D03*
X1271246Y1178240D03*
X1271256Y1185205D03*
X1262605Y1187215D03*
X1262298Y1180175D03*
X1260800Y1191096D03*
X1268571Y1201043D03*
X1264575D03*
X1261538Y1199814D03*
X1255296Y1196056D03*
X1263449Y1217228D03*
X1266113Y1219895D03*
X1269388Y1223170D03*
X1267333Y1531334D03*
X1262891Y1527334D03*
X1267183Y1539334D03*
X1262891Y1535334D03*
X1286044Y85539D03*
Y82939D03*
Y75139D03*
Y80339D03*
Y77739D03*
X1286088Y92874D03*
X1272809Y90615D03*
X1277130Y99961D03*
X1277180Y95236D03*
X1285137Y162368D03*
X1275992Y215478D03*
Y212978D03*
Y210478D03*
Y207978D03*
X1286448Y213213D03*
Y210713D03*
Y208213D03*
Y215713D03*
X1281821Y264180D03*
X1279321D03*
X1279246Y258880D03*
X1271571Y281185D03*
X1289345Y330655D03*
X1284419Y359377D03*
X1287437Y379429D03*
X1280699Y377173D03*
X1284659D03*
X1274436Y377350D03*
X1276659Y385123D03*
X1273659D03*
X1280659D03*
X1284333Y391569D03*
X1282760Y401066D03*
X1272421Y403300D03*
X1271828Y405889D03*
Y408489D03*
Y413689D03*
Y411089D03*
Y416289D03*
Y421489D03*
Y418889D03*
Y424089D03*
X1272215Y432718D03*
Y435518D03*
X1282092Y442118D03*
Y439318D03*
X1271828Y426689D03*
X1272927Y450091D03*
X1275927D03*
X1273397Y447081D03*
X1281737Y461034D03*
Y456034D03*
X1272927Y462060D03*
X1275927D03*
X1286005Y485580D03*
X1280631Y480194D03*
Y477694D03*
X1277897Y478876D03*
Y476376D03*
X1274415Y477053D03*
X1271915D03*
X1284900Y678800D03*
X1283400Y715500D03*
X1278255Y722241D03*
X1283400Y719700D03*
X1282539Y746076D03*
X1279539Y748576D03*
X1282539Y751076D03*
X1279539Y763576D03*
X1282539Y766076D03*
X1279539Y758576D03*
X1282539Y756076D03*
Y761076D03*
X1279539Y753576D03*
Y768576D03*
Y780576D03*
Y784576D03*
X1285092Y819500D03*
X1285500Y827500D03*
X1281388Y827388D03*
X1281777Y823500D03*
X1285500Y843500D03*
X1281331Y843331D03*
X1281269Y835492D03*
X1285500Y835500D03*
X1283025Y848305D03*
X1271438Y861846D03*
X1285500Y863500D03*
Y859500D03*
Y855500D03*
Y851500D03*
X1279460Y854487D03*
Y859487D03*
Y864487D03*
X1274396Y866896D03*
X1285500Y867500D03*
X1279460Y874487D03*
Y869487D03*
Y879487D03*
X1285302Y877283D03*
X1282285Y865602D03*
X1274264Y898591D03*
X1279460Y884487D03*
X1285302Y885783D03*
X1279299Y898813D03*
X1279460Y889487D03*
X1285302Y881783D03*
X1281075Y911075D03*
X1282184Y898854D03*
X1274400Y914123D03*
X1283494Y907176D03*
X1275493Y929858D03*
X1279493D03*
X1283493D03*
X1279693Y919800D03*
X1274670Y919808D03*
X1281400Y940256D03*
X1289547Y941000D03*
X1281733Y949475D03*
X1275788Y1124088D03*
X1282421Y1137129D03*
X1271921Y1134729D03*
X1275794D03*
X1282830Y1150087D03*
X1275050Y1157404D03*
X1280306Y1170767D03*
X1275965Y1187232D03*
X1280602Y1185238D03*
X1280395Y1180235D03*
X1272541Y1201043D03*
X1276575Y1201039D03*
X1280575Y1200969D03*
X1280694Y1208993D03*
X1274446Y1228226D03*
X1272235Y1226016D03*
X1297687Y-33656D03*
Y-30256D03*
X1297785Y33768D03*
X1302139Y26325D03*
X1302785Y31168D03*
X1294369Y98551D03*
X1304923Y97475D03*
X1297264Y114623D03*
Y111223D03*
X1297919Y103783D03*
X1288115Y104249D03*
Y107649D03*
X1297264Y128796D03*
Y125396D03*
X1294837Y162793D03*
X1287737Y162368D03*
X1294837Y165393D03*
Y167993D03*
Y170493D03*
X1301761Y177616D03*
X1302342Y172190D03*
X1299840Y181009D03*
X1293834Y181426D03*
X1297045Y181366D03*
X1294042Y184221D03*
X1296659Y184012D03*
X1301781Y213132D03*
X1298078Y211359D03*
Y213859D03*
X1290520Y211695D03*
X1293020D03*
X1290520Y208695D03*
X1293320D03*
X1301781Y215632D03*
X1302025Y256303D03*
X1296697Y265701D03*
X1301784Y265896D03*
X1293515Y270026D03*
X1291015D03*
X1288215D03*
Y267526D03*
X1293515D03*
X1291015D03*
X1304273Y281982D03*
X1298332Y281716D03*
X1294000Y324000D03*
X1303000Y326692D03*
X1293000Y338500D03*
X1303000Y331000D03*
X1302896Y343797D03*
Y340397D03*
X1292500Y335000D03*
X1299959Y356954D03*
X1294080Y349820D03*
X1291410Y371060D03*
X1295410Y371076D03*
X1293048Y379088D03*
X1298346Y379028D03*
X1293100Y409539D03*
X1296100D03*
X1293100Y406739D03*
X1296100Y407039D03*
X1295764Y401981D03*
X1298264D03*
X1300037Y398278D03*
X1297537D03*
X1292618Y413611D03*
X1295118D03*
X1300118D03*
X1297618D03*
X1292383Y424067D03*
X1294883D03*
X1299883D03*
X1297383D03*
X1299757Y438293D03*
Y441093D03*
X1290092Y442118D03*
Y439318D03*
X1299757Y443893D03*
X1287719Y470001D03*
X1290219D03*
X1299867Y477318D03*
X1299466Y466409D03*
X1299807Y472020D03*
X1288144Y489036D03*
X1291005Y485580D03*
X1288505D03*
X1301314Y484882D03*
X1299304Y487382D03*
X1290380Y495636D03*
Y492836D03*
X1300817Y568635D03*
X1301194Y565518D03*
X1305836Y660009D03*
X1298963Y659609D03*
X1289811Y677612D03*
X1289317Y706932D03*
X1291604Y781576D03*
Y776576D03*
Y771435D03*
X1295491Y798821D03*
X1298720Y798975D03*
X1289730Y806845D03*
X1302140Y812625D03*
X1302501Y824747D03*
X1297667Y832150D03*
X1293500Y827500D03*
X1296770Y828775D03*
X1293500Y843500D03*
Y835500D03*
X1296687Y839500D03*
X1293500Y851500D03*
X1294000Y863500D03*
X1293500Y879800D03*
Y871800D03*
Y875800D03*
X1288164Y892354D03*
X1296866Y894993D03*
X1305250Y889250D03*
X1293272Y887800D03*
X1293500Y883800D03*
X1291129Y892267D03*
X1294264Y905595D03*
X1301657Y899129D03*
X1288500Y901254D03*
X1298966Y899610D03*
X1296466D03*
X1298000Y917000D03*
X1294075D03*
X1304949Y928546D03*
X1292500Y928000D03*
X1295453Y928047D03*
X1291059Y917000D03*
X1302000D03*
X1302500Y939500D03*
X1300882Y937144D03*
X1296500Y961500D03*
X1289500Y949500D03*
X1300500Y960000D03*
X1290792Y961363D03*
X1300500Y970187D03*
X1297558Y970216D03*
X1292836Y975244D03*
X1292631Y979845D03*
X1299717Y1024136D03*
X1297852Y1014475D03*
X1295815Y1124943D03*
X1295893Y1122182D03*
X1310853Y37543D03*
X1314887Y45448D03*
X1318859D03*
X1311904Y100625D03*
X1320566Y103621D03*
X1304854Y106186D03*
X1316277Y112083D03*
X1307666Y118335D03*
Y132509D03*
Y121735D03*
Y135909D03*
X1305015Y168697D03*
X1319912Y183834D03*
X1314627Y171523D03*
X1320085Y172665D03*
X1320022Y178560D03*
X1306103Y191941D03*
X1319432Y190185D03*
X1314157Y192490D03*
X1320202Y200864D03*
X1310115Y192300D03*
X1308112Y206767D03*
X1313112D03*
X1310612D03*
X1320225Y207037D03*
X1320291Y212455D03*
X1313242Y221708D03*
X1310742D03*
X1309357Y231021D03*
Y228221D03*
X1317592Y221642D03*
X1308242Y221708D03*
X1307657Y224421D03*
X1309908Y236189D03*
X1314908D03*
X1312408D03*
X1312349Y248765D03*
X1309849D03*
X1314849D03*
X1306800Y266114D03*
X1310046Y268195D03*
X1312546D03*
X1315346D03*
X1319006Y265897D03*
X1312546Y270695D03*
X1310046D03*
X1315346D03*
X1318362Y310562D03*
X1305928Y318250D03*
X1308428D03*
X1315256Y336510D03*
X1313103Y339606D03*
X1312240Y334681D03*
X1315397Y333709D03*
X1308012Y348109D03*
X1305910Y377581D03*
X1310172Y367956D03*
X1308410Y379591D03*
X1311283Y370801D03*
X1308826Y389402D03*
X1306113Y383817D03*
X1312626Y387702D03*
X1315426D03*
X1306113Y386317D03*
Y388817D03*
X1309750Y438293D03*
Y441093D03*
Y443893D03*
X1311488Y471560D03*
X1307819Y474382D03*
X1307835Y470382D03*
X1319474Y467560D03*
X1319974Y475560D03*
X1311488D03*
X1318160Y520053D03*
X1317945Y523058D03*
X1319000Y562500D03*
Y558500D03*
Y586500D03*
Y574500D03*
Y578500D03*
Y605000D03*
Y590500D03*
X1319323Y598454D03*
X1319000Y621000D03*
Y609000D03*
Y633000D03*
Y625000D03*
Y637000D03*
Y653500D03*
Y649500D03*
Y641000D03*
Y669500D03*
Y665500D03*
Y681500D03*
Y677500D03*
X1313979Y677726D03*
X1319000Y685500D03*
Y696500D03*
Y700500D03*
Y712500D03*
Y716500D03*
Y724500D03*
Y728500D03*
Y732500D03*
X1321000Y796000D03*
X1313000D03*
X1317000Y799000D03*
Y788000D03*
X1313000D03*
X1315000Y811620D03*
X1319000D03*
X1317000Y804000D03*
X1313000D03*
X1321000D03*
X1310715Y820491D03*
Y822991D03*
Y817991D03*
X1310687Y830206D03*
Y832706D03*
Y827706D03*
X1310971Y842319D03*
X1305786Y867704D03*
X1310994Y866859D03*
X1309753Y877589D03*
X1305740Y877534D03*
X1310535Y870775D03*
X1308220Y889253D03*
X1311061Y889361D03*
X1314500Y911500D03*
X1319500Y901500D03*
X1314500Y905000D03*
X1305356Y902597D03*
X1319500Y905000D03*
X1309103Y917000D03*
X1313867Y925605D03*
X1311325Y928918D03*
X1319554Y925585D03*
X1309103Y936559D03*
X1306500Y936500D03*
X1315779Y943743D03*
X1313152Y936605D03*
X1312575Y943974D03*
X1321256Y943815D03*
X1311000Y961500D03*
X1307000Y960500D03*
X1315441Y960000D03*
X1307000Y970000D03*
X1311000Y970124D03*
X1307707Y979870D03*
X1317254Y990777D03*
X1317053Y988111D03*
X1319874Y989856D03*
X1307561Y986951D03*
X1315606Y1042825D03*
X1315756Y1039344D03*
X1312873Y1036543D03*
X1306385Y1036646D03*
X1319221Y1058097D03*
Y1060697D03*
X1316869Y1107997D03*
X1319069Y1112397D03*
X1318969Y1109397D03*
X1316869Y1113797D03*
Y1110897D03*
X1317437Y1160834D03*
X1318178Y1192621D03*
Y1190121D03*
X1319237Y1221428D03*
X1311237D03*
X1315237D03*
X1311237Y1233428D03*
Y1229428D03*
Y1225428D03*
X1315237Y1237428D03*
Y1233428D03*
Y1229428D03*
Y1225428D03*
X1319237Y1237428D03*
Y1233428D03*
Y1229428D03*
Y1225428D03*
X1315237Y1241428D03*
X1319237D03*
X1308107Y1283395D03*
X1310773Y1282411D03*
X1303900Y1288000D03*
X1318287Y1295381D03*
Y1291381D03*
X1324120Y22742D03*
X1331073Y33400D03*
X1328003Y32403D03*
X1328318Y27333D03*
X1336623Y30483D03*
X1322853Y37530D03*
X1328799Y168665D03*
Y176665D03*
X1320898Y186629D03*
X1328799Y192665D03*
Y196665D03*
X1328912Y186778D03*
X1328831Y204864D03*
Y208864D03*
X1324472Y219379D03*
X1325100Y228631D03*
X1321506Y265897D03*
X1334110Y310562D03*
X1321762D03*
X1329636Y307562D03*
X1326236D03*
X1332563Y326356D03*
X1325573Y326719D03*
X1332359Y322685D03*
X1326489Y356945D03*
X1331005Y356670D03*
X1331922Y359836D03*
X1325007Y370951D03*
X1334109Y373401D03*
X1334285Y386567D03*
X1331606D03*
X1328896D03*
X1320594Y387151D03*
Y382151D03*
Y384651D03*
X1329097Y435321D03*
Y438121D03*
X1326297Y435321D03*
Y438121D03*
X1329097Y440921D03*
X1326297D03*
X1329097Y443721D03*
X1326297D03*
X1335440Y452799D03*
X1329083Y448931D03*
X1329606Y459170D03*
X1332974Y474513D03*
X1321450Y520268D03*
X1321164Y523130D03*
X1326993Y556788D03*
X1331096Y549931D03*
X1327043Y573346D03*
X1327000Y562500D03*
X1326946Y567906D03*
X1338000Y562500D03*
X1327000Y578500D03*
Y583826D03*
X1335000Y594500D03*
X1327000Y605000D03*
Y594500D03*
Y609000D03*
X1333224Y615484D03*
X1327000Y613000D03*
Y621000D03*
X1335532Y622260D03*
X1338000Y609000D03*
X1327000Y629000D03*
X1327003Y623940D03*
X1335000Y641000D03*
X1338000Y653500D03*
X1327000Y641000D03*
X1327011Y646064D03*
X1327000Y657500D03*
X1335000Y685500D03*
X1327000D03*
Y695500D03*
Y700500D03*
X1338000D03*
X1327000Y711500D03*
Y716500D03*
X1335000Y732500D03*
X1327000D03*
X1330295Y746328D03*
X1326970Y736464D03*
X1336661Y753675D03*
Y745675D03*
Y737675D03*
X1330295Y751328D03*
X1330086Y763758D03*
X1330324Y779030D03*
X1336746Y781675D03*
X1329000Y796000D03*
X1325000Y799000D03*
X1337000Y796000D03*
X1333000Y799000D03*
Y788000D03*
X1329000D03*
X1321000D03*
X1325000D03*
X1331000Y811620D03*
X1327000D03*
X1329000Y804000D03*
X1325000D03*
X1333000D03*
X1323000Y811620D03*
X1335000D03*
X1335803Y826500D03*
X1331056Y904557D03*
X1336096Y905042D03*
X1336000Y900500D03*
X1324000Y901000D03*
X1331078Y900500D03*
X1330500Y925500D03*
X1334500D03*
X1326500D03*
X1333425Y930925D03*
X1324000D03*
X1333132Y933781D03*
X1336000Y943500D03*
X1329199Y933825D03*
X1323000Y934075D03*
X1326500Y943500D03*
X1335343Y961727D03*
X1321028Y961749D03*
X1332500Y961500D03*
X1325550Y960445D03*
X1332000Y969500D03*
X1327000D03*
X1329503Y991088D03*
X1334909Y990340D03*
X1332404Y988215D03*
X1329834Y988132D03*
X1324735Y989966D03*
X1327267Y988271D03*
X1322427Y988221D03*
X1333974Y1033483D03*
X1320549Y1037876D03*
X1322773Y1040599D03*
X1329221Y1058097D03*
X1321721D03*
X1324221D03*
X1326721D03*
Y1060697D03*
X1329221D03*
X1321721D03*
X1324221D03*
X1326163Y1082501D03*
X1326189Y1085205D03*
X1329163Y1082501D03*
X1329189Y1085205D03*
X1326189Y1088205D03*
X1326471Y1091227D03*
X1329189Y1088205D03*
X1323189Y1085205D03*
Y1087705D03*
X1323163Y1082501D03*
X1323021Y1090956D03*
X1337514Y1104335D03*
X1334956Y1105552D03*
X1321069Y1107997D03*
X1323021Y1093956D03*
X1331162Y1104792D03*
X1332669Y1106867D03*
X1321169Y1110597D03*
X1321954Y1113648D03*
X1326254D03*
X1328754D03*
X1323405Y1118801D03*
Y1116101D03*
X1325635Y1172384D03*
Y1162384D03*
Y1164884D03*
Y1167384D03*
Y1169884D03*
X1323135Y1172384D03*
Y1162384D03*
Y1164884D03*
Y1167384D03*
Y1169884D03*
X1334793Y1179421D03*
Y1181921D03*
Y1184421D03*
Y1186921D03*
X1320493Y1186709D03*
Y1184209D03*
Y1181709D03*
Y1179209D03*
X1325635Y1174884D03*
X1323135D03*
X1331643Y1192621D03*
Y1190121D03*
X1327237Y1221428D03*
X1331237D03*
X1335237D03*
X1323237D03*
X1327237Y1237428D03*
Y1233428D03*
Y1229428D03*
Y1225428D03*
X1331237Y1237428D03*
Y1233428D03*
Y1229428D03*
Y1225428D03*
X1335237Y1237428D03*
Y1233428D03*
Y1229428D03*
Y1225428D03*
X1323237Y1237428D03*
Y1233428D03*
Y1229428D03*
Y1225428D03*
X1335237Y1241428D03*
X1323237Y1245428D03*
Y1241428D03*
X1327237Y1245428D03*
Y1241428D03*
X1331237Y1245428D03*
Y1241428D03*
X1335237Y1245428D03*
X1333876Y1257160D03*
Y1260160D03*
X1337687Y-69306D03*
Y-72706D03*
X1336646Y22627D03*
X1336551Y26534D03*
X1340320Y147540D03*
X1344092Y141247D03*
X1351559Y143740D03*
X1348939Y148277D03*
X1348419Y265222D03*
X1340104Y279117D03*
X1344007Y279054D03*
X1337510Y310562D03*
X1347990Y322539D03*
X1341169Y325926D03*
X1346009Y336080D03*
X1346093Y340805D03*
X1349636Y340862D03*
X1346065Y347106D03*
X1338471Y356959D03*
X1337509Y373401D03*
X1349763Y371908D03*
X1342810Y408104D03*
X1345610D03*
X1348410D03*
X1336388Y424939D03*
X1342527Y420375D03*
X1345327D03*
X1348127D03*
X1336388Y427439D03*
X1346443Y431112D03*
X1352008Y435101D03*
X1352271Y442114D03*
X1346613Y440101D03*
X1352251Y447121D03*
X1346248Y452718D03*
X1340820Y452987D03*
X1352259Y452601D03*
X1347846Y461607D03*
X1339846D03*
X1339049Y471334D03*
X1343846Y461607D03*
X1346738Y564492D03*
X1339289Y568461D03*
X1342053Y579339D03*
X1346533Y576780D03*
X1340522Y586133D03*
X1343000Y590458D03*
X1346533Y581898D03*
X1344129Y606914D03*
X1344433Y601201D03*
X1339289Y614961D03*
X1344680Y619085D03*
X1346738Y611192D03*
X1346533Y628398D03*
X1346378Y623734D03*
X1342053Y625839D03*
X1340522Y632633D03*
X1343000Y636958D03*
X1346738Y655492D03*
X1339289Y659461D03*
X1346533Y667780D03*
X1342053Y670339D03*
X1346533Y672898D03*
X1340522Y677133D03*
X1343000Y681458D03*
X1350929Y687043D03*
X1340299Y686243D03*
X1346738Y702492D03*
X1346533Y719898D03*
X1339289Y706461D03*
X1342053Y717339D03*
X1346533Y714780D03*
X1340522Y724133D03*
X1343000Y728458D03*
X1344768Y737675D03*
Y741675D03*
Y745675D03*
Y749675D03*
Y753675D03*
Y761675D03*
Y757675D03*
X1336450Y765675D03*
X1344768Y773675D03*
Y781350D03*
X1345226Y777675D03*
X1341000Y799000D03*
X1345000Y796000D03*
X1341000Y788000D03*
X1345000D03*
X1337000D03*
X1348917Y796000D03*
Y788000D03*
X1352817Y796000D03*
X1349000Y804000D03*
X1351000Y811620D03*
X1347000D03*
X1343000D03*
X1337000Y804000D03*
X1345000D03*
X1341000D03*
X1349976Y829000D03*
X1350000Y825500D03*
X1340000Y900000D03*
X1351500Y903000D03*
Y906500D03*
X1340000Y906000D03*
Y903000D03*
X1351511Y900000D03*
X1350500Y925500D03*
X1338500D03*
X1342500D03*
X1346500D03*
X1353948Y943603D03*
X1345948D03*
X1349848Y936755D03*
X1338500Y930500D03*
X1350500D03*
X1342500D03*
X1346500D03*
X1337514Y988259D03*
X1343465Y1026123D03*
X1340665D03*
X1343465Y1028923D03*
X1340665D03*
X1347552Y1091816D03*
Y1089316D03*
X1345052Y1081816D03*
Y1084316D03*
Y1086816D03*
X1347552D03*
Y1084316D03*
X1350418Y1090288D03*
X1347552Y1081816D03*
X1344241Y1106298D03*
X1348997Y1107997D03*
X1350418Y1093088D03*
X1339234Y1101917D03*
X1339169Y1106897D03*
X1341984Y1110092D03*
X1345650Y1115896D03*
X1348997Y1113797D03*
Y1110897D03*
X1351197Y1112397D03*
X1351097Y1109397D03*
X1345650Y1118396D03*
X1347300Y1128332D03*
X1343725Y1128738D03*
X1343905Y1162384D03*
Y1164884D03*
Y1167384D03*
Y1169884D03*
Y1172384D03*
X1341405D03*
Y1169884D03*
Y1167384D03*
Y1164884D03*
Y1162384D03*
X1350963Y1172384D03*
Y1169884D03*
Y1167384D03*
Y1164884D03*
Y1162384D03*
X1351149Y1158200D03*
X1347423Y1186709D03*
Y1184209D03*
Y1181709D03*
Y1179209D03*
X1343905Y1174884D03*
X1341405D03*
X1350963D03*
X1337108Y1192621D03*
Y1190121D03*
X1345108D03*
Y1192621D03*
X1347237Y1221428D03*
X1343237D03*
X1339237D03*
X1347237Y1237428D03*
Y1233428D03*
Y1229428D03*
X1343237D03*
Y1233428D03*
Y1237428D03*
X1339237D03*
Y1233428D03*
Y1229428D03*
Y1225428D03*
X1347237Y1245428D03*
Y1241428D03*
X1343237D03*
Y1245428D03*
X1339237D03*
Y1241428D03*
X1339876Y1257160D03*
X1342876D03*
X1345876Y1260160D03*
Y1257160D03*
X1348876Y1260160D03*
Y1257160D03*
X1351876Y1260160D03*
Y1257160D03*
X1336876Y1260160D03*
Y1257160D03*
X1342876Y1260160D03*
X1339876D03*
X1360122Y141247D03*
X1364609Y143518D03*
X1363709Y152373D03*
X1366859Y152562D03*
X1363535Y327877D03*
X1366535Y335751D03*
Y339151D03*
X1363535Y331277D03*
Y343625D03*
X1366535Y354899D03*
Y351499D03*
X1363535Y347025D03*
X1360719Y424601D03*
X1352817Y788000D03*
X1367000Y811620D03*
X1365000Y804000D03*
X1355000Y811620D03*
X1363000D03*
X1353000Y804000D03*
X1359000Y811620D03*
X1357000Y804000D03*
X1361000D03*
X1354185Y906498D03*
X1367000Y904500D03*
X1363000Y900500D03*
X1367000D03*
X1354500Y925500D03*
X1366500D03*
X1358500D03*
X1362500D03*
X1365948Y939475D03*
X1357948Y938842D03*
X1361948Y943603D03*
X1369948D03*
X1362500Y930500D03*
X1366500D03*
X1354500D03*
X1358500D03*
X1364765Y1004766D03*
X1367444Y1003763D03*
X1357765Y1019766D03*
X1361265D03*
X1365049Y1028416D03*
X1365314Y1021793D03*
X1357265Y1026266D03*
Y1034266D03*
X1366265Y1039880D03*
X1369642Y1104335D03*
X1367084Y1105552D03*
X1353197Y1107997D03*
X1363290Y1104792D03*
X1364797Y1106867D03*
X1353297Y1110597D03*
X1354082Y1113648D03*
X1355533Y1116101D03*
Y1118801D03*
X1360882Y1113648D03*
X1358382D03*
X1353463Y1172384D03*
Y1169884D03*
Y1167384D03*
Y1164884D03*
Y1162384D03*
X1361723Y1179421D03*
Y1181921D03*
Y1184421D03*
Y1186921D03*
X1353463Y1174884D03*
X1364038Y1190121D03*
Y1192621D03*
X1363876Y1260160D03*
Y1257160D03*
X1354876Y1260160D03*
X1357876D03*
X1360876D03*
Y1257160D03*
X1357876D03*
X1354876D03*
X1366876Y1260160D03*
Y1257160D03*
X1376262Y116594D03*
X1382205Y110784D03*
X1387205D03*
X1376262Y119594D03*
X1386784Y124663D03*
X1376696Y124283D03*
X1381762Y124879D03*
X1375103Y161306D03*
X1372354Y157370D03*
X1384319Y218085D03*
X1381519D03*
X1386846Y249108D03*
X1378227Y248371D03*
X1384265Y320871D03*
Y325371D03*
X1383551Y337808D03*
X1384265Y329871D03*
X1383634Y342766D03*
X1384265Y334371D03*
X1375073Y356871D03*
Y361371D03*
X1383505Y349437D03*
X1384265Y352371D03*
X1372232Y361298D03*
X1383963Y366675D03*
X1377024Y397713D03*
X1375108Y420838D03*
X1375171Y424741D03*
X1375400Y435192D03*
X1375360Y432234D03*
X1383343Y508228D03*
X1383907Y516591D03*
X1383556Y554388D03*
X1378415Y558795D03*
X1383608Y571927D03*
X1378415Y563984D03*
Y569776D03*
X1378957Y584457D03*
X1383000Y584500D03*
X1382997Y581317D03*
X1383425Y590425D03*
X1378415Y605295D03*
X1383608Y618427D03*
X1378415Y610484D03*
Y616276D03*
X1383425Y636925D03*
X1378957Y630957D03*
X1384657Y631620D03*
X1378957Y627988D03*
X1378415Y649795D03*
Y654984D03*
Y660776D03*
X1386289Y672488D03*
X1383425Y681425D03*
X1378957Y675457D03*
X1383000Y675500D03*
X1378415Y696795D03*
Y701984D03*
X1378957Y719488D03*
X1378415Y707776D03*
X1383425Y728425D03*
X1378957Y722457D03*
X1385290Y722400D03*
X1371000Y811620D03*
X1381000Y804000D03*
X1373000D03*
X1369000D03*
X1385360Y811757D03*
X1381428Y812287D03*
X1375193Y811724D03*
X1376708Y901000D03*
X1378500Y925500D03*
X1374369Y925499D03*
X1370500Y925500D03*
X1382500D03*
X1382775Y930281D03*
X1373948Y940103D03*
X1374500Y930500D03*
X1370500D03*
X1378500D03*
X1381519Y996280D03*
X1383162Y991829D03*
X1373534Y1012325D03*
Y1004680D03*
X1378938Y1000586D03*
X1374034Y1015825D03*
X1374059Y1018860D03*
X1376359Y1016825D03*
X1378559Y1038534D03*
X1384784Y1033783D03*
X1385929Y1038665D03*
X1373874Y1032266D03*
Y1035716D03*
X1385152Y1046591D03*
X1377087Y1106365D03*
X1371362Y1101917D03*
X1371297Y1106897D03*
X1382456Y1107997D03*
X1374112Y1110092D03*
X1377778Y1115896D03*
X1384656Y1112397D03*
X1382456Y1110897D03*
Y1113797D03*
X1384556Y1109397D03*
X1377778Y1118396D03*
X1369233Y1169884D03*
Y1172384D03*
X1371733D03*
Y1169884D03*
Y1167384D03*
Y1164884D03*
Y1162384D03*
X1369233D03*
Y1164884D03*
Y1167384D03*
X1376861Y1160834D03*
X1383024D03*
X1369233Y1174884D03*
X1371733D03*
X1375459Y1197471D03*
Y1193471D03*
X1379959Y1197471D03*
Y1193471D03*
X1397848Y97667D03*
X1388231Y116594D03*
X1393504Y102495D03*
X1388231Y119594D03*
X1399648Y132515D03*
Y121742D03*
Y118342D03*
X1391765Y125107D03*
X1399648Y135915D03*
X1393238Y142862D03*
X1400379Y143762D03*
X1394279Y148717D03*
X1388128Y138838D03*
X1399327Y195176D03*
X1396827D03*
X1400845Y199248D03*
Y201748D03*
X1398681Y206806D03*
X1401181D03*
X1399408Y210509D03*
X1396908D03*
X1390832Y216970D03*
Y219470D03*
X1390898Y226320D03*
X1390832Y221970D03*
X1388119Y216385D03*
X1402855Y227824D03*
X1398600Y230556D03*
X1393859Y228646D03*
X1397585Y242078D03*
X1392816Y232971D03*
X1389466Y244571D03*
X1396809Y256394D03*
X1395726Y320529D03*
X1395568Y325529D03*
X1395726Y330529D03*
X1395736Y335529D03*
X1395726Y340529D03*
Y345529D03*
Y360529D03*
Y350529D03*
Y355529D03*
X1391896Y365529D03*
X1399884Y367165D03*
X1387847Y366710D03*
X1400231Y390256D03*
X1396528Y397454D03*
X1399571Y397418D03*
X1393575Y397310D03*
X1390553Y397436D03*
X1391623Y409900D03*
X1387125Y417312D03*
X1393177Y424804D03*
X1389557Y424678D03*
X1389431Y421593D03*
X1390271Y417578D03*
X1393208Y428109D03*
X1393336Y431100D03*
X1403085Y460565D03*
X1393944Y507856D03*
X1394044Y510990D03*
X1397079Y527726D03*
Y548726D03*
Y544726D03*
X1395605Y556217D03*
X1390741Y561000D03*
Y569000D03*
Y565000D03*
X1391087Y581317D03*
X1398946Y621311D03*
X1390741Y611500D03*
Y607500D03*
Y615500D03*
X1391586Y623692D03*
X1398946Y629311D03*
Y625311D03*
X1397000Y652000D03*
Y656000D03*
Y660000D03*
Y699000D03*
Y707000D03*
Y703000D03*
X1391040Y812027D03*
X1386335Y803704D03*
X1390537Y803679D03*
X1394537Y803653D03*
X1398530Y811717D03*
X1402417Y811692D03*
X1400069Y827515D03*
X1401300Y820485D03*
X1395955Y832697D03*
X1402000Y840000D03*
Y848000D03*
X1399872Y845109D03*
X1402000Y864000D03*
X1391316Y857849D03*
X1388488Y857822D03*
X1402000Y876000D03*
X1390182Y873460D03*
X1387582Y873487D03*
X1402000Y884000D03*
Y892000D03*
X1388479Y892923D03*
X1385979D03*
X1390979D03*
X1402000Y900000D03*
X1387520Y905307D03*
X1387753Y912629D03*
X1394891Y914783D03*
X1402187Y908270D03*
X1387504Y899931D03*
X1390541Y900086D03*
X1388980Y921075D03*
X1401000Y925789D03*
X1396869Y958707D03*
X1402064Y965913D03*
X1389192Y992568D03*
X1398854Y987277D03*
X1394885Y999941D03*
X1392031Y1004375D03*
X1385732Y1029482D03*
X1389762Y1043055D03*
X1387813Y1030952D03*
X1399807Y1036155D03*
X1399852Y1039779D03*
X1388523Y1090090D03*
X1392691Y1089224D03*
X1392086Y1092743D03*
X1392691Y1086724D03*
Y1084224D03*
Y1081724D03*
X1390191D03*
Y1084224D03*
Y1086724D03*
X1403101Y1104335D03*
X1400543Y1105552D03*
X1396749Y1104792D03*
X1388451Y1093048D03*
X1386656Y1107997D03*
X1398256Y1106867D03*
X1386756Y1110597D03*
X1394341Y1113648D03*
X1388992Y1118801D03*
Y1116101D03*
X1387541Y1113648D03*
X1391841D03*
X1388722Y1162384D03*
Y1164884D03*
Y1167384D03*
Y1169884D03*
Y1172384D03*
X1391222Y1162384D03*
Y1164884D03*
Y1167384D03*
Y1169884D03*
Y1172384D03*
X1388722Y1174884D03*
X1391222D03*
X1393695Y1186709D03*
Y1184209D03*
Y1181709D03*
Y1179209D03*
X1391380Y1190121D03*
Y1192621D03*
X1385821Y1260160D03*
X1391821Y1257160D03*
X1394821D03*
X1385821D03*
X1388821D03*
X1397821Y1260160D03*
Y1257160D03*
X1400821Y1260160D03*
Y1257160D03*
X1388821Y1260160D03*
X1394821D03*
X1391821D03*
X1385052Y1303139D03*
X1389052D03*
X1406308Y103411D03*
X1406702Y97667D03*
X1417498Y90650D03*
X1417248Y95236D03*
X1402098Y95111D03*
X1406948Y111255D03*
Y114655D03*
X1406467Y106561D03*
X1406948Y128828D03*
Y125428D03*
X1403845Y199248D03*
X1401827Y195176D03*
X1404327D03*
X1403845Y202048D03*
X1407445Y230117D03*
X1403461Y238714D03*
X1402942Y246874D03*
X1405162Y244297D03*
X1402921Y322403D03*
X1409830Y347649D03*
X1404690Y362209D03*
X1416912Y386903D03*
X1408854Y381207D03*
X1416470Y381397D03*
X1402968Y390177D03*
X1414369Y398056D03*
X1408254Y398041D03*
X1407844Y411033D03*
X1415610Y417644D03*
X1415674Y421278D03*
X1417856Y448419D03*
X1414903Y469905D03*
X1410903Y470419D03*
Y461919D03*
X1418903Y461419D03*
X1411269Y481467D03*
X1415623Y492268D03*
X1415823Y482165D03*
X1416061Y504825D03*
X1413561D03*
X1411061D03*
X1415064Y500202D03*
X1406910Y495982D03*
X1416413Y495649D03*
X1406910Y491982D03*
X1416002Y517401D03*
X1413502D03*
X1411002D03*
X1416553Y522569D03*
Y525369D03*
X1415168Y531882D03*
X1412668D03*
X1409618Y531948D03*
X1401438Y534211D03*
X1405992Y534909D03*
X1405619Y541135D03*
X1405685Y546553D03*
X1405708Y552726D03*
X1415103Y555194D03*
Y563194D03*
Y571194D03*
X1416660Y581222D03*
Y591215D03*
X1401383Y611071D03*
X1416832Y610562D03*
Y607762D03*
X1411622Y610548D03*
X1407566Y622285D03*
X1407754Y616905D03*
X1418439Y633736D03*
X1407952Y633724D03*
X1413432Y633716D03*
X1407835Y627713D03*
X1405229Y652028D03*
X1405000Y660000D03*
X1410000Y685000D03*
Y681000D03*
X1404500Y675000D03*
X1410000Y701000D03*
Y697000D03*
X1418000Y696000D03*
Y701000D03*
X1410000Y709000D03*
Y713000D03*
X1405000Y707000D03*
Y703000D03*
X1418000Y717000D03*
X1410000D03*
X1404500Y722000D03*
X1410000Y729000D03*
Y725000D03*
X1418000Y724000D03*
Y729000D03*
X1404249Y735858D03*
X1410000Y745000D03*
Y741000D03*
X1418000Y740000D03*
Y745000D03*
X1407482Y750853D03*
X1410000Y757000D03*
Y753000D03*
Y761000D03*
X1418000D03*
X1406867Y783273D03*
X1409115Y773520D03*
X1414597Y792375D03*
X1406483Y811717D03*
X1413500Y832000D03*
Y828000D03*
X1413449Y823934D03*
X1405402Y819917D03*
X1405500Y844000D03*
Y836000D03*
X1413500Y848000D03*
Y840000D03*
Y836000D03*
Y844000D03*
X1405500Y860000D03*
X1413500Y864000D03*
Y860000D03*
Y856000D03*
Y852000D03*
X1405500Y880000D03*
Y868000D03*
X1413500Y876000D03*
X1417797Y879501D03*
X1413500Y872000D03*
Y868000D03*
X1405500Y888000D03*
Y896000D03*
X1417081D03*
X1413500Y892000D03*
Y884000D03*
Y888000D03*
X1413733Y911137D03*
X1412376Y907848D03*
X1414876D03*
X1417376D03*
X1409876D03*
X1405500Y904000D03*
X1404760Y915186D03*
X1413500Y904000D03*
Y900000D03*
X1417284Y911009D03*
X1416802Y936845D03*
X1416244Y942285D03*
X1419337D03*
X1405214Y965074D03*
X1419446Y977192D03*
X1416618Y992307D03*
X1401265Y989465D03*
X1407265D03*
X1414143Y985486D03*
X1412698Y997590D03*
X1412609Y1008766D03*
X1412759Y1016266D03*
X1402215Y1020440D03*
X1414851Y1058097D03*
X1412351D03*
X1407351D03*
X1409851D03*
X1417351D03*
X1414851Y1060697D03*
X1412351D03*
X1407351D03*
X1409851D03*
X1417351D03*
X1405677Y1086796D03*
X1408177D03*
X1410677D03*
X1413177D03*
X1415677D03*
Y1084296D03*
X1413177D03*
X1410677D03*
X1408177D03*
X1405677D03*
X1416005Y1090288D03*
X1410546Y1106298D03*
X1404821Y1101917D03*
X1404756Y1106897D03*
X1416005Y1093088D03*
X1414584Y1107997D03*
X1411237Y1115896D03*
X1407571Y1110092D03*
X1414584Y1113797D03*
X1416784Y1112397D03*
X1414584Y1110897D03*
X1416684Y1109397D03*
X1411237Y1118396D03*
X1409425Y1129238D03*
X1413177Y1128894D03*
X1409492Y1167384D03*
Y1169884D03*
Y1172384D03*
X1406992D03*
Y1169884D03*
X1416550Y1162384D03*
Y1164884D03*
Y1167384D03*
Y1169884D03*
Y1172384D03*
X1406992Y1167384D03*
Y1164884D03*
Y1162384D03*
X1409492D03*
Y1164884D03*
X1416736Y1158200D03*
X1416550Y1174884D03*
X1409492D03*
X1406992D03*
X1407995Y1179421D03*
Y1181921D03*
Y1184421D03*
Y1186921D03*
X1410310Y1192621D03*
Y1190121D03*
X1404845D03*
Y1192621D03*
X1408736Y1222194D03*
X1412736D03*
X1416736D03*
X1408736Y1238194D03*
Y1234194D03*
Y1230194D03*
Y1226194D03*
X1412736Y1238194D03*
Y1234194D03*
Y1230194D03*
Y1226194D03*
X1416736Y1238194D03*
Y1234194D03*
Y1230194D03*
Y1226194D03*
X1412736Y1246194D03*
Y1242194D03*
X1416736Y1246194D03*
Y1242194D03*
X1408736D03*
Y1246194D03*
X1409821Y1260160D03*
X1412821D03*
Y1257160D03*
X1409821D03*
X1406821D03*
X1403821D03*
X1415821Y1260160D03*
Y1257160D03*
X1403821Y1260160D03*
X1406821D03*
X1417711Y1301729D03*
X1410817Y1305417D03*
X1407825Y1426975D03*
X1408536Y1536570D03*
X1407747Y1549054D03*
X1408044Y1559306D03*
X1407255Y1571732D03*
X1422810Y90615D03*
X1427131Y99961D03*
X1427181Y95236D03*
X1425993Y212978D03*
Y207978D03*
Y210478D03*
Y215478D03*
X1429322Y264180D03*
X1431822D03*
X1429247Y258880D03*
X1434166Y325361D03*
X1434164Y339232D03*
X1434038Y334114D03*
X1435818Y352361D03*
X1421005Y407616D03*
X1417903Y439919D03*
X1434997Y442603D03*
X1427117Y443071D03*
X1423427Y456839D03*
X1425927D03*
X1423427Y454339D03*
X1425927D03*
X1432414Y459371D03*
X1423427Y459339D03*
X1425927D03*
X1418903Y469905D03*
X1431484Y470045D03*
X1427484Y462004D03*
X1422499Y485138D03*
X1419650Y485128D03*
X1426384Y478625D03*
X1428084Y482425D03*
X1427499Y485138D03*
X1424999D03*
X1426384Y476125D03*
X1418253Y529169D03*
X1417668Y531882D03*
X1424129Y537658D03*
X1427832Y539731D03*
X1424129Y540458D03*
X1432590Y544895D03*
X1435390D03*
X1427832Y542231D03*
X1432890Y541895D03*
X1417903Y555194D03*
Y563194D03*
Y571194D03*
X1422260Y581222D03*
X1419460D03*
X1435119Y590801D03*
X1422260Y591215D03*
X1419460D03*
X1431000Y591000D03*
X1434944Y597130D03*
X1433114Y620653D03*
Y617853D03*
X1419632Y607762D03*
X1422432D03*
X1425232Y610562D03*
Y607762D03*
X1422432Y610562D03*
X1419632D03*
X1430944Y605443D03*
X1420452Y628078D03*
X1430175Y627852D03*
X1425452Y633473D03*
X1430481Y658153D03*
X1433529Y660564D03*
X1426615Y674112D03*
X1429000Y685000D03*
X1418000D03*
Y681000D03*
X1425909Y691120D03*
X1433464Y692658D03*
X1418000Y689000D03*
X1433053Y701839D03*
X1426000Y717000D03*
X1418000Y705000D03*
X1431522Y708633D03*
X1434000Y712958D03*
X1430289Y734961D03*
X1418000Y733000D03*
X1417969Y720894D03*
X1429000Y729000D03*
X1434000Y751958D03*
X1433153Y745839D03*
X1427000Y766500D03*
X1426000Y761000D03*
X1435000Y765500D03*
X1434000Y756958D03*
X1418023Y765343D03*
X1427000Y781834D03*
Y770500D03*
X1435000D03*
X1427000Y794500D03*
X1435000Y802500D03*
X1427000Y810500D03*
Y814500D03*
X1435000D03*
Y809500D03*
X1427000Y802500D03*
Y830500D03*
Y826500D03*
X1434975Y830500D03*
X1435000Y825500D03*
X1427000Y842500D03*
Y838500D03*
X1435000Y846500D03*
X1427000D03*
X1435043Y874694D03*
X1435082Y869475D03*
X1423190Y905295D03*
X1429059Y908579D03*
X1426085Y910281D03*
X1429907Y936998D03*
X1424897Y936777D03*
X1435516Y936000D03*
X1420699Y958452D03*
X1430839Y965546D03*
X1420740Y1008766D03*
X1428740Y1000766D03*
X1420740Y996766D03*
X1428864D03*
X1420740Y1012266D03*
X1428740Y1016266D03*
X1428823Y1020266D03*
X1435229Y1104335D03*
X1432671Y1105552D03*
X1428877Y1104792D03*
X1418784Y1107997D03*
X1430384Y1106867D03*
X1418884Y1110597D03*
X1421120Y1116101D03*
Y1118801D03*
X1426469Y1113648D03*
X1423969D03*
X1419669D03*
X1419050Y1162384D03*
Y1164884D03*
Y1167384D03*
Y1169884D03*
Y1172384D03*
Y1174884D03*
X1420625Y1186709D03*
Y1184209D03*
Y1181709D03*
Y1179209D03*
X1418310Y1192621D03*
Y1190121D03*
X1420736Y1222194D03*
X1424736D03*
X1428736D03*
X1432736D03*
X1420736Y1238194D03*
Y1234194D03*
Y1230194D03*
Y1226194D03*
X1424736Y1238194D03*
Y1234194D03*
Y1230194D03*
Y1226194D03*
X1428736Y1238194D03*
Y1234194D03*
Y1230194D03*
Y1226194D03*
X1432736Y1234194D03*
Y1230194D03*
Y1226194D03*
X1420736Y1246194D03*
Y1242194D03*
X1424736Y1246194D03*
Y1242194D03*
X1428736Y1246194D03*
Y1242194D03*
X1421821Y1257160D03*
X1418821D03*
Y1260160D03*
X1421821D03*
X1431080Y1301702D03*
X1421238Y1301712D03*
X1428009Y1301760D03*
X1424732Y1301603D03*
X1432258Y1414600D03*
X1430374Y1492474D03*
X1420877Y1494706D03*
X1421964Y1502813D03*
X1423930Y1520364D03*
X1429587Y1527450D03*
X1433405Y1546001D03*
X1432913Y1568679D03*
X1449685Y34228D03*
X1436045Y77393D03*
Y74793D03*
Y85193D03*
Y82593D03*
Y79993D03*
X1444370Y98551D03*
X1436089Y92874D03*
X1447265Y111223D03*
Y114623D03*
X1447920Y103783D03*
X1438116Y107649D03*
Y104249D03*
X1447265Y125396D03*
Y128796D03*
X1442682Y147540D03*
X1446454Y141247D03*
X1451301Y148277D03*
X1435138Y162368D03*
X1437738D03*
X1444838Y162793D03*
Y165393D03*
Y170493D03*
Y167993D03*
X1451762Y177616D03*
X1449841Y181009D03*
X1447046Y181366D03*
X1443835Y181426D03*
X1444043Y184221D03*
X1446660Y184012D03*
X1448079Y211359D03*
Y213859D03*
X1436449Y213213D03*
Y210713D03*
X1440521Y211695D03*
X1443021D03*
X1440521Y208695D03*
X1443321D03*
X1436449Y208213D03*
Y215713D03*
X1451785Y265896D03*
X1446698Y265701D03*
X1441016Y267526D03*
Y270026D03*
X1443516D03*
X1438216D03*
X1443516Y267526D03*
X1438216D03*
X1448333Y281716D03*
X1449060Y329861D03*
X1448948Y326448D03*
X1449060Y320861D03*
X1438829Y329861D03*
X1437064Y320861D03*
X1448822Y345324D03*
X1448734Y332910D03*
X1448500Y340575D03*
X1439712Y336673D03*
X1440420Y346833D03*
X1449060Y356861D03*
X1441180Y354909D03*
X1448572Y349441D03*
X1449060Y352361D03*
X1447502Y360785D03*
X1434697Y347125D03*
X1439719Y350387D03*
X1443041Y363648D03*
X1434608Y362584D03*
X1438768Y371655D03*
X1442633Y371502D03*
X1445906Y366030D03*
X1440523Y382747D03*
X1435424Y430361D03*
X1440390Y456652D03*
X1442890D03*
Y459152D03*
Y461652D03*
X1440390Y459152D03*
Y461652D03*
X1436930Y461818D03*
X1433960Y491214D03*
X1449293Y491133D03*
X1442721Y495151D03*
X1437663Y492987D03*
X1442421Y498151D03*
X1433960Y493714D03*
X1437663Y495487D03*
X1445221Y498151D03*
X1449293Y493633D03*
Y496133D03*
Y498633D03*
X1445221Y495151D03*
X1439462Y537877D03*
X1449393Y553297D03*
Y555897D03*
X1446988Y548418D03*
X1439462Y540377D03*
X1435390Y541895D03*
X1444488Y548418D03*
X1439488D03*
X1441988D03*
X1439462Y542877D03*
Y545377D03*
X1449393Y558497D03*
Y566797D03*
Y563697D03*
Y561097D03*
X1443388Y570686D03*
X1446183Y570478D03*
X1435668Y582747D03*
X1446600Y576484D03*
X1446243Y573689D03*
X1443597Y573303D03*
X1449993Y578405D03*
X1438944Y597232D03*
X1443775Y596089D03*
X1448994Y596782D03*
X1440930Y613913D03*
Y616713D03*
Y619513D03*
X1434944Y605443D03*
X1438944Y605637D03*
X1437790Y625013D03*
X1435952Y642184D03*
X1446323Y673183D03*
X1437738Y686992D03*
X1448991Y694392D03*
X1451976Y693844D03*
X1437533Y704398D03*
Y699280D03*
X1438930Y716363D03*
X1446860Y730735D03*
X1446538Y719548D03*
X1437738Y730992D03*
X1446717Y735536D03*
X1437533Y743280D03*
Y748398D03*
X1447289Y776461D03*
X1446000Y770500D03*
X1451000Y793458D03*
Y798458D03*
X1450253Y787339D03*
X1443000Y802500D03*
X1447000Y810500D03*
Y818500D03*
X1435000D03*
X1448000Y834500D03*
X1443000Y846500D03*
X1435000Y834500D03*
X1449000Y844500D03*
X1435212Y854042D03*
X1448726Y864400D03*
X1439891Y873821D03*
X1445367Y891888D03*
X1441223Y891957D03*
X1435745Y901500D03*
X1443231Y899006D03*
X1439103Y898564D03*
X1447261Y898571D03*
X1446022Y927000D03*
X1448137Y949440D03*
X1439031Y957683D03*
X1441088Y976409D03*
X1433996Y981437D03*
X1440700Y981763D03*
X1435669Y1005366D03*
X1440869Y1010256D03*
X1435197Y1028372D03*
X1442674Y1106365D03*
X1436949Y1101917D03*
X1436884Y1106897D03*
X1439699Y1110092D03*
X1443365Y1115896D03*
Y1118396D03*
X1442448Y1160834D03*
X1434820Y1162384D03*
Y1164884D03*
Y1167384D03*
Y1169884D03*
Y1172384D03*
X1437320D03*
Y1169884D03*
Y1167384D03*
Y1164884D03*
Y1162384D03*
X1434925Y1179421D03*
Y1181921D03*
Y1184421D03*
Y1186921D03*
X1434820Y1174884D03*
X1437320D03*
X1437240Y1192621D03*
Y1190121D03*
X1436736Y1222194D03*
Y1226194D03*
X1443660Y1310698D03*
X1440260D03*
X1446817Y1335846D03*
X1441200Y1338700D03*
X1435900Y1340800D03*
X1439258Y1414600D03*
X1446135Y1530876D03*
X1443103Y1527201D03*
X1441145Y1540415D03*
X1440153Y1563093D03*
X1443769Y1562173D03*
X1452717Y34052D03*
X1457347Y31518D03*
X1457829Y26425D03*
X1455013Y43128D03*
X1460466Y76587D03*
Y72615D03*
X1461905Y100625D03*
X1454924Y97475D03*
X1454855Y106186D03*
X1457667Y118335D03*
Y121735D03*
Y132509D03*
Y135909D03*
X1462484Y141247D03*
X1466971Y143518D03*
X1453921Y143740D03*
X1466071Y152373D03*
X1455016Y168697D03*
X1452343Y172190D03*
X1464628Y171523D03*
X1456104Y191941D03*
X1464158Y192490D03*
X1458113Y206767D03*
X1463113D03*
X1460613D03*
X1451782Y213132D03*
X1463243Y221708D03*
X1460743D03*
X1458243D03*
X1457658Y224421D03*
X1459358Y231021D03*
Y228221D03*
X1451782Y215632D03*
X1459909Y236189D03*
X1464909D03*
X1462409D03*
X1459850Y248765D03*
X1464850D03*
X1462350D03*
X1452026Y256303D03*
X1456801Y266114D03*
X1460047Y270695D03*
Y268195D03*
X1462547Y270695D03*
Y268195D03*
X1465347Y270695D03*
Y268195D03*
X1454274Y281982D03*
X1459060Y320861D03*
Y325361D03*
Y329861D03*
Y338861D03*
Y343361D03*
Y334361D03*
Y347861D03*
Y352361D03*
X1459873Y391705D03*
X1463145Y391579D03*
X1458214Y406231D03*
X1464536Y433114D03*
X1458912Y581659D03*
X1455419Y578986D03*
X1454944Y596729D03*
X1453000Y614158D03*
Y616958D03*
Y619758D03*
X1450944Y605443D03*
X1458944D03*
X1461474Y655807D03*
X1455761Y683448D03*
X1468372Y673812D03*
X1460111Y683536D03*
X1451428Y673252D03*
X1460816Y727964D03*
X1455291Y759656D03*
X1455159Y763714D03*
X1454504Y777575D03*
X1454533Y784780D03*
X1454738Y772492D03*
X1454533Y789898D03*
X1453102Y821102D03*
X1454541Y831339D03*
X1453102Y826500D03*
X1452619Y836457D03*
X1461113Y871389D03*
X1457218Y888764D03*
X1452641Y888033D03*
X1451286Y898549D03*
X1462500Y905295D03*
X1461888Y936055D03*
X1462000Y957000D03*
X1458202Y960288D03*
X1457937Y966712D03*
X1457352Y976277D03*
X1459519Y989432D03*
X1467096Y988813D03*
X1456966Y998507D03*
X1458892Y1007522D03*
X1465658Y1006648D03*
X1465846Y1023900D03*
X1463025Y1018307D03*
X1459267Y1013678D03*
X1456280Y1023405D03*
X1459683Y1028377D03*
X1481905Y-69278D03*
Y-72678D03*
X1479972Y40780D03*
X1472146Y55513D03*
X1468371Y68581D03*
X1474746Y60513D03*
X1477606Y60438D03*
X1468384Y80581D03*
X1474874Y85731D03*
X1483287Y86012D03*
X1472514Y88801D03*
X1478428Y86046D03*
X1475431Y94351D03*
X1479380Y94279D03*
X1470567Y103621D03*
X1478624Y116594D03*
X1466278Y112083D03*
X1484567Y110784D03*
X1478624Y119594D03*
X1479058Y124283D03*
X1484124Y124879D03*
X1477465Y161306D03*
X1469221Y152562D03*
X1474716Y157370D03*
X1478800Y168665D03*
Y176665D03*
X1469913Y183834D03*
X1470023Y178560D03*
X1470086Y172665D03*
X1470899Y186629D03*
X1469433Y190185D03*
X1478800Y192665D03*
Y196665D03*
X1470203Y200864D03*
X1478913Y186778D03*
X1478832Y204864D03*
X1470292Y212455D03*
X1470226Y207037D03*
X1478832Y208864D03*
X1467593Y221642D03*
X1474473Y219379D03*
X1475101Y228631D03*
X1480589Y248371D03*
X1471507Y265897D03*
X1469007D03*
X1477549Y327200D03*
Y322700D03*
Y345200D03*
Y340700D03*
Y331700D03*
Y358700D03*
Y349700D03*
Y354200D03*
X1480702Y368516D03*
X1468309Y408861D03*
X1475236Y412482D03*
X1466231Y423671D03*
X1469538Y416795D03*
X1466653Y428582D03*
X1471375Y433115D03*
X1477597Y682997D03*
X1475264Y680933D03*
X1474713Y685247D03*
X1479297Y693630D03*
X1476794Y691447D03*
X1476716Y704398D03*
X1479500Y689630D03*
Y697630D03*
X1474425Y712925D03*
X1479759Y720885D03*
X1469957Y706957D03*
X1474000Y707000D03*
X1479794Y709388D03*
X1472000Y727500D03*
X1469116Y719055D03*
X1480000Y731500D03*
X1479759Y743500D03*
X1479657Y735500D03*
X1469957Y750957D03*
X1476716Y748398D03*
X1480000Y739500D03*
X1471006Y744818D03*
X1470801Y739280D03*
X1474425Y756925D03*
X1479665Y754555D03*
X1474000Y753093D03*
X1476677Y827626D03*
X1473489Y861354D03*
X1474060Y877196D03*
X1473468Y874267D03*
X1482387Y872940D03*
X1474883Y868206D03*
X1473433Y891043D03*
X1473387Y897425D03*
X1482195Y885807D03*
X1470925Y920575D03*
X1480343Y914776D03*
X1480109Y943496D03*
X1480144Y946880D03*
X1479441Y961941D03*
X1480414Y952214D03*
X1476500Y974000D03*
X1482237Y966028D03*
X1479196Y970000D03*
X1480414Y975064D03*
X1475096Y980330D03*
X1471096D03*
X1479096Y988813D03*
X1471296D03*
X1475096D03*
X1483096D03*
X1475062Y1008300D03*
Y1002453D03*
X1482535Y1024254D03*
X1468869Y1018469D03*
X1476230Y1030672D03*
X1473230D03*
X1471374Y1118654D03*
X1474384Y1109564D03*
X1480231D03*
X1474384Y1122164D03*
X1480231D03*
X1474384Y1134764D03*
X1480231D03*
X1474384Y1147364D03*
X1480231D03*
X1474384Y1172564D03*
X1480231D03*
X1474384Y1159964D03*
X1480231D03*
X1474384Y1185164D03*
X1480231D03*
X1483308Y1214372D03*
X1479063Y1218169D03*
X1498621Y19043D03*
X1489556Y17645D03*
X1498621Y31043D03*
Y23043D03*
X1489829Y29424D03*
X1490563Y23043D03*
X1500210Y97667D03*
X1483287Y94374D03*
X1490593Y116594D03*
X1495866Y102495D03*
X1489567Y110784D03*
X1490593Y119594D03*
X1494127Y125107D03*
X1489146Y124663D03*
X1495600Y142862D03*
X1496641Y148717D03*
X1490490Y138838D03*
X1493260Y226320D03*
X1493194Y221970D03*
X1490481Y216385D03*
X1493194Y216970D03*
Y219470D03*
X1486681Y218085D03*
X1483881D03*
X1496221Y228646D03*
X1495178Y232971D03*
X1491828Y244571D03*
X1489208Y249108D03*
X1499171Y256394D03*
X1497446Y295877D03*
X1486860Y327200D03*
X1500659Y330024D03*
X1495605Y322700D03*
X1487318Y318200D03*
X1486360Y322700D03*
Y345200D03*
X1500386Y344642D03*
X1486913Y340327D03*
X1487152Y331272D03*
X1495689Y332534D03*
X1495521Y340700D03*
X1486360Y349700D03*
X1495521Y349681D03*
X1495925Y358700D03*
X1499839Y354001D03*
X1486890Y368576D03*
X1494286Y372699D03*
X1488000Y731500D03*
X1495500Y750500D03*
X1488731Y739500D03*
X1496629Y765000D03*
X1496763Y777000D03*
X1493301Y776911D03*
X1496814Y773000D03*
X1497000Y781000D03*
X1496756Y785000D03*
X1491425Y798425D03*
X1499633Y787794D03*
X1493716Y789898D03*
X1486957Y792457D03*
X1495170Y796670D03*
X1487050Y809413D03*
X1496845Y809000D03*
X1496806Y817000D03*
X1496621Y829000D03*
X1496447Y821000D03*
X1486386Y825296D03*
X1493092Y820444D03*
X1493038Y833898D03*
X1495240Y825000D03*
X1491425Y842425D03*
X1486957Y836457D03*
X1492625Y837324D03*
X1488138Y878339D03*
Y872839D03*
X1482566Y882154D03*
X1494954Y895264D03*
X1484824Y927324D03*
X1487240Y924453D03*
X1497063Y934000D03*
X1496072Y940201D03*
X1483324Y939324D03*
X1482921Y931324D03*
X1485500Y932500D03*
X1497075Y961000D03*
X1487240Y952012D03*
X1496072Y953981D03*
X1495500Y972500D03*
X1489500D03*
X1487096Y988813D03*
X1491096D03*
X1495096D03*
X1499096D03*
X1490235Y1004816D03*
X1487266Y1002046D03*
X1486030Y1016827D03*
X1491877D03*
X1486030Y1029427D03*
X1491877D03*
X1496140Y1105091D03*
X1496185Y1102091D03*
X1496140Y1117691D03*
X1496185Y1114691D03*
Y1127291D03*
X1496140Y1130291D03*
X1496185Y1139891D03*
X1496140Y1155491D03*
Y1142891D03*
X1496185Y1152491D03*
X1496140Y1168091D03*
X1496185Y1165091D03*
X1496140Y1180691D03*
X1496185Y1177691D03*
X1482705Y1200001D03*
X1489793Y1207737D03*
X1497693Y1230407D03*
X1508670Y103411D03*
X1509064Y97667D03*
X1504460Y95111D03*
X1509310Y114655D03*
Y111255D03*
X1508829Y106561D03*
X1502010Y121742D03*
X1509310Y125428D03*
Y128828D03*
X1502010Y118342D03*
Y132515D03*
Y135915D03*
X1502741Y143762D03*
X1506689Y195176D03*
X1506207Y199248D03*
X1501689Y195176D03*
X1503207Y199248D03*
X1499189Y195176D03*
X1504189D03*
X1506207Y202048D03*
X1503207Y201748D03*
X1499270Y210509D03*
X1501043Y206806D03*
X1501770Y210509D03*
X1503543Y206806D03*
X1509807Y230117D03*
X1500962Y230556D03*
X1505217Y227824D03*
X1505823Y238714D03*
X1499947Y242078D03*
X1505304Y246874D03*
X1507524Y244297D03*
X1503884Y295549D03*
X1501500Y321000D03*
X1501000Y317500D03*
X1501684Y336561D03*
X1516838Y347422D03*
X1515909Y354601D03*
X1511950Y401513D03*
Y398113D03*
X1509550Y412287D03*
Y415687D03*
Y426460D03*
Y440633D03*
Y429860D03*
Y444033D03*
X1516636Y458711D03*
X1509550Y472787D03*
Y469387D03*
Y483560D03*
Y486960D03*
Y516921D03*
Y513521D03*
Y527694D03*
Y531094D03*
X1513284Y552466D03*
X1504495Y796844D03*
X1510527Y833500D03*
X1504938Y859711D03*
X1500353Y859855D03*
X1500638Y873839D03*
X1512712Y867418D03*
X1502158Y899479D03*
X1510527Y908951D03*
X1513927D03*
X1504208Y909740D03*
X1509274Y921226D03*
X1505337Y921240D03*
X1509500Y937000D03*
Y944138D03*
X1516500Y947500D03*
X1501812Y938397D03*
X1512161Y957541D03*
X1509500Y950500D03*
X1498973Y975443D03*
X1511000Y970500D03*
X1511096Y988813D03*
X1507096D03*
X1503096D03*
X1515096D03*
X1513286Y1012354D03*
X1507831Y1009354D03*
X1507786Y1012354D03*
Y1024954D03*
X1513286D03*
X1507831Y1021954D03*
X1503572Y1034538D03*
X1501640Y1105091D03*
Y1117691D03*
Y1130291D03*
Y1142891D03*
Y1155491D03*
Y1168091D03*
Y1180691D03*
X1508356Y1220068D03*
X1500675Y1227300D03*
X1506807Y1234921D03*
X1507692Y1224472D03*
X1507058Y1229402D03*
X1517261Y-33758D03*
Y-30358D03*
X1525172Y90615D03*
X1519860Y90650D03*
X1529493Y99961D03*
X1529543Y95236D03*
X1519610D03*
X1528355Y210478D03*
Y215478D03*
Y212978D03*
Y207978D03*
X1519321Y378600D03*
X1519952Y391001D03*
X1519321Y382600D03*
X1519952Y394401D03*
Y408574D03*
Y405174D03*
Y422747D03*
Y419347D03*
Y436921D03*
Y433521D03*
X1519436Y458711D03*
X1521963Y453682D03*
X1520200Y455921D03*
X1518780Y463600D03*
X1519952Y479899D03*
Y476499D03*
Y490673D03*
Y494073D03*
Y520633D03*
Y524033D03*
Y534806D03*
Y538206D03*
X1519185Y603600D03*
Y619600D03*
Y623600D03*
X1520729Y634190D03*
X1524200Y646098D03*
X1518517Y878898D03*
X1518452Y873780D03*
X1525022Y909558D03*
X1522881Y901034D03*
X1522954Y897951D03*
X1521085Y921094D03*
X1515179D03*
X1527267Y932647D03*
X1522209Y937846D03*
X1521500Y947500D03*
X1528500Y947612D03*
X1529128Y952978D03*
X1521085Y957340D03*
X1525583Y968500D03*
X1530767Y972981D03*
X1519863Y977637D03*
X1525005Y974323D03*
X1530594Y979952D03*
X1531096Y988813D03*
X1523096D03*
X1519096D03*
X1527096Y997860D03*
X1526810Y1025090D03*
X1522904Y1021256D03*
X1521939Y1040818D03*
X1522099Y1035521D03*
X1531993Y1056453D03*
X1531961Y1050849D03*
X1524953Y1051037D03*
X1517855Y1053457D03*
X1538407Y85539D03*
Y82939D03*
Y75139D03*
Y80339D03*
Y77739D03*
X1546732Y98551D03*
X1538451Y92874D03*
X1540478Y107649D03*
Y104249D03*
X1545044Y147540D03*
X1540100Y162368D03*
X1537500D03*
X1547200Y162793D03*
Y165393D03*
Y167993D03*
Y170493D03*
X1546197Y181426D03*
X1546405Y184221D03*
X1538811Y213213D03*
Y210713D03*
X1542883Y211695D03*
X1545383D03*
X1542883Y208695D03*
X1545683D03*
X1538811Y208213D03*
Y215713D03*
X1534184Y264180D03*
X1531684D03*
X1531609Y258880D03*
X1549060Y265701D03*
X1545878Y270026D03*
X1543378D03*
X1540578D03*
X1543378Y267526D03*
X1540578D03*
X1545878D03*
X1544736Y305156D03*
X1545583Y316363D03*
X1539140Y320863D03*
X1545636Y325363D03*
X1542797Y329863D03*
X1545846Y334363D03*
X1544951Y343363D03*
X1538133Y354553D03*
X1545434Y352363D03*
X1546183Y541863D03*
Y545263D03*
X1544375Y553407D03*
X1546875D03*
X1544375Y550907D03*
X1546875D03*
X1542704Y572162D03*
X1543946Y569928D03*
X1546293Y570962D03*
X1546036Y568475D03*
X1548080Y910757D03*
X1547644Y903060D03*
X1532067Y1041832D03*
X1531947Y1046212D03*
X1531546Y1062769D03*
X1536909Y1151870D03*
Y1159350D03*
X1540649Y1155610D03*
X1562828Y72615D03*
Y76587D03*
X1564267Y100625D03*
X1557286Y97475D03*
X1549627Y111223D03*
Y114623D03*
X1557217Y106186D03*
X1550282Y103783D03*
X1549627Y128796D03*
X1560029Y132509D03*
Y121735D03*
Y118335D03*
X1549627Y125396D03*
X1560029Y135909D03*
X1548816Y141247D03*
X1564846D03*
X1556283Y143740D03*
X1553663Y148277D03*
X1552203Y181009D03*
X1549408Y181366D03*
X1557378Y168697D03*
X1554705Y172190D03*
X1554124Y177616D03*
X1558466Y191941D03*
X1549022Y184012D03*
X1560475Y206767D03*
X1562975D03*
X1554144Y213132D03*
X1550441Y211359D03*
Y213859D03*
X1560605Y221708D03*
X1560020Y224421D03*
X1563105Y221708D03*
X1561720Y231021D03*
Y228221D03*
X1554144Y215632D03*
X1562271Y236189D03*
X1562212Y248765D03*
X1554388Y256303D03*
X1559163Y266114D03*
X1554147Y265896D03*
X1562409Y268195D03*
Y270695D03*
X1556636Y281982D03*
X1550695Y281716D03*
X1550931Y305158D03*
X1554403Y316363D03*
X1553534Y327337D03*
X1553910Y331798D03*
X1553597Y336601D03*
X1553862Y344867D03*
X1551175Y347283D03*
X1556588Y545528D03*
X1548359Y569426D03*
X1548645Y566929D03*
X1562385Y610400D03*
X1564670Y650122D03*
X1565132Y668153D03*
X1561552Y665455D03*
X1548629Y927836D03*
X1548504Y915689D03*
X1548616Y931602D03*
X1551163Y952888D03*
X1552000Y969850D03*
X1571895Y58013D03*
X1570733Y68581D03*
X1577108Y60513D03*
X1570746Y80581D03*
X1577236Y85731D03*
X1574876Y88801D03*
X1581742Y94279D03*
X1577793Y94351D03*
X1572929Y103621D03*
X1568640Y112083D03*
X1581420Y124283D03*
X1569333Y143518D03*
X1568433Y152373D03*
X1579827Y161306D03*
X1571583Y152562D03*
X1577078Y157370D03*
X1572275Y183834D03*
X1566990Y171523D03*
X1572385Y178560D03*
X1572448Y172665D03*
X1573261Y186629D03*
X1571795Y190185D03*
X1566520Y192490D03*
X1572565Y200864D03*
X1565475Y206767D03*
X1572654Y212455D03*
X1572588Y207037D03*
X1581194Y208864D03*
X1565605Y221708D03*
X1569955Y221642D03*
X1576835Y219379D03*
X1577463Y228631D03*
X1564771Y236189D03*
X1567271D03*
X1564712Y248765D03*
X1567212D03*
X1567709Y270695D03*
X1573869Y265897D03*
X1571369D03*
X1567709Y268195D03*
X1564909Y270695D03*
Y268195D03*
X1563877Y325363D03*
Y316363D03*
X1571625Y344131D03*
X1574775Y333549D03*
X1563877Y329863D03*
Y343363D03*
Y334363D03*
X1578587Y341787D03*
X1578420Y338309D03*
X1574775Y344127D03*
X1563877Y352363D03*
X1575935Y382109D03*
X1576940Y398082D03*
Y401482D03*
Y415655D03*
Y412255D03*
Y426428D03*
Y440602D03*
Y429828D03*
Y444002D03*
Y476468D03*
Y490641D03*
Y479868D03*
Y494041D03*
Y520602D03*
Y524002D03*
Y534775D03*
Y538175D03*
X1577862Y554121D03*
X1575934Y561420D03*
Y558917D03*
X1565323Y577716D03*
X1571755Y577937D03*
X1579760Y595500D03*
X1574760Y606929D03*
X1579260Y604567D03*
X1574720Y618400D03*
X1575001Y612592D03*
X1580418Y610072D03*
X1580354Y616317D03*
X1576297Y627600D03*
X1577077Y631712D03*
X1574880Y645891D03*
X1571888Y649380D03*
X1572141Y662981D03*
X1578000Y678776D03*
X1569434Y677111D03*
X1568872Y686971D03*
X1575192Y707592D03*
X1592187Y-69306D03*
Y-72706D03*
X1582187Y-33786D03*
Y-30386D03*
X1579968Y60438D03*
X1585649Y86012D03*
Y94374D03*
X1580790Y86046D03*
X1592955Y116594D03*
X1580986D03*
X1586929Y110784D03*
X1591929D03*
X1592955Y119594D03*
X1580986D03*
X1596489Y125107D03*
X1586486Y124879D03*
X1591508Y124663D03*
X1592852Y138838D03*
X1581162Y168665D03*
Y176665D03*
Y192665D03*
Y196665D03*
X1581275Y186778D03*
X1581194Y204864D03*
X1586243Y218085D03*
X1595622Y226320D03*
X1592843Y216385D03*
X1595556Y216970D03*
Y219470D03*
Y221970D03*
X1589043Y218085D03*
X1594190Y244571D03*
X1591570Y249108D03*
X1582951Y248371D03*
X1595069Y337361D03*
X1595109Y342663D03*
X1594466Y350984D03*
X1584240Y390995D03*
Y408568D03*
Y405168D03*
Y394395D03*
Y419341D03*
Y422741D03*
Y433515D03*
Y436915D03*
X1592635Y455911D03*
X1584240Y472781D03*
Y469381D03*
X1591443Y465332D03*
X1584240Y483554D03*
Y486954D03*
Y516915D03*
Y513515D03*
Y531088D03*
Y527688D03*
X1595460Y549800D03*
X1595260Y547075D03*
X1594760Y568000D03*
X1595364Y562800D03*
X1595300Y558800D03*
X1596790Y1442557D03*
X1592643Y1460707D03*
X1593019Y1457557D03*
X1591775Y1473090D03*
X1596038Y1492000D03*
X1591925Y1512075D03*
X1591333Y1501980D03*
X1590748Y1523377D03*
X1602572Y97667D03*
X1611032Y103411D03*
X1611426Y97667D03*
X1606822Y95111D03*
X1611672Y111255D03*
Y114655D03*
X1598228Y102495D03*
X1611191Y106561D03*
X1604372Y118342D03*
X1611672Y125428D03*
X1604372Y121742D03*
X1611672Y128828D03*
X1604372Y132515D03*
Y135915D03*
X1597962Y142862D03*
X1605103Y143762D03*
X1599003Y148717D03*
X1604051Y195176D03*
X1605569Y199248D03*
X1601551Y195176D03*
X1606551D03*
X1609051D03*
X1608569Y199248D03*
X1603405Y206806D03*
X1605905D03*
X1601632Y210509D03*
X1604132D03*
X1608569Y202048D03*
X1605569Y201748D03*
X1603324Y230556D03*
X1607579Y227824D03*
X1612169Y230117D03*
X1598583Y228646D03*
X1608185Y238714D03*
X1602309Y242078D03*
X1607666Y246874D03*
X1597540Y232971D03*
X1609886Y244297D03*
X1604677Y253198D03*
X1596691Y287397D03*
X1596197Y293477D03*
X1607947Y332326D03*
X1605966Y343794D03*
X1602138Y351047D03*
X1596253Y375633D03*
X1596534Y379760D03*
X1599527Y396718D03*
X1596760Y530000D03*
X1596260Y540500D03*
X1611316Y685800D03*
X1611027Y722427D03*
X1611327Y735973D03*
X1611627Y780327D03*
X1609500Y776100D03*
X1611873Y795127D03*
X1606190Y803774D03*
X1606709Y819165D03*
X1600333Y1440504D03*
X1596836Y1446488D03*
X1600333Y1449068D03*
X1601968Y1453442D03*
X1597457Y1460662D03*
X1605430Y1468023D03*
X1597039Y1475100D03*
X1599726Y1474990D03*
X1600008Y1488492D03*
X1601500Y1514500D03*
X1608500Y1506000D03*
Y1515000D03*
X1613790Y1531334D03*
X1609348Y1527334D03*
X1613790Y1523334D03*
X1604000Y1519000D03*
X1600732Y1539334D03*
X1609348Y1535334D03*
X1598574Y1543373D03*
X1622222Y90650D03*
X1627534Y90615D03*
X1621972Y95236D03*
X1626147Y351033D03*
X1628636Y422088D03*
X1623955Y442956D03*
X1625772Y438323D03*
X1621596Y456386D03*
X1625938Y445873D03*
X1620385Y465874D03*
X1627965Y474424D03*
Y488597D03*
Y477824D03*
Y491997D03*
Y521958D03*
Y518558D03*
Y536131D03*
Y532731D03*
X1616622Y546712D03*
Y542712D03*
X1627965Y571997D03*
Y568597D03*
Y582771D03*
Y586171D03*
Y596944D03*
Y600344D03*
Y614517D03*
Y611117D03*
X1618538Y618288D03*
X1614538D03*
X1627224Y643252D03*
X1613362Y656321D03*
X1621362D03*
X1617362D03*
X1616260Y678462D03*
X1619950Y678519D03*
X1615913Y692245D03*
X1628200Y711417D03*
X1612800Y705900D03*
X1620600D03*
X1620500Y723200D03*
X1628343Y747288D03*
X1616683Y744517D03*
X1620100Y738300D03*
X1624000Y760900D03*
X1612573Y761427D03*
X1628027Y801427D03*
X1613117Y828117D03*
X1640769Y85539D03*
Y82939D03*
Y75139D03*
Y80339D03*
Y77739D03*
X1640813Y92874D03*
X1631905Y95236D03*
X1631855Y99961D03*
X1642840Y104249D03*
Y107649D03*
X1639862Y162368D03*
X1642462D03*
X1641173Y213213D03*
Y210713D03*
Y208213D03*
X1630717Y210478D03*
Y215478D03*
Y212978D03*
Y207978D03*
X1641173Y215713D03*
X1634046Y264180D03*
X1636546D03*
X1633971Y258880D03*
X1642940Y267526D03*
Y270026D03*
X1629553Y329067D03*
X1629302Y334402D03*
X1640030Y335550D03*
X1636561Y343072D03*
X1629514Y331727D03*
X1630691Y347432D03*
X1640197Y374690D03*
X1638340Y379536D03*
X1641615Y379600D03*
X1635170Y442856D03*
X1632439Y452265D03*
X1633225Y458455D03*
X1636271Y453881D03*
X1635185Y446595D03*
X1635265Y470737D03*
Y467337D03*
Y484910D03*
Y481510D03*
Y514871D03*
Y511471D03*
Y529044D03*
Y525644D03*
Y564910D03*
Y561510D03*
Y575684D03*
Y579084D03*
Y593257D03*
Y604030D03*
Y589857D03*
Y607430D03*
X1635283Y728117D03*
X1630327Y774627D03*
X1629927Y787327D03*
X1644552Y871353D03*
X1635176Y886761D03*
X1644718Y909263D03*
X1635000Y919263D03*
X1644325Y942120D03*
X1637771Y952120D03*
X1640581Y1551907D03*
X1649094Y98551D03*
X1659648Y97475D03*
X1651989Y114623D03*
Y111223D03*
X1652644Y103783D03*
X1659579Y106186D03*
X1651989Y125396D03*
Y128796D03*
X1647406Y147540D03*
X1651178Y141247D03*
X1658645Y143740D03*
X1656025Y148277D03*
X1649562Y162793D03*
Y165393D03*
Y167993D03*
Y170493D03*
X1656486Y177616D03*
X1654565Y181009D03*
X1648559Y181426D03*
X1651770Y181366D03*
X1659740Y168697D03*
X1657067Y172190D03*
X1660828Y191941D03*
X1651384Y184012D03*
X1648767Y184221D03*
X1647745Y211695D03*
X1645245Y208695D03*
X1648045D03*
X1656506Y213132D03*
X1652803Y211359D03*
Y213859D03*
X1645245Y211695D03*
X1656506Y215632D03*
X1656750Y256303D03*
X1656509Y265896D03*
X1661525Y266114D03*
X1651422Y265701D03*
X1648240Y267526D03*
X1645740D03*
Y270026D03*
X1648240D03*
X1653057Y281716D03*
X1658998Y281982D03*
X1658200Y315039D03*
X1654771Y352088D03*
X1645685Y381500D03*
X1648835Y390500D03*
X1650044Y435158D03*
X1649789Y440489D03*
X1646209Y442606D03*
X1650087Y444841D03*
X1649773Y449961D03*
X1653490Y458572D03*
X1645826Y446606D03*
X1647133Y463479D03*
X1647604Y467367D03*
X1656112Y768669D03*
X1657042Y773604D03*
X1647402Y881460D03*
X1648375Y886766D03*
X1650205Y925911D03*
X1647763Y919268D03*
X1648387Y945554D03*
X1647470Y952125D03*
X1651443Y981515D03*
X1647565Y981432D03*
X1652944Y993796D03*
X1653414Y990590D03*
X1676870Y55513D03*
X1673095Y68581D03*
X1679470Y60513D03*
X1673108Y80581D03*
X1665190Y76587D03*
Y72615D03*
X1679598Y85731D03*
X1677238Y88801D03*
X1675291Y103621D03*
X1666629Y100625D03*
X1671002Y112083D03*
X1662391Y118335D03*
Y121735D03*
Y132509D03*
Y135909D03*
X1667208Y141247D03*
X1671695Y143518D03*
X1670795Y152373D03*
X1673945Y152562D03*
X1674637Y183834D03*
X1669352Y171523D03*
X1674810Y172665D03*
X1674747Y178560D03*
X1675623Y186629D03*
X1674157Y190185D03*
X1668882Y192490D03*
X1667318Y198828D03*
X1674927Y200864D03*
X1664840Y192300D03*
X1662837Y206767D03*
X1667837D03*
X1665337D03*
X1674950Y207037D03*
X1675016Y212455D03*
X1667967Y221708D03*
X1665467D03*
X1664082Y231021D03*
Y228221D03*
X1672317Y221642D03*
X1662967Y221708D03*
X1662382Y224421D03*
X1669633Y236189D03*
X1667133D03*
X1664633D03*
X1667074Y248765D03*
X1664574D03*
X1669574D03*
X1676231Y265897D03*
X1673731D03*
X1670071Y268195D03*
Y270695D03*
X1667271Y268195D03*
X1664771D03*
Y270695D03*
X1667271D03*
X1673203Y328867D03*
X1668979Y339559D03*
X1666860Y353661D03*
X1663650Y353283D03*
X1673723Y353881D03*
X1670323Y353534D03*
X1670260Y377912D03*
X1669260Y391496D03*
X1663618Y393858D03*
X1663780Y384410D03*
X1666959Y382047D03*
X1670260Y386500D03*
X1669260Y409000D03*
X1665260Y398583D03*
X1670348Y397912D03*
X1667260Y403500D03*
X1663713Y440869D03*
Y438269D03*
X1666513Y433069D03*
Y430469D03*
Y435669D03*
Y440869D03*
Y438269D03*
X1663713Y433069D03*
Y430469D03*
Y435669D03*
X1664567Y451677D03*
X1667067D03*
X1664567Y454177D03*
X1667067D03*
X1666271Y460218D03*
Y463618D03*
X1682330Y60438D03*
X1688011Y86012D03*
Y94374D03*
X1683152Y86046D03*
X1680155Y94351D03*
X1684104Y94279D03*
X1683348Y116594D03*
X1694291Y110784D03*
X1689291D03*
X1683348Y119594D03*
X1683782Y124283D03*
X1693870Y124663D03*
X1688848Y124879D03*
X1695214Y138838D03*
X1682189Y161306D03*
X1679440Y157370D03*
X1683524Y168665D03*
Y176665D03*
Y192665D03*
X1683637Y186778D03*
X1683556Y204864D03*
Y208864D03*
X1688605Y218085D03*
X1691405D03*
X1679197Y219379D03*
X1679825Y228631D03*
X1693932Y249108D03*
X1685313Y248371D03*
X1686339Y314890D03*
X1686115Y311740D03*
X1683523Y324518D03*
X1677810Y324466D03*
X1686408Y332584D03*
X1687424Y347937D03*
X1692676Y348015D03*
X1688593Y353470D03*
X1691182Y357016D03*
X1680518Y377912D03*
Y381912D03*
Y397912D03*
X1692253Y467306D03*
Y470706D03*
Y484879D03*
Y481479D03*
Y511439D03*
Y514839D03*
Y529013D03*
Y525613D03*
X1689920Y539315D03*
X1689236Y550137D03*
X1692028D03*
X1692253Y561479D03*
Y564879D03*
Y575652D03*
Y579052D03*
Y593225D03*
Y603999D03*
Y589825D03*
Y607399D03*
X1693000Y626912D03*
X1692379Y622912D03*
X1704934Y97667D03*
X1709184Y95111D03*
X1695317Y116594D03*
X1700590Y102495D03*
X1695317Y119594D03*
X1706734Y118342D03*
Y132515D03*
Y121742D03*
X1698851Y125107D03*
X1706734Y135915D03*
X1700324Y142862D03*
X1707465Y143762D03*
X1701365Y148717D03*
X1708913Y195176D03*
X1710931Y199248D03*
X1706413Y195176D03*
X1703913D03*
X1707931Y199248D03*
Y201748D03*
X1706494Y210509D03*
X1703994D03*
X1705767Y206806D03*
X1708267D03*
X1697984Y226320D03*
X1695205Y216385D03*
X1697918Y216970D03*
Y219470D03*
Y221970D03*
X1705686Y230556D03*
X1709941Y228747D03*
X1700945Y228646D03*
X1704671Y242078D03*
X1699902Y232971D03*
X1696552Y244571D03*
X1703895Y256394D03*
X1700223Y292141D03*
X1703609Y287320D03*
X1698292Y303962D03*
X1702655Y474418D03*
Y477818D03*
Y488591D03*
Y491991D03*
Y521952D03*
Y518552D03*
Y536125D03*
Y532725D03*
X1698716Y550065D03*
X1702655Y571991D03*
Y568591D03*
Y586165D03*
Y582765D03*
Y600338D03*
Y596938D03*
Y611111D03*
Y614511D03*
X1708015Y1142700D03*
X1711333Y1146609D03*
X1706450Y1173065D03*
X1703400Y1174400D03*
X1713394Y103411D03*
X1713788Y97667D03*
X1724584Y90650D03*
X1724334Y95236D03*
X1714034Y111255D03*
Y114655D03*
X1713553Y106561D03*
X1714034Y125428D03*
Y128828D03*
X1711413Y195176D03*
X1710931Y202048D03*
X1714531Y230117D03*
X1710547Y238714D03*
X1710028Y246874D03*
X1712248Y244297D03*
X1716755Y326179D03*
X1712226Y344028D03*
X1715930Y340969D03*
X1715590Y331719D03*
X1721746Y377173D03*
X1715228Y387966D03*
X1718851Y391533D03*
X1720571Y385644D03*
X1725746Y385123D03*
X1718318Y399918D03*
X1725154Y406060D03*
X1725415Y416289D03*
Y418889D03*
Y421489D03*
X1721423Y412106D03*
X1716310Y454334D03*
X1724627Y459330D03*
X1724580Y454214D03*
X1724923Y449045D03*
X1724930Y473571D03*
Y476071D03*
Y478571D03*
Y481071D03*
X1710174Y553101D03*
X1717626Y1134729D03*
X1710511Y1138130D03*
X1721008Y1134729D03*
X1723805Y1142666D03*
X1725008Y1134636D03*
X1725680Y1157544D03*
X1724191Y1167768D03*
X1713239Y1176038D03*
X1712526Y1171950D03*
X1728343Y1185205D03*
X1719692Y1187215D03*
X1719385Y1180175D03*
X1712715Y1188500D03*
X1721662Y1201043D03*
X1725658D03*
X1718625Y1199814D03*
X1712542Y1196600D03*
X1720536Y1217228D03*
X1723200Y1219895D03*
X1710825Y1231688D03*
X1712966Y1229841D03*
X1736405Y-69278D03*
Y-72678D03*
X1743175Y92874D03*
X1729896Y90615D03*
X1734267Y95236D03*
X1734217Y99961D03*
X1742224Y162368D03*
X1733079Y207978D03*
Y210478D03*
Y215478D03*
Y212978D03*
X1736408Y264180D03*
X1738908D03*
X1736333Y258880D03*
X1744524Y379429D03*
X1741746Y377173D03*
X1737786D03*
X1729751D03*
X1733746Y385123D03*
X1730746D03*
X1737746D03*
X1741420Y391569D03*
X1739847Y401066D03*
X1729508Y403300D03*
X1728915Y405889D03*
Y408489D03*
Y413689D03*
Y411089D03*
Y416289D03*
Y421489D03*
Y418889D03*
Y424089D03*
X1729302Y432718D03*
Y435518D03*
X1739179Y439318D03*
X1728915Y426689D03*
X1739179Y442118D03*
X1733014Y450091D03*
X1730014D03*
X1727404Y447209D03*
X1730404D03*
X1738824Y456034D03*
Y461034D03*
X1733014Y462060D03*
X1730014D03*
X1734952Y479217D03*
X1737646Y477213D03*
Y479713D03*
X1729002Y477053D03*
X1731502D03*
X1734952Y476717D03*
X1741800Y917900D03*
X1742029Y1116251D03*
X1739508Y1137129D03*
X1729008Y1134729D03*
X1732881D03*
X1739917Y1150087D03*
X1732137Y1157404D03*
X1737393Y1170767D03*
X1729210Y1167768D03*
X1728333Y1178240D03*
X1733052Y1187310D03*
X1737689Y1185238D03*
X1737482Y1180235D03*
X1733662Y1201039D03*
X1729628Y1201043D03*
X1737662Y1200969D03*
X1737781Y1208993D03*
X1726475Y1223170D03*
X1731533Y1228226D03*
X1729322Y1226016D03*
X1743131Y85539D03*
Y82939D03*
Y75139D03*
Y80339D03*
Y77739D03*
X1751456Y98551D03*
X1754351Y111223D03*
Y114623D03*
X1755006Y103783D03*
X1745202Y104249D03*
Y107649D03*
X1754351Y128796D03*
Y125396D03*
X1744824Y162368D03*
X1751924Y162793D03*
Y165393D03*
Y167993D03*
Y170493D03*
X1758848Y177616D03*
X1759429Y172190D03*
X1756927Y181009D03*
X1750921Y181426D03*
X1754132Y181366D03*
X1751129Y184221D03*
X1753746Y184012D03*
X1747607Y211695D03*
X1755165Y211359D03*
Y213859D03*
X1750107Y211695D03*
X1747607Y208695D03*
X1750407D03*
X1743535Y208213D03*
Y213213D03*
Y210713D03*
Y215713D03*
X1753784Y265701D03*
X1758871Y265896D03*
X1750602Y267526D03*
X1745302D03*
X1748102D03*
X1745302Y270026D03*
X1748102D03*
X1750602D03*
X1755419Y281716D03*
X1748497Y371060D03*
X1752497Y371076D03*
X1750135Y379088D03*
X1755433Y379028D03*
X1744180Y383966D03*
X1750187Y409539D03*
X1753187D03*
X1750187Y406739D03*
X1753187Y407039D03*
X1752851Y401981D03*
X1755351D03*
X1757124Y398278D03*
X1754624D03*
X1749470Y424067D03*
X1751970D03*
X1756970D03*
X1754470D03*
X1749705Y413611D03*
X1752205D03*
X1757205D03*
X1754705D03*
X1756844Y438293D03*
X1747179Y439318D03*
X1756844Y441093D03*
X1747179Y442118D03*
X1756844Y443893D03*
X1747306Y470001D03*
X1744806D03*
X1756894Y472020D03*
X1756553Y466409D03*
X1756954Y477318D03*
X1745231Y489036D03*
X1743092Y485580D03*
X1745592D03*
X1748092D03*
X1758401Y484882D03*
X1756391Y487382D03*
X1747467Y492836D03*
Y495636D03*
X1756089Y542952D03*
X1750879Y541940D03*
X1754906Y824333D03*
Y820737D03*
X1746897Y879199D03*
X1746884Y884649D03*
X1747900Y900160D03*
X1744900D03*
X1750915Y902055D03*
X1749267Y918413D03*
X1751200Y931100D03*
X1746600Y935100D03*
X1751854Y991297D03*
X1749314Y987904D03*
X1745824Y987058D03*
X1748677Y993986D03*
X1753860Y997271D03*
X1759569Y1021944D03*
X1744529Y1116251D03*
X1758390Y1577905D03*
X1759947Y1599029D03*
X1750685Y1621654D03*
X1767552Y76587D03*
Y72615D03*
X1762010Y97475D03*
X1768991Y100625D03*
X1761941Y106186D03*
X1773364Y112083D03*
X1764753Y121735D03*
Y118335D03*
Y132509D03*
Y135909D03*
X1771714Y171523D03*
X1776999Y183834D03*
X1762102Y168697D03*
X1763190Y191941D03*
X1771244Y192490D03*
X1776519Y190185D03*
X1767202Y192300D03*
X1765199Y206767D03*
X1770199D03*
X1767699D03*
X1758868Y213132D03*
X1765329Y221708D03*
X1770329D03*
X1767829D03*
X1764744Y224421D03*
X1766444Y231021D03*
Y228221D03*
X1774679Y221642D03*
X1758868Y215632D03*
X1771995Y236189D03*
X1769495D03*
X1766995D03*
X1771936Y248765D03*
X1769436D03*
X1766936D03*
X1759112Y256303D03*
X1763887Y266114D03*
X1767133Y270695D03*
X1769633D03*
X1772433Y268195D03*
Y270695D03*
X1769633Y268195D03*
X1767133D03*
X1761360Y281982D03*
X1762997Y377581D03*
X1765497Y379591D03*
X1772513Y387702D03*
X1769713D03*
X1765913Y389402D03*
X1763200Y388817D03*
Y383817D03*
Y386317D03*
X1766837Y438293D03*
Y441093D03*
Y443893D03*
X1768586Y467560D03*
X1764903Y470382D03*
X1764906Y474382D03*
X1776561Y467560D03*
X1777061Y475560D03*
X1768575D03*
X1770135Y490711D03*
X1758957Y543036D03*
X1773789Y927663D03*
X1765664Y923724D03*
X1769064D03*
X1773789Y930663D03*
X1774476Y995049D03*
X1773810Y990821D03*
X1762486Y990260D03*
X1760201Y992475D03*
X1758881Y995633D03*
X1769004Y1019395D03*
X1768844Y1023694D03*
Y1027248D03*
X1771773Y1028829D03*
X1772188Y1428369D03*
X1766313Y1580198D03*
X1761072Y1590719D03*
X1765040Y1599511D03*
X1760422Y1640303D03*
X1768422D03*
X1772422D03*
X1762041Y1631511D03*
X1768422Y1632245D03*
X1773820Y1631238D03*
X1779232Y55513D03*
X1775457Y68581D03*
X1785246Y60660D03*
X1781832Y60513D03*
X1775470Y80581D03*
X1781960Y85731D03*
X1790712Y81713D03*
X1790664Y71908D03*
X1779600Y88801D03*
X1790373Y94663D03*
X1786466Y85923D03*
Y94279D03*
X1782517Y94351D03*
X1777653Y103621D03*
X1785886Y168665D03*
Y176665D03*
X1777172Y172665D03*
X1777109Y178560D03*
X1777985Y186629D03*
X1785779Y192665D03*
X1785886Y196665D03*
X1777289Y200864D03*
X1785999Y186778D03*
X1785918Y204864D03*
X1777378Y212455D03*
X1777312Y207037D03*
X1785918Y208864D03*
X1781559Y219379D03*
X1782187Y228631D03*
X1778593Y265897D03*
X1776093D03*
X1787674Y303130D03*
X1777681Y387151D03*
Y382151D03*
Y384651D03*
X1786184Y435321D03*
Y438121D03*
X1783384Y435321D03*
Y438121D03*
X1786184Y440921D03*
X1783384D03*
X1786184Y443721D03*
X1783384D03*
X1786170Y448931D03*
X1792527Y452799D03*
X1786693Y459170D03*
X1790061Y474513D03*
X1779404Y826570D03*
X1791041Y818795D03*
X1780016Y874400D03*
X1775904Y924546D03*
X1778047Y916120D03*
X1789537Y930498D03*
X1780158Y953295D03*
X1785758Y956095D03*
Y953295D03*
X1782958D03*
Y956095D03*
X1780158D03*
X1789363Y969160D03*
X1782563Y979660D03*
X1785663D03*
X1779363D03*
X1786863Y985060D03*
X1779143Y995203D03*
X1779033Y1023432D03*
X1786740Y1019237D03*
X1780802Y1019474D03*
X1774863Y1019237D03*
X1774844Y1023694D03*
X1783844D03*
X1786844Y1027248D03*
X1780844D03*
X1774844D03*
X1789844Y1023694D03*
X1775998Y1074707D03*
Y1072207D03*
X1781198Y1074707D03*
X1778598D03*
X1783798D03*
Y1072207D03*
X1778598D03*
X1781198D03*
X1790736Y1072090D03*
Y1074590D03*
X1780326Y1089851D03*
X1777726D03*
X1782926D03*
Y1092351D03*
X1777726D03*
X1780326D03*
X1775126Y1089851D03*
Y1092351D03*
X1790639Y1082585D03*
X1790572Y1085152D03*
X1780662Y1108413D03*
X1783262D03*
X1778062D03*
X1775462D03*
X1785321Y1121122D03*
X1787921D03*
X1790521D03*
X1780566Y1111038D03*
X1783166D03*
X1777966D03*
X1775366D03*
X1790521Y1130822D03*
X1781874Y1139822D03*
X1787921Y1130822D03*
X1785321D03*
X1784374Y1139822D03*
X1781802Y1147822D03*
X1784302D03*
X1783278Y1208140D03*
X1778227Y1438099D03*
X1786091Y1443715D03*
X1787745Y1437765D03*
X1783178Y1437550D03*
X1778104Y1470289D03*
X1801761Y-33888D03*
Y-30488D03*
X1791088Y77296D03*
X1804758Y294429D03*
X1793524Y303343D03*
X1805196Y300952D03*
X1799897Y408104D03*
X1802697D03*
X1805497D03*
X1793475Y424939D03*
X1799614Y420375D03*
X1802414D03*
X1805214D03*
X1793475Y427439D03*
X1809095Y435101D03*
X1803700Y440101D03*
X1803530Y431112D03*
X1809358Y442114D03*
X1803335Y452718D03*
X1809346Y452601D03*
X1797907Y452987D03*
X1809338Y447121D03*
X1804933Y461607D03*
X1796933D03*
X1796136Y471334D03*
X1800933Y461607D03*
X1802000Y892447D03*
X1797365Y930761D03*
X1793474Y930374D03*
X1805463Y969260D03*
X1801963Y969160D03*
X1802363Y989660D03*
X1803351Y1027471D03*
X1805188Y1019078D03*
X1799646Y1018999D03*
X1793470Y1018762D03*
X1801844Y1023694D03*
X1795844D03*
X1798844Y1027248D03*
X1792844D03*
X1795936Y1072090D03*
X1793336D03*
X1798536D03*
Y1074590D03*
X1793336D03*
X1795936D03*
X1801961Y1081717D03*
X1795819Y1088553D03*
X1800813Y1103246D03*
X1806206Y1114589D03*
X1803506D03*
X1800906D03*
X1798306D03*
X1798702Y1124328D03*
X1801302D03*
X1803902D03*
X1806602D03*
X1793221Y1121122D03*
Y1130822D03*
X1804532Y1133356D03*
X1807232D03*
X1807035Y1136912D03*
Y1144912D03*
X1806835Y1214668D03*
X1800489Y1220598D03*
X1807243Y1219955D03*
X1802670Y1210905D03*
X1805126Y1225745D03*
X1799845Y1261044D03*
X1794845D03*
X1797345D03*
X1799845Y1263544D03*
X1797345D03*
X1794845D03*
X1803885Y1435046D03*
X1806428Y1444543D03*
X1795374D03*
X1802813Y1464015D03*
X1803762Y1467236D03*
X1819900Y906900D03*
X1807663Y966660D03*
Y963860D03*
X1808014Y984832D03*
X1812538Y1026859D03*
X1811468Y1021084D03*
X1807844Y1023694D03*
Y1027248D03*
X1810349Y1031264D03*
X1816756Y1089145D03*
Y1094145D03*
X1816235Y1083970D03*
X1810346Y1082250D03*
X1816756Y1097145D03*
Y1101145D03*
X1810310Y1104819D03*
X1809535Y1136912D03*
Y1144912D03*
X1812130Y1205349D03*
X1822594Y1211054D03*
Y1215324D03*
X1814741Y1217093D03*
X1811482Y1226423D03*
X1810018Y1295944D03*
X1812818D03*
X1815618Y1298744D03*
Y1295944D03*
X1812818Y1298744D03*
X1810018D03*
X1812202Y1432624D03*
X1809342Y1476733D03*
X1824706Y1085145D03*
X1824949Y1077145D03*
X1824706Y1100185D03*
Y1106145D03*
X1828272Y1095968D03*
X1824706Y1093150D03*
X1830915Y1109146D03*
X1834665Y1213239D03*
G54D22*
X51750Y617861D03*
X48207D03*
X44664D03*
X51750Y620661D03*
X48207D03*
X44664D03*
X55294Y617861D03*
Y620661D03*
X146948Y1088287D03*
X143208D03*
X146948Y1099507D03*
X143208D03*
X146948Y1106988D03*
X143208D03*
X146948Y1114468D03*
Y1121948D03*
X143208Y1114468D03*
Y1121948D03*
X146948Y1129429D03*
X143208D03*
X146948Y1136909D03*
X143208D03*
X146948Y1148129D03*
X143208D03*
X146947Y1170570D03*
X143207D03*
X146947Y1178051D03*
X143207D03*
X165649Y1073326D03*
X158169D03*
X150689D03*
X165649Y1092027D03*
X158169D03*
X150689D03*
X165649Y1077066D03*
X161909Y1084547D03*
X158169Y1077066D03*
X154429Y1084547D03*
X161909Y1080807D03*
X154429D03*
X165649Y1095767D03*
X161909Y1103247D03*
X158169Y1095767D03*
X154429Y1103247D03*
X150689Y1095767D03*
X161909Y1099507D03*
X154429D03*
X161909Y1118208D03*
Y1121948D03*
X165649Y1110728D03*
X161909D03*
X154429D03*
Y1118208D03*
X150689Y1110728D03*
Y1118208D03*
X154429Y1125688D03*
X150689D03*
Y1133169D03*
X165649D03*
X161909D03*
X154429D03*
X165649Y1148129D03*
Y1144389D03*
Y1155610D03*
X160039Y1176180D03*
X156299D03*
X169389Y1084547D03*
Y1080807D03*
Y1103247D03*
X173129Y1136909D03*
X169389D03*
X176870Y1151870D03*
Y1148129D03*
Y1144389D03*
X169389Y1151870D03*
Y1148129D03*
X176870Y1166830D03*
Y1159350D03*
X169389D03*
X176870Y1174310D03*
Y1178051D03*
Y1181791D03*
X188090Y1114468D03*
X184350D03*
X191830D03*
X195570D03*
X191830Y1140649D03*
Y1136909D03*
X195570Y1140649D03*
X184350Y1136909D03*
X191830Y1133169D03*
Y1129429D03*
Y1144389D03*
Y1151869D03*
X195570Y1148129D03*
Y1155610D03*
X184350Y1144389D03*
X188090Y1155610D03*
X184350Y1151870D03*
X188090Y1148129D03*
X191830Y1159350D03*
Y1170570D03*
X195570Y1166830D03*
X184350Y1159350D03*
Y1170570D03*
X188090Y1166830D03*
X191830Y1185531D03*
Y1178051D03*
X195570Y1181791D03*
Y1174310D03*
X184350Y1185531D03*
X188090Y1181791D03*
Y1174310D03*
X184350Y1178051D03*
X191830Y1193011D03*
X195570Y1215452D03*
X197440Y1217322D03*
X186220D03*
X189960D03*
Y1213582D03*
X203051Y1114468D03*
X199311D03*
X206791D03*
X210531D03*
X206791Y1136909D03*
X203051D03*
X199311D03*
X214271D03*
X210531D03*
X199311Y1129429D03*
X206791D03*
X214271D03*
X210531D03*
X203051D03*
X210531Y1155610D03*
X203051D03*
X206791Y1144389D03*
X203051D03*
X199311D03*
X214271D03*
X210531D03*
X214271Y1151870D03*
X210531D03*
X206791D03*
X203051D03*
X199311D03*
X214271Y1170570D03*
X210531Y1166830D03*
X214271Y1159350D03*
X206791Y1170570D03*
X203051Y1166830D03*
X199311Y1170570D03*
X206791Y1159350D03*
X199311D03*
X203051Y1174310D03*
X210531D03*
X203051Y1185531D03*
X199311D03*
X206791D03*
X214271D03*
X210531D03*
X206791Y1178051D03*
X203051D03*
X199311D03*
X214271D03*
X210531D03*
X214271Y1193011D03*
X210531D03*
X199311D03*
X203051D03*
X206791D03*
X214271Y1200491D03*
X210531D03*
X199311D03*
X206791D03*
X203051D03*
X201181Y1213582D03*
X214271Y1211712D03*
X208661Y1213582D03*
X203051Y1215452D03*
X214271D03*
X201181Y1217322D03*
X208661D03*
X210531Y1215452D03*
X204921Y1213582D03*
X225492Y1114468D03*
X221752D03*
X218011D03*
X225492Y1136909D03*
X221751D03*
X218011D03*
X229232D03*
Y1129429D03*
X218011D03*
X221751D03*
X225492D03*
X218011Y1155610D03*
X225492D03*
Y1144389D03*
X221751D03*
X218011D03*
X229232D03*
Y1151870D03*
X221752D03*
X218011D03*
X225492D03*
Y1166830D03*
X221751Y1170570D03*
X218011Y1166830D03*
X221751Y1159350D03*
X229232Y1170570D03*
Y1159350D03*
X225492Y1174310D03*
X218011D03*
X225492Y1185531D03*
X218011D03*
X221751D03*
X229232D03*
X225492Y1178051D03*
X221751D03*
X218011D03*
X229232D03*
X218011Y1193011D03*
X221751D03*
X225492D03*
X229232D03*
X218011Y1200491D03*
X221751D03*
X225492D03*
X229232D03*
X218011Y1215452D03*
X229232Y1211712D03*
Y1215452D03*
X225492Y1211712D03*
X221752D03*
Y1215452D03*
X240452Y1114468D03*
X244192D03*
X236712Y1118208D03*
X244192D03*
X236712Y1114468D03*
X240452Y1118208D03*
Y1136909D03*
X236712D03*
X244192D03*
Y1129429D03*
X240452D03*
X236712D03*
Y1155610D03*
X244192D03*
X240452Y1151869D03*
X236712D03*
X244192D03*
X240452Y1144389D03*
X236712D03*
X244192D03*
X236712Y1166830D03*
X240452Y1170570D03*
Y1159350D03*
X244192Y1166830D03*
X236712Y1174310D03*
X244192D03*
X240452Y1185531D03*
X236712D03*
X244192D03*
X240452Y1178051D03*
X236712D03*
X244192D03*
X240452Y1193011D03*
X236712D03*
X244192D03*
X236712Y1200491D03*
X244192D03*
X240452D03*
X244192Y1215452D03*
X240452D03*
X242322Y1217322D03*
X236712Y1211712D03*
Y1215452D03*
X238582Y1217322D03*
X262893Y1118208D03*
X259153Y1114468D03*
X262893D03*
X255413Y1118208D03*
Y1114468D03*
X247933D03*
X259153Y1118208D03*
X251673Y1114468D03*
X247933Y1118208D03*
X251673D03*
X255413Y1136909D03*
X251673D03*
X247933D03*
X259153D03*
X262893D03*
X247933Y1129429D03*
X259153D03*
X262893D03*
X255413D03*
X251673D03*
Y1155610D03*
X259153D03*
X251673Y1144389D03*
X247933D03*
X255413D03*
X259153Y1151869D03*
X262893D03*
X247933D03*
X255413D03*
X251673D03*
X262893Y1144389D03*
X259153D03*
X251673Y1166830D03*
X255413Y1170570D03*
X247933D03*
X255413Y1159350D03*
X247933D03*
X259153Y1166830D03*
X262893Y1170570D03*
Y1159350D03*
X251673Y1174310D03*
X259153D03*
X247933Y1185531D03*
X255413D03*
X251673D03*
X259153D03*
X262893D03*
X251673Y1178051D03*
X247933D03*
X255413D03*
X259153D03*
X262893D03*
X251673Y1193011D03*
X255413D03*
X247933D03*
X262893D03*
X259153D03*
Y1200491D03*
X262893D03*
X251673D03*
X247933D03*
X255413D03*
Y1215452D03*
X262893D03*
X247932Y1215451D03*
X259153Y1215452D03*
X251673D03*
X247932Y1211711D03*
X251673D03*
X270373Y1114468D03*
X274114D03*
X277854D03*
X266633Y1136909D03*
Y1129429D03*
X274114D03*
Y1140649D03*
Y1136909D03*
X266633Y1155610D03*
X277854D03*
X266633Y1151869D03*
Y1144389D03*
X274114D03*
X277854Y1159350D03*
Y1166830D03*
Y1170570D03*
X266633D03*
X270373D03*
X266633Y1159350D03*
X270373D03*
Y1166830D03*
X266633D03*
Y1174310D03*
X277854D03*
X266633Y1185531D03*
Y1178051D03*
X270373Y1181791D03*
X274114Y1185531D03*
Y1189271D03*
Y1178051D03*
X266633Y1193011D03*
Y1200491D03*
X274114D03*
Y1193011D03*
X277854Y1204232D03*
Y1196751D03*
Y1200491D03*
X274114Y1215452D03*
X277854D03*
X266633D03*
X274114Y1211712D03*
X277854Y1207972D03*
X285334Y1118208D03*
X281594D03*
X285334Y1114468D03*
X281594D03*
X289074Y1140649D03*
X285334D03*
Y1136909D03*
X292815Y1140649D03*
X285334Y1155610D03*
X281594Y1144389D03*
X285334Y1148129D03*
Y1144389D03*
X289074Y1148129D03*
X292815D03*
Y1155610D03*
X285334Y1170570D03*
Y1166830D03*
Y1159350D03*
X292815Y1170570D03*
X285334Y1174310D03*
X289074Y1189271D03*
X285334D03*
X281594Y1181791D03*
X285334Y1178051D03*
X289074Y1181791D03*
X285334Y1196751D03*
Y1204232D03*
X281594Y1200491D03*
X285334D03*
Y1207972D03*
Y1215452D03*
Y1211712D03*
X281594Y1215452D03*
Y1207972D03*
X311515Y1140649D03*
X304035Y1144389D03*
Y1151869D03*
X307775Y1144389D03*
Y1151869D03*
X296555Y1155610D03*
X311515Y1148129D03*
Y1155610D03*
X304035Y1166830D03*
Y1159350D03*
X307775Y1166830D03*
X296555Y1170570D03*
X311515D03*
X304035Y1174310D03*
Y1181791D03*
Y1189271D03*
X307775Y1174310D03*
Y1181791D03*
Y1189271D03*
X311515Y1178051D03*
Y1185531D03*
Y1193011D03*
X322736Y1136909D03*
X326476D03*
X315255Y1140649D03*
X322736Y1144389D03*
Y1151870D03*
X326476Y1144389D03*
X315255Y1148129D03*
X326476Y1151870D03*
X315255Y1155610D03*
X322736Y1159350D03*
X326476D03*
X315255Y1170570D03*
X322736Y1174310D03*
Y1181791D03*
Y1189271D03*
X326476Y1174310D03*
X315255Y1178051D03*
X326476Y1181791D03*
X315255Y1185531D03*
X326476Y1189271D03*
X315255Y1193011D03*
X425023Y441086D03*
Y433999D03*
Y437543D03*
X422223Y441086D03*
Y433999D03*
Y437543D03*
X425023Y444629D03*
X422223D03*
X501750Y620661D03*
X505293D03*
X501750Y617861D03*
X505293D03*
X512380D03*
X508836Y620661D03*
Y617861D03*
X512380Y620661D03*
X600295Y1088287D03*
X604035D03*
X600295Y1099507D03*
X604035D03*
X600295Y1106988D03*
X604035D03*
Y1121948D03*
X600295D03*
Y1114468D03*
X604035D03*
X600295Y1136909D03*
X604035D03*
X600295Y1129429D03*
X604035D03*
Y1148129D03*
X600295D03*
X604034Y1170570D03*
X600294D03*
X604034Y1178051D03*
X600294D03*
X615256Y1073326D03*
X607776D03*
X618996Y1084547D03*
Y1080807D03*
X615256Y1077066D03*
X611516Y1080807D03*
Y1084547D03*
X607776Y1092027D03*
X615256D03*
X607776Y1095767D03*
X615256D03*
X618996Y1103247D03*
X611516D03*
X618996Y1099507D03*
X611516D03*
X618996Y1118208D03*
Y1121948D03*
X611516Y1118208D03*
X607776D03*
X611516Y1110728D03*
X618996D03*
X607776D03*
X611516Y1125688D03*
X607776D03*
Y1133169D03*
X615256Y1178051D03*
X611516D03*
X622736Y1073326D03*
Y1077066D03*
X626476Y1084547D03*
X622736Y1092027D03*
X626476Y1080807D03*
X622736Y1095767D03*
X626476Y1103247D03*
X622736Y1118208D03*
X626476Y1114468D03*
X622736Y1110728D03*
X630216Y1114468D03*
X633957Y1151870D03*
Y1148129D03*
Y1144389D03*
X626476Y1148129D03*
X622736Y1144389D03*
Y1148129D03*
X626476Y1151870D03*
X622736Y1155610D03*
X633957Y1166830D03*
Y1159350D03*
X626476D03*
X633957Y1174310D03*
Y1178051D03*
Y1181791D03*
X645177Y1114468D03*
X641437D03*
X648917D03*
X652657D03*
X648917Y1140649D03*
Y1136909D03*
X652657Y1140649D03*
X641437Y1136909D03*
X648917Y1129429D03*
Y1133169D03*
X652657Y1148129D03*
Y1155610D03*
X648917Y1144389D03*
Y1151869D03*
X641437Y1144389D03*
Y1151870D03*
X645177Y1155610D03*
Y1148129D03*
X648917Y1159350D03*
Y1170570D03*
X652657Y1166830D03*
X641437Y1170570D03*
X645177Y1166830D03*
X641437Y1159350D03*
X648917Y1185531D03*
Y1178051D03*
X652657Y1181791D03*
Y1174310D03*
X641437Y1185531D03*
Y1178051D03*
X645177Y1181791D03*
Y1174310D03*
X648917Y1193011D03*
X652657Y1215452D03*
Y1219192D03*
X641437Y1215452D03*
X648917D03*
X645177D03*
X660138Y1114468D03*
X656398D03*
X663878D03*
X667618D03*
Y1129429D03*
X660138D03*
X656398D03*
X663878D03*
Y1136909D03*
X660138D03*
X656398D03*
X667618D03*
X660138Y1155610D03*
X667618D03*
Y1144389D03*
X663878D03*
X660138D03*
X656398D03*
X667618Y1151870D03*
X663878D03*
X660138D03*
X656398D03*
X663878Y1170570D03*
X660138Y1166830D03*
X656398Y1170570D03*
X663878Y1159350D03*
X656398D03*
X667618Y1166830D03*
Y1174310D03*
X660138D03*
X667618Y1185531D03*
X660138D03*
X656398D03*
X663878D03*
X667618Y1178051D03*
X663878D03*
X660138D03*
X656398D03*
X667618Y1200491D03*
X656398D03*
X663878D03*
X660138D03*
X663878Y1193011D03*
X660138D03*
X656398D03*
X667618D03*
X663878Y1211712D03*
X656398D03*
X660138Y1215452D03*
X656398D03*
X663878D03*
X667618D03*
X660138Y1211712D03*
X682579Y1114468D03*
X678839D03*
X675098D03*
Y1129429D03*
X671358D03*
X678838D03*
X682579D03*
Y1136909D03*
X678838D03*
X675098D03*
X671358D03*
X682579Y1155610D03*
X675098D03*
X678839Y1151870D03*
X675098D03*
X671358D03*
X682579D03*
Y1144389D03*
X671358D03*
X678838D03*
X675098D03*
X682579Y1166830D03*
X678838Y1170570D03*
X671358D03*
X675098Y1166830D03*
X671358Y1159350D03*
X678838D03*
X682579Y1174310D03*
X675098D03*
X682579Y1185531D03*
X675098D03*
X671358D03*
X678838D03*
X682579Y1178051D03*
X678838D03*
X675098D03*
X671358D03*
X675098Y1200491D03*
X671358D03*
X678838D03*
X682579D03*
Y1193011D03*
X678838D03*
X675098D03*
X671358D03*
X682579Y1211712D03*
X678839D03*
Y1215452D03*
X671358Y1211712D03*
Y1215452D03*
X675098D03*
X693799Y1114468D03*
Y1118208D03*
X701279Y1114468D03*
X697539Y1118208D03*
Y1114468D03*
X701279Y1118208D03*
Y1129429D03*
X697539D03*
X693799D03*
X686319D03*
X697539Y1136909D03*
X693799D03*
X701279D03*
X686319D03*
X701279Y1155610D03*
X693799D03*
X701279Y1151869D03*
X697539D03*
X693799D03*
X701279Y1144389D03*
X697539D03*
X693799D03*
X686319D03*
Y1151870D03*
X693799Y1166830D03*
X697539Y1170570D03*
Y1159350D03*
X701279Y1166830D03*
X686319Y1170570D03*
Y1159350D03*
X701279Y1174310D03*
X693799D03*
X701279Y1185531D03*
X697539D03*
X693799D03*
X701279Y1178051D03*
X697539D03*
X693799D03*
X686319Y1185531D03*
Y1178051D03*
X701279Y1200491D03*
X697539D03*
X693799D03*
X686319D03*
X701279Y1193011D03*
X697539D03*
X693799D03*
X686319D03*
Y1211712D03*
Y1215452D03*
X699409Y1217322D03*
X697539Y1215452D03*
X693799D03*
Y1211712D03*
X701279Y1215452D03*
X695669Y1217322D03*
X708760Y1114468D03*
X716240Y1118208D03*
X705020Y1114468D03*
X712500D03*
X716240D03*
X705020Y1118208D03*
X712500D03*
X708760D03*
X705020Y1129429D03*
X708760D03*
X712500D03*
X716240D03*
Y1136909D03*
X705020D03*
X708760D03*
X712500D03*
X708760Y1155610D03*
X716240D03*
Y1151869D03*
X708760D03*
X712500D03*
X705020D03*
X712500Y1144389D03*
X705020D03*
X708760D03*
X716240D03*
Y1166830D03*
X705020Y1159350D03*
X712500D03*
X705020Y1170570D03*
X712500D03*
X708760Y1166830D03*
X716240Y1174310D03*
X708760D03*
X716240Y1185531D03*
X708760D03*
X712500D03*
X705020D03*
X716240Y1178051D03*
X712500D03*
X705020D03*
X708760D03*
X712500Y1200491D03*
X705020D03*
X708760D03*
X716240D03*
X708760Y1193011D03*
X712500D03*
X705020D03*
X716240D03*
Y1215452D03*
X708760D03*
X712500D03*
X705019Y1215451D03*
Y1211711D03*
X708760D03*
X731201Y1114468D03*
X734941D03*
X727460D03*
X719980Y1118208D03*
Y1114468D03*
Y1129429D03*
X723720D03*
X731201D03*
X719980Y1136909D03*
X723720D03*
X731201D03*
Y1140649D03*
X723720Y1155610D03*
X719980Y1151869D03*
X723720D03*
Y1144389D03*
X719980D03*
X734941Y1155610D03*
X731201Y1144389D03*
X719980Y1159350D03*
X727460D03*
X723720D03*
Y1166830D03*
X727460D03*
X719980Y1170570D03*
X727460D03*
X723720D03*
X734941Y1159350D03*
Y1166830D03*
Y1170570D03*
X723720Y1174310D03*
X727460Y1181791D03*
X719980Y1185531D03*
Y1178051D03*
X723720D03*
Y1185531D03*
X734941Y1174310D03*
X731201Y1189271D03*
Y1185531D03*
Y1178051D03*
X719980Y1200491D03*
X723720D03*
X731201D03*
X719980Y1193011D03*
X723720D03*
X731201D03*
X734941Y1196751D03*
Y1204232D03*
Y1200491D03*
X731201Y1215452D03*
X734941D03*
X723720D03*
X719980D03*
X731201Y1211712D03*
X734941Y1207972D03*
X727461Y1215452D03*
X738681Y1118208D03*
X742421D03*
X738681Y1114468D03*
X742421D03*
Y1140649D03*
Y1136909D03*
X746161Y1140649D03*
X749902D03*
X742421Y1155610D03*
X746161Y1148129D03*
X738681Y1144389D03*
X742421Y1148129D03*
Y1144389D03*
X749902Y1155610D03*
Y1148129D03*
X742421Y1159350D03*
Y1166830D03*
Y1170570D03*
X749902D03*
X742421Y1189271D03*
X746161D03*
X742421Y1174310D03*
X738681Y1181791D03*
X746161D03*
X742421Y1178051D03*
Y1196751D03*
X738681Y1200491D03*
X742421Y1204232D03*
Y1200491D03*
Y1211712D03*
Y1215452D03*
Y1207972D03*
X738681Y1215452D03*
Y1207972D03*
Y1211712D03*
X761122Y1144389D03*
Y1151869D03*
X753642Y1155610D03*
X764862Y1151869D03*
Y1144389D03*
Y1166830D03*
X761122D03*
Y1159350D03*
X753642Y1170570D03*
X764862Y1174310D03*
X761122Y1181791D03*
X764862D03*
X761122Y1174310D03*
X768602Y1140649D03*
X772342D03*
Y1148129D03*
Y1155610D03*
X783563Y1151870D03*
X779823D03*
Y1144389D03*
X783563D03*
X768602Y1155610D03*
Y1148129D03*
X779823Y1159350D03*
X772342Y1170570D03*
X768602D03*
X783563Y1159350D03*
Y1189271D03*
X768602Y1185531D03*
X772342Y1178051D03*
X779823Y1189271D03*
X772342Y1185531D03*
X783563Y1174310D03*
X779823D03*
X783563Y1181791D03*
X768602Y1178051D03*
X779823Y1181791D03*
X768602Y1193011D03*
X772342D03*
X920349Y450340D03*
X917549D03*
X920349Y453884D03*
Y457427D03*
X917549Y453884D03*
Y457427D03*
X920349Y460970D03*
X917549D03*
X962380Y617861D03*
X958837D03*
X962380Y620661D03*
X958837D03*
X969467D03*
X965923Y617861D03*
Y620661D03*
X969467Y617861D03*
X1057381Y1088287D03*
Y1106988D03*
Y1099507D03*
Y1114468D03*
Y1121948D03*
Y1129429D03*
Y1136909D03*
Y1148129D03*
X1057380Y1170570D03*
Y1178051D03*
X1072342Y1073326D03*
X1064862D03*
Y1092027D03*
X1072342Y1077066D03*
X1068602Y1084547D03*
Y1080807D03*
X1061121Y1088287D03*
X1072342Y1092027D03*
X1068602Y1099507D03*
X1072342Y1095767D03*
X1061121Y1106988D03*
X1068602Y1103247D03*
X1064862Y1095767D03*
X1061121Y1099507D03*
Y1114468D03*
X1068602Y1110728D03*
Y1118208D03*
X1064862Y1110728D03*
Y1118208D03*
X1061121Y1121948D03*
X1064862Y1125688D03*
X1068602D03*
X1061121Y1129429D03*
X1064862Y1133169D03*
X1061121Y1136909D03*
Y1148129D03*
X1061120Y1170570D03*
X1072342Y1178051D03*
X1068602D03*
X1061120D03*
X1079822Y1073326D03*
Y1092027D03*
X1083562Y1084547D03*
X1079822Y1077066D03*
X1076082Y1084547D03*
Y1080807D03*
X1083562D03*
X1076082Y1103247D03*
X1079822Y1095767D03*
X1076082Y1099507D03*
X1083562Y1103247D03*
X1079822Y1118208D03*
X1076082Y1121948D03*
Y1118208D03*
X1079822Y1110728D03*
X1083562Y1114468D03*
X1087302D03*
X1076082Y1110728D03*
X1091043Y1151870D03*
Y1148129D03*
Y1144389D03*
X1083562Y1148129D03*
X1079822Y1144389D03*
Y1148129D03*
X1083562Y1151870D03*
X1079822Y1155610D03*
X1091043Y1166830D03*
Y1159350D03*
X1083562D03*
X1091043Y1181791D03*
Y1178051D03*
Y1174310D03*
X1102263Y1114468D03*
X1098523D03*
X1106003D03*
Y1140649D03*
Y1136909D03*
X1098523D03*
X1106003Y1129429D03*
Y1133169D03*
Y1151869D03*
Y1144389D03*
X1098523D03*
Y1151870D03*
X1102263Y1148129D03*
Y1155610D03*
X1106003Y1170570D03*
Y1159350D03*
X1102263Y1166830D03*
X1098523Y1159350D03*
Y1170570D03*
X1106003Y1178051D03*
Y1185531D03*
X1098523D03*
X1102263Y1174310D03*
X1098523Y1178051D03*
X1102263Y1181791D03*
X1106003Y1193011D03*
Y1215452D03*
X1098523D03*
X1102263D03*
X1117224Y1114468D03*
X1113484D03*
X1120964D03*
X1124704D03*
X1109743D03*
X1120964Y1129429D03*
X1113484D03*
X1117224D03*
X1124704D03*
Y1136909D03*
X1113484D03*
X1117224D03*
X1120964D03*
X1109743Y1140649D03*
X1124704Y1144389D03*
X1113484D03*
X1117224D03*
X1120964D03*
X1113484Y1151870D03*
X1117224D03*
X1120964D03*
X1124704D03*
Y1155610D03*
X1109743D03*
Y1148129D03*
X1117224Y1155610D03*
X1113484Y1159350D03*
X1120964D03*
X1109743Y1166830D03*
X1113484Y1170570D03*
X1117224Y1166830D03*
X1120964Y1170570D03*
X1124704Y1166830D03*
X1113484Y1178051D03*
X1117224D03*
X1120964D03*
X1124704D03*
X1120964Y1185531D03*
X1113484D03*
X1117224D03*
X1124704D03*
X1109743Y1174310D03*
Y1181791D03*
X1117224Y1174310D03*
X1124704D03*
X1117224Y1200491D03*
X1120964D03*
X1113484D03*
X1124704D03*
X1120964Y1193011D03*
X1117224D03*
X1113484D03*
X1124704D03*
Y1215452D03*
X1120964D03*
Y1211712D03*
X1117224Y1215452D03*
X1109743D03*
X1113484Y1211712D03*
X1111613Y1217322D03*
X1115354D03*
X1117224Y1211712D03*
X1139665Y1114468D03*
X1135925D03*
X1132184D03*
Y1129429D03*
X1128444D03*
X1135924D03*
X1139665D03*
Y1136909D03*
X1135924D03*
X1132184D03*
X1128444D03*
Y1144389D03*
X1135924D03*
X1132184D03*
X1139665D03*
X1135925Y1151870D03*
X1132184D03*
X1128444D03*
X1139665D03*
Y1155610D03*
X1132184D03*
X1139665Y1166830D03*
X1135924Y1170570D03*
X1128444D03*
X1132184Y1166830D03*
X1128444Y1159350D03*
X1135924D03*
X1139665Y1178051D03*
X1135924D03*
X1132184D03*
X1128444D03*
X1139665Y1185531D03*
X1132184D03*
X1128444D03*
X1135924D03*
X1139665Y1174310D03*
X1132184D03*
Y1200491D03*
X1128444D03*
X1135924D03*
X1139665D03*
X1128444Y1193011D03*
X1132184D03*
X1135924D03*
X1139665D03*
Y1211712D03*
X1135925D03*
Y1215452D03*
X1128444D03*
X1132184D03*
X1128444Y1211712D03*
X1154625Y1118208D03*
X1150885D03*
X1154625Y1114468D03*
X1150885D03*
X1154625Y1129429D03*
X1150885D03*
X1143405D03*
Y1136909D03*
X1154625D03*
X1150885D03*
X1143405Y1144389D03*
X1150885Y1151869D03*
X1154625D03*
Y1144389D03*
X1150885D03*
X1143405Y1151870D03*
X1150885Y1155610D03*
X1143405Y1170570D03*
X1154625Y1159350D03*
X1143405D03*
X1150885Y1166830D03*
X1154625Y1170570D03*
X1143405Y1178051D03*
Y1185531D03*
X1154625D03*
X1150885D03*
X1154625Y1178051D03*
X1150885D03*
Y1174310D03*
X1143405Y1200491D03*
X1154625D03*
X1150885D03*
Y1193011D03*
X1154625D03*
X1143405D03*
Y1211712D03*
Y1215452D03*
X1150885Y1211712D03*
Y1215452D03*
X1154625D03*
X1156495Y1217322D03*
X1152755D03*
X1162106Y1114468D03*
X1169586D03*
X1162106Y1118208D03*
X1173326Y1114468D03*
X1158365Y1118208D03*
X1173326D03*
X1165846Y1114468D03*
X1158365D03*
X1169586Y1118208D03*
X1165846D03*
X1169586Y1129429D03*
X1165846D03*
X1162106D03*
X1158365D03*
X1173326D03*
Y1136909D03*
X1169586D03*
X1165846D03*
X1158365D03*
X1162106D03*
X1173326Y1151869D03*
X1158365D03*
X1162106D03*
X1169586D03*
X1165846D03*
X1173326Y1144389D03*
X1165846D03*
X1158365D03*
X1162106D03*
X1169586D03*
X1173326Y1155610D03*
X1165846D03*
X1158365D03*
X1173326Y1166830D03*
X1165846D03*
X1169586Y1170570D03*
X1158365Y1166830D03*
X1162106Y1170570D03*
X1169586Y1159350D03*
X1162106D03*
X1158365Y1185531D03*
X1162106D03*
X1169586D03*
X1165846D03*
X1173326D03*
X1165846Y1178051D03*
X1158365D03*
X1162106D03*
X1169586D03*
X1173326D03*
X1165846Y1174310D03*
X1158365D03*
X1173326D03*
Y1200491D03*
X1165846D03*
X1162106D03*
X1158365D03*
X1169586D03*
X1165846Y1193011D03*
X1169586D03*
X1158365D03*
X1162106D03*
X1173326D03*
Y1215452D03*
X1165846D03*
X1169586D03*
X1162105Y1215451D03*
X1158365Y1215452D03*
X1162105Y1211711D03*
X1165846D03*
X1188287Y1114468D03*
X1177066D03*
Y1118208D03*
X1184546Y1114468D03*
X1180806Y1129429D03*
X1177066D03*
X1188287D03*
X1180806Y1136909D03*
X1177066D03*
X1188287D03*
Y1140649D03*
X1180806Y1151869D03*
X1177066D03*
Y1144389D03*
X1180806D03*
Y1155610D03*
X1188287Y1144389D03*
X1180806Y1170570D03*
X1184546D03*
X1177066D03*
X1184546Y1166830D03*
X1180806D03*
X1177066Y1159350D03*
X1180806D03*
X1184546D03*
X1177066Y1185531D03*
Y1178051D03*
X1180806Y1185531D03*
Y1178051D03*
Y1174310D03*
X1184546Y1181791D03*
X1188287Y1185531D03*
Y1189271D03*
Y1178051D03*
X1180806Y1200491D03*
X1177066D03*
X1188287D03*
X1177066Y1193011D03*
X1180806D03*
X1188287D03*
Y1215452D03*
X1180806D03*
X1177066D03*
X1188287Y1211712D03*
X1199507Y1118208D03*
X1195767D03*
Y1114468D03*
X1192027D03*
X1199507D03*
Y1140649D03*
Y1136909D03*
X1203247Y1140649D03*
X1199507Y1155610D03*
X1192027D03*
X1203247Y1148129D03*
X1195767Y1144389D03*
X1199507Y1148129D03*
Y1144389D03*
Y1170570D03*
Y1166830D03*
Y1159350D03*
X1192027Y1166830D03*
Y1170570D03*
Y1159350D03*
X1203247Y1189271D03*
X1199507D03*
Y1174310D03*
X1195767Y1181791D03*
X1192027Y1174310D03*
X1199507Y1178051D03*
X1203247Y1181791D03*
X1199507Y1196751D03*
Y1204232D03*
X1195767Y1200491D03*
X1192027Y1196751D03*
Y1200491D03*
Y1204232D03*
X1199507Y1200491D03*
X1192027Y1215452D03*
X1199507Y1211712D03*
Y1215452D03*
Y1207972D03*
X1195767Y1215452D03*
X1192027Y1207972D03*
X1195767D03*
Y1211712D03*
X1206988Y1140649D03*
X1218208Y1144389D03*
Y1151869D03*
X1206988Y1155610D03*
Y1148129D03*
X1210728Y1155610D03*
X1221948Y1151869D03*
Y1144389D03*
X1218208Y1166830D03*
Y1159350D03*
X1221948Y1166830D03*
X1210728Y1170570D03*
X1206988D03*
X1218208Y1189271D03*
Y1174310D03*
X1221948Y1181791D03*
Y1174310D03*
X1218208Y1181791D03*
X1221948Y1189271D03*
X1236909Y1136909D03*
X1225688Y1140649D03*
X1229428D03*
X1236909Y1151870D03*
X1225688Y1148129D03*
X1229428D03*
X1225688Y1155610D03*
X1236909Y1144389D03*
X1229428Y1155610D03*
Y1170570D03*
X1225688D03*
X1236909Y1159350D03*
Y1181791D03*
X1225688Y1185531D03*
X1236909Y1189271D03*
X1229428Y1178051D03*
Y1185531D03*
X1236909Y1174310D03*
X1225688Y1178051D03*
Y1193011D03*
X1229428D03*
X1240649Y1136909D03*
Y1151870D03*
Y1144389D03*
Y1159350D03*
Y1174310D03*
Y1181791D03*
Y1189271D03*
X1339196Y441086D03*
Y433999D03*
Y437543D03*
X1336396Y441086D03*
Y433999D03*
Y437543D03*
X1339196Y444629D03*
X1336396D03*
X1415924Y620661D03*
Y617861D03*
X1423010Y620661D03*
X1419467Y617861D03*
X1423010D03*
X1426554Y620661D03*
Y617861D03*
X1419467Y620661D03*
X1514468Y1088287D03*
Y1099507D03*
Y1106988D03*
Y1121948D03*
Y1114468D03*
Y1129429D03*
Y1136909D03*
Y1148129D03*
Y1155610D03*
X1514467Y1170570D03*
Y1178051D03*
X1521949Y1073326D03*
X1529429D03*
Y1077066D03*
X1525689Y1084547D03*
X1529429Y1092027D03*
X1521949D03*
X1518208Y1088287D03*
X1525689Y1080807D03*
X1518208Y1099507D03*
X1525689D03*
X1529429Y1095767D03*
X1525689Y1103247D03*
X1518208Y1106988D03*
X1521949Y1095767D03*
Y1110728D03*
X1518208Y1114468D03*
X1525689Y1110728D03*
X1518208Y1121948D03*
X1521949Y1118208D03*
X1525689D03*
Y1125688D03*
X1518208Y1129429D03*
X1521949Y1125688D03*
X1518208Y1136909D03*
X1521949Y1133169D03*
X1518208Y1148129D03*
Y1155610D03*
X1518207Y1170570D03*
X1527559Y1176180D03*
X1518207Y1178051D03*
X1536909Y1073326D03*
X1533169Y1080807D03*
Y1084547D03*
X1540649Y1080807D03*
X1536909Y1077066D03*
X1540649Y1084547D03*
X1536909Y1092027D03*
Y1095767D03*
X1533169Y1099507D03*
X1540649Y1103247D03*
X1533169D03*
X1536909Y1118208D03*
X1533169D03*
Y1121948D03*
X1544389Y1114468D03*
X1536909Y1110728D03*
X1533169D03*
X1540649Y1114468D03*
X1536909Y1148129D03*
X1540649Y1151870D03*
Y1148129D03*
X1536909Y1144389D03*
Y1155610D03*
X1540649Y1159350D03*
Y1170570D03*
Y1174310D03*
Y1178050D03*
X1531299Y1176180D03*
X1559350Y1114468D03*
X1555610D03*
X1563090D03*
Y1140649D03*
Y1136909D03*
X1555610D03*
X1563090Y1129429D03*
Y1133169D03*
Y1144389D03*
Y1151869D03*
X1555610Y1144389D03*
X1548130Y1151870D03*
Y1148129D03*
Y1144389D03*
X1559350Y1155610D03*
X1555610Y1151870D03*
X1559350Y1148129D03*
X1563090Y1159350D03*
Y1170570D03*
X1548130Y1166830D03*
Y1159350D03*
X1555610Y1170570D03*
X1559350Y1166830D03*
X1555610Y1159350D03*
X1548130Y1174310D03*
Y1178051D03*
Y1181791D03*
X1563090Y1185531D03*
Y1178051D03*
X1555610Y1185531D03*
X1559350Y1174310D03*
Y1181791D03*
X1555610Y1178051D03*
X1563090Y1193011D03*
X1555610Y1215452D03*
X1563090D03*
X1559350D03*
X1574311Y1114468D03*
X1570571D03*
X1578051D03*
X1566830D03*
X1578051Y1136909D03*
X1574311D03*
X1570571D03*
X1574311Y1129429D03*
X1570571D03*
X1578051D03*
X1566830Y1140649D03*
X1578051Y1144389D03*
X1574311D03*
X1570571D03*
X1578051Y1151870D03*
X1574311D03*
X1570571D03*
X1574311Y1155610D03*
X1566830Y1148129D03*
Y1155610D03*
X1578051Y1170570D03*
X1574311Y1166830D03*
X1570571Y1170570D03*
X1566830Y1166830D03*
X1578051Y1159350D03*
X1570571D03*
X1574311Y1185531D03*
X1570571D03*
X1578051D03*
Y1178051D03*
X1574311D03*
X1570571D03*
X1574311Y1174310D03*
X1566830Y1181791D03*
Y1174310D03*
X1570571Y1193011D03*
X1574311D03*
X1578051D03*
X1570571Y1200491D03*
X1578051D03*
X1574311D03*
X1578051Y1215452D03*
X1566830D03*
X1570571Y1211712D03*
X1566830Y1219192D03*
X1574311Y1215452D03*
X1570571D03*
X1578051Y1211712D03*
X1574311D03*
X1593012Y1114468D03*
X1589271D03*
X1581791D03*
X1593011Y1136909D03*
X1589271D03*
X1585531D03*
X1581791D03*
X1589271Y1129429D03*
X1585531D03*
X1581791D03*
X1593011D03*
X1585531Y1144389D03*
X1581791D03*
X1593011D03*
X1589271D03*
X1593012Y1151870D03*
X1589271D03*
X1585531D03*
X1581791D03*
Y1155610D03*
X1589271D03*
X1593011Y1170570D03*
X1585531D03*
X1589271Y1166830D03*
X1581791D03*
X1585531Y1159350D03*
X1593011D03*
X1589271Y1185531D03*
X1585531D03*
X1581791D03*
X1593011D03*
X1581791Y1178051D03*
X1593011D03*
X1589271D03*
X1585531D03*
X1589271Y1174310D03*
X1581791D03*
X1585531Y1193011D03*
X1589271D03*
X1593011D03*
X1581791D03*
X1589271Y1200491D03*
X1585531D03*
X1581791D03*
X1593011D03*
X1593012Y1211712D03*
Y1215452D03*
X1581791D03*
X1589271D03*
X1585531D03*
Y1211712D03*
X1596752Y1114468D03*
X1607972D03*
X1611712Y1118208D03*
X1607972D03*
X1611712Y1114468D03*
X1600492Y1136909D03*
X1596752D03*
X1611712D03*
X1607972D03*
X1611712Y1129429D03*
X1607972D03*
X1600492D03*
X1596752D03*
X1600492Y1144389D03*
X1596752D03*
X1611712Y1151869D03*
X1607972D03*
X1611712Y1144389D03*
X1607972D03*
X1600492Y1151870D03*
X1596752D03*
Y1155610D03*
X1607972D03*
Y1166830D03*
X1611712Y1170570D03*
X1600492D03*
X1596752Y1166830D03*
X1611712Y1159350D03*
X1600492D03*
Y1185531D03*
X1596752D03*
X1600492Y1178051D03*
X1596752D03*
X1611712Y1185531D03*
X1607972D03*
X1611712Y1178051D03*
X1607972D03*
Y1174310D03*
X1596752D03*
X1607972Y1193011D03*
X1611712D03*
X1600492D03*
X1596752D03*
X1600492Y1200491D03*
X1596752D03*
X1611712D03*
X1607972D03*
X1600492Y1211712D03*
Y1215452D03*
X1596752Y1211712D03*
X1611712Y1215452D03*
X1607972D03*
Y1211712D03*
X1609842Y1217322D03*
X1615452Y1118208D03*
X1619193D03*
X1615452Y1114468D03*
X1619193D03*
X1622933D03*
X1626673D03*
Y1118208D03*
X1622933D03*
X1626673Y1136909D03*
X1622933D03*
X1615452D03*
X1619193D03*
X1626673Y1129429D03*
X1622933D03*
X1619193D03*
X1615452D03*
Y1151869D03*
X1619193D03*
X1626673D03*
X1622933D03*
Y1144389D03*
X1615452D03*
X1619193D03*
X1626673D03*
X1622933Y1155610D03*
X1615452D03*
Y1166830D03*
X1619193Y1170570D03*
X1626673Y1159350D03*
X1619193D03*
X1622933Y1166830D03*
X1626673Y1170570D03*
X1619193Y1185531D03*
X1626673D03*
X1622933D03*
Y1178051D03*
X1615452D03*
X1619193D03*
X1626673D03*
X1615452Y1185531D03*
X1622933Y1174310D03*
X1615452D03*
X1622933Y1193011D03*
X1626673D03*
X1615452D03*
X1619193D03*
X1622933Y1200491D03*
X1619193D03*
X1615452D03*
X1626673D03*
X1622933Y1215452D03*
X1619192Y1215451D03*
X1626673Y1215452D03*
X1615452D03*
X1613582Y1217322D03*
X1619192Y1211711D03*
X1622933D03*
X1637893Y1118208D03*
Y1114468D03*
X1634153D03*
X1630413D03*
X1641633D03*
X1634153Y1118208D03*
X1630413D03*
Y1136909D03*
X1637893D03*
X1634153D03*
X1630413Y1129429D03*
X1637893D03*
X1634153D03*
X1630413Y1151869D03*
X1637893D03*
X1634153D03*
Y1144389D03*
X1630413D03*
X1637893D03*
Y1155610D03*
X1630413D03*
X1637893Y1170570D03*
X1641633D03*
X1634153D03*
X1641633Y1166830D03*
X1637893D03*
Y1159350D03*
X1641633D03*
X1634153D03*
X1630413Y1166830D03*
X1641633Y1181791D03*
X1630413Y1185531D03*
X1634153D03*
X1630413Y1178051D03*
X1634153D03*
X1637893Y1185531D03*
Y1178051D03*
Y1174310D03*
X1630413D03*
X1634153Y1193011D03*
X1637893D03*
X1630413D03*
Y1200491D03*
X1637893D03*
X1634153D03*
X1630413Y1215452D03*
X1637893D03*
X1634153D03*
X1656594Y1118208D03*
X1652854D03*
Y1114468D03*
X1645374D03*
X1649114D03*
X1656594D03*
X1645374Y1129429D03*
Y1136909D03*
Y1140649D03*
X1656594Y1133169D03*
Y1140649D03*
Y1136909D03*
X1660334Y1140649D03*
X1649114Y1155610D03*
X1656594D03*
X1645374Y1144389D03*
X1660334Y1148129D03*
X1652854Y1144389D03*
X1656594Y1148129D03*
Y1144389D03*
X1649114Y1159350D03*
Y1170570D03*
Y1166830D03*
X1656594Y1170570D03*
Y1166830D03*
Y1159350D03*
Y1189271D03*
X1649114Y1174310D03*
X1656594D03*
X1652854Y1181791D03*
X1660334Y1189271D03*
X1645374Y1185531D03*
Y1189271D03*
X1660334Y1181791D03*
X1656594Y1178051D03*
X1645374D03*
Y1200491D03*
Y1193011D03*
X1656594Y1196751D03*
Y1204232D03*
X1652854Y1200491D03*
X1649114Y1204232D03*
Y1196751D03*
Y1200491D03*
X1656594D03*
X1645374Y1215452D03*
X1649114D03*
X1652854D03*
X1656594Y1211712D03*
X1645374D03*
X1656594Y1215452D03*
Y1207972D03*
X1649114D03*
X1652854D03*
Y1211712D03*
X1664075Y1140649D03*
X1667815Y1155610D03*
X1664075Y1148129D03*
Y1155610D03*
X1675295Y1144389D03*
Y1151869D03*
Y1166830D03*
Y1159350D03*
X1664075Y1170570D03*
X1667815D03*
X1675295Y1189271D03*
Y1174310D03*
Y1181791D03*
X1686515Y1140649D03*
X1682775D03*
X1679035Y1151869D03*
Y1144389D03*
X1682775Y1148129D03*
X1686515Y1155610D03*
Y1148129D03*
X1682775Y1155610D03*
X1679035Y1166830D03*
X1686515Y1170570D03*
X1682775D03*
X1679035Y1181791D03*
Y1189271D03*
Y1174310D03*
X1686515Y1185531D03*
X1682775Y1178051D03*
X1686515D03*
X1682775Y1185531D03*
X1686515Y1193011D03*
X1682775D03*
Y1222932D03*
X1693996Y1136909D03*
X1697736D03*
X1693996Y1151870D03*
X1697736D03*
X1693996Y1144389D03*
X1697736D03*
Y1159350D03*
X1693996D03*
X1697736Y1174310D03*
X1693996Y1189271D03*
X1697736D03*
Y1181791D03*
X1693996D03*
Y1174310D03*
X1796283Y441086D03*
Y433999D03*
Y437543D03*
X1793483Y441086D03*
Y433999D03*
Y437543D03*
X1796283Y444629D03*
X1793483D03*
G54D50*
X970071Y1365652D03*
Y1409152D03*
G54D32*
X109882Y1458622D03*
Y1463741D03*
Y1473977D03*
Y1479095D03*
Y1489331D03*
Y1494449D03*
Y1504685D03*
Y1509804D03*
Y1560985D03*
Y1566103D03*
Y1576339D03*
Y1581457D03*
Y1591693D03*
Y1596811D03*
Y1607048D03*
Y1612166D03*
Y1622402D03*
X127205Y1458622D03*
Y1463741D03*
X118543Y1452717D03*
Y1462953D03*
X127205Y1473977D03*
Y1479095D03*
X118543Y1468071D03*
Y1478308D03*
X127205Y1489331D03*
Y1494449D03*
X118543Y1483426D03*
Y1493662D03*
Y1498780D03*
X127205Y1504685D03*
Y1509804D03*
X118543Y1509016D03*
Y1514134D03*
X127205Y1560985D03*
Y1566103D03*
Y1576339D03*
X118543Y1565315D03*
Y1570434D03*
X127205Y1581457D03*
Y1591693D03*
X118543Y1580670D03*
Y1585788D03*
Y1596024D03*
X127205Y1596811D03*
Y1607048D03*
Y1612166D03*
X118543Y1601142D03*
Y1611378D03*
X127205Y1622402D03*
X118543Y1616496D03*
X144528Y1458622D03*
Y1463741D03*
X135866Y1452717D03*
Y1462953D03*
X144528Y1473977D03*
Y1479095D03*
X135866Y1468071D03*
Y1478308D03*
X144528Y1489331D03*
Y1494449D03*
X135866Y1483426D03*
Y1493662D03*
Y1498780D03*
X144528Y1504685D03*
Y1509804D03*
X135866Y1509016D03*
Y1514134D03*
X144528Y1560985D03*
Y1566103D03*
Y1576339D03*
X135866Y1565315D03*
Y1570434D03*
X144528Y1581457D03*
Y1591693D03*
X135866Y1580670D03*
Y1585788D03*
Y1596024D03*
X144528Y1596811D03*
Y1607048D03*
Y1612166D03*
X135866Y1601142D03*
Y1611378D03*
X144528Y1622402D03*
X135866Y1616496D03*
X161850Y1458622D03*
Y1463741D03*
X153189Y1452717D03*
Y1462953D03*
X161850Y1473977D03*
Y1479095D03*
X153189Y1468071D03*
Y1478308D03*
X161850Y1489331D03*
Y1494449D03*
X153189Y1483426D03*
Y1493662D03*
Y1498780D03*
X161850Y1504685D03*
Y1509804D03*
X153189Y1509016D03*
Y1514134D03*
X161850Y1560985D03*
Y1566103D03*
Y1576339D03*
X153189Y1565315D03*
Y1570434D03*
X161850Y1581457D03*
Y1591693D03*
X153189Y1580670D03*
Y1585788D03*
Y1596024D03*
X161850Y1596811D03*
Y1607048D03*
Y1612166D03*
X153189Y1601142D03*
Y1611378D03*
X161850Y1622402D03*
X153189Y1616496D03*
X179173Y1458622D03*
Y1463741D03*
X170512Y1452717D03*
Y1462953D03*
X179173Y1473977D03*
Y1479095D03*
X170512Y1468071D03*
Y1478308D03*
X179173Y1489331D03*
Y1494449D03*
X170512Y1483426D03*
Y1493662D03*
Y1498780D03*
X179173Y1504685D03*
Y1509804D03*
X170512Y1509016D03*
Y1514134D03*
X179173Y1560985D03*
Y1566103D03*
Y1576339D03*
X170512Y1565315D03*
Y1570434D03*
X179173Y1581457D03*
Y1591693D03*
X170512Y1580670D03*
Y1585788D03*
Y1596024D03*
X179173Y1596811D03*
Y1607048D03*
Y1612166D03*
X170512Y1601142D03*
Y1611378D03*
X179173Y1622402D03*
X170512Y1616496D03*
X187835Y1452717D03*
Y1462953D03*
Y1468071D03*
Y1478308D03*
Y1483426D03*
Y1493662D03*
Y1498780D03*
Y1509016D03*
Y1514134D03*
Y1565315D03*
Y1570434D03*
Y1580670D03*
Y1585788D03*
Y1596024D03*
Y1601142D03*
Y1611378D03*
Y1616496D03*
X291771Y1452717D03*
X283110Y1458622D03*
X291771Y1462953D03*
X283110Y1463741D03*
X291771Y1468071D03*
X283110Y1473977D03*
X291771Y1478308D03*
X283110Y1479095D03*
X291771Y1483426D03*
X283110Y1489331D03*
X291771Y1493662D03*
X283110Y1494449D03*
X291771Y1498780D03*
X283110Y1504685D03*
X291771Y1509016D03*
X283110Y1509804D03*
X291771Y1514134D03*
X283110Y1560985D03*
X291771Y1565315D03*
X283110Y1566103D03*
X291771Y1570434D03*
X283110Y1576339D03*
X291771Y1580670D03*
X283110Y1581457D03*
X291771Y1585788D03*
X283110Y1591693D03*
X291771Y1596024D03*
X283110Y1596811D03*
X291771Y1601142D03*
X283110Y1607048D03*
X291771Y1611378D03*
X283110Y1612166D03*
X291771Y1616496D03*
X283110Y1622402D03*
X309094Y1452717D03*
X300433Y1458622D03*
X309094Y1462953D03*
X300433Y1463741D03*
X309094Y1468071D03*
X300433Y1473977D03*
X309094Y1478308D03*
X300433Y1479095D03*
X309094Y1483426D03*
X300433Y1489331D03*
X309094Y1493662D03*
X300433Y1494449D03*
X309094Y1498780D03*
X300433Y1504685D03*
X309094Y1509016D03*
X300433Y1509804D03*
X309094Y1514134D03*
X300433Y1560985D03*
X309094Y1565315D03*
X300433Y1566103D03*
X309094Y1570434D03*
X300433Y1576339D03*
X309094Y1580670D03*
X300433Y1581457D03*
X309094Y1585788D03*
X300433Y1591693D03*
X309094Y1596024D03*
X300433Y1596811D03*
X309094Y1601142D03*
X300433Y1607048D03*
X309094Y1611378D03*
X300433Y1612166D03*
X309094Y1616496D03*
X300433Y1622402D03*
X326417Y1452717D03*
X317756Y1458622D03*
X326417Y1462953D03*
X317756Y1463741D03*
X326417Y1468071D03*
X317756Y1473977D03*
X326417Y1478308D03*
X317756Y1479095D03*
X326417Y1483426D03*
X317756Y1489331D03*
X326417Y1493662D03*
X317756Y1494449D03*
X326417Y1498780D03*
X317756Y1504685D03*
X326417Y1509016D03*
X317756Y1509804D03*
X326417Y1514134D03*
X317756Y1560985D03*
X326417Y1565315D03*
X317756Y1566103D03*
X326417Y1570434D03*
X317756Y1576339D03*
X326417Y1580670D03*
X317756Y1581457D03*
X326417Y1585788D03*
X317756Y1591693D03*
X326417Y1596024D03*
X317756Y1596811D03*
X326417Y1601142D03*
X317756Y1607048D03*
X326417Y1611378D03*
X317756Y1612166D03*
X326417Y1616496D03*
X317756Y1622402D03*
X343740Y1452717D03*
X335078Y1458622D03*
X343740Y1462953D03*
X335078Y1463741D03*
X343740Y1468071D03*
X335078Y1473977D03*
X343740Y1478308D03*
X335078Y1479095D03*
X343740Y1483426D03*
X335078Y1489331D03*
X343740Y1493662D03*
X335078Y1494449D03*
X343740Y1498780D03*
X335078Y1504685D03*
X343740Y1509016D03*
X335078Y1509804D03*
X343740Y1514134D03*
X335078Y1560985D03*
X343740Y1565315D03*
X335078Y1566103D03*
X343740Y1570434D03*
X335078Y1576339D03*
X343740Y1580670D03*
X335078Y1581457D03*
X343740Y1585788D03*
X335078Y1591693D03*
X343740Y1596024D03*
X335078Y1596811D03*
X343740Y1601142D03*
X335078Y1607048D03*
X343740Y1611378D03*
X335078Y1612166D03*
X343740Y1616496D03*
X335078Y1622402D03*
X361063Y1452717D03*
X352401Y1458622D03*
Y1463741D03*
X361063Y1462953D03*
Y1468071D03*
X352401Y1473977D03*
Y1479095D03*
X361063Y1478308D03*
Y1483426D03*
X352401Y1489331D03*
Y1494449D03*
X361063Y1493662D03*
Y1498780D03*
X352401Y1504685D03*
Y1509804D03*
X361063Y1509016D03*
Y1514134D03*
X352401Y1560985D03*
Y1566103D03*
X361063Y1565315D03*
Y1570434D03*
X352401Y1576339D03*
Y1581457D03*
X361063Y1580670D03*
Y1585788D03*
X352401Y1591693D03*
X361063Y1596024D03*
X352401Y1596811D03*
X361063Y1601142D03*
X352401Y1607048D03*
Y1612166D03*
X361063Y1611378D03*
Y1616496D03*
X352401Y1622402D03*
X456339Y1458622D03*
Y1463741D03*
Y1473977D03*
Y1479095D03*
Y1489331D03*
Y1494449D03*
Y1504685D03*
Y1509804D03*
Y1560985D03*
Y1566103D03*
Y1576339D03*
Y1581457D03*
Y1591693D03*
Y1596811D03*
Y1607048D03*
Y1612166D03*
Y1622402D03*
X473662Y1458622D03*
Y1463741D03*
X465000Y1452717D03*
Y1462953D03*
X473662Y1473977D03*
Y1479095D03*
X465000Y1468071D03*
Y1478308D03*
X473662Y1489331D03*
Y1494449D03*
X465000Y1483426D03*
Y1493662D03*
Y1498780D03*
X473662Y1504685D03*
Y1509804D03*
X465000Y1509016D03*
Y1514134D03*
X473662Y1560985D03*
Y1566103D03*
Y1576339D03*
X465000Y1565315D03*
Y1570434D03*
X473662Y1581457D03*
Y1591693D03*
X465000Y1580670D03*
Y1585788D03*
Y1596024D03*
X473662Y1596811D03*
Y1607048D03*
Y1612166D03*
X465000Y1601142D03*
Y1611378D03*
X473662Y1622402D03*
X465000Y1616496D03*
X490985Y1458622D03*
Y1463741D03*
X482323Y1452717D03*
Y1462953D03*
X490985Y1473977D03*
Y1479095D03*
X482323Y1468071D03*
Y1478308D03*
X490985Y1489331D03*
Y1494449D03*
X482323Y1483426D03*
Y1493662D03*
Y1498780D03*
X490985Y1504685D03*
Y1509804D03*
X482323Y1509016D03*
Y1514134D03*
X490985Y1560985D03*
Y1566103D03*
Y1576339D03*
X482323Y1565315D03*
Y1570434D03*
X490985Y1581457D03*
Y1591693D03*
X482323Y1580670D03*
Y1585788D03*
Y1596024D03*
X490985Y1596811D03*
Y1607048D03*
Y1612166D03*
X482323Y1601142D03*
Y1611378D03*
X490985Y1622402D03*
X482323Y1616496D03*
X499646Y1452717D03*
Y1462953D03*
Y1468071D03*
Y1478308D03*
Y1483426D03*
Y1493662D03*
Y1498780D03*
Y1509016D03*
Y1514134D03*
Y1565315D03*
Y1570434D03*
Y1580670D03*
Y1585788D03*
Y1596024D03*
Y1601142D03*
Y1611378D03*
Y1616496D03*
X516969Y1452717D03*
X508307Y1458622D03*
X516969Y1462953D03*
X508307Y1463741D03*
X516969Y1468071D03*
X508307Y1473977D03*
X516969Y1478308D03*
X508307Y1479095D03*
X516969Y1483426D03*
X508307Y1489331D03*
X516969Y1493662D03*
X508307Y1494449D03*
X516969Y1498780D03*
X508307Y1504685D03*
X516969Y1509016D03*
X508307Y1509804D03*
X516969Y1514134D03*
X508307Y1560985D03*
X516969Y1565315D03*
X508307Y1566103D03*
X516969Y1570434D03*
X508307Y1576339D03*
X516969Y1580670D03*
X508307Y1581457D03*
X516969Y1585788D03*
X508307Y1591693D03*
X516969Y1596024D03*
X508307Y1596811D03*
X516969Y1601142D03*
X508307Y1607048D03*
X516969Y1611378D03*
X508307Y1612166D03*
X516969Y1616496D03*
X508307Y1622402D03*
X534292Y1452717D03*
X525630Y1458622D03*
Y1463741D03*
X534292Y1462953D03*
Y1468071D03*
X525630Y1473977D03*
Y1479095D03*
X534292Y1478308D03*
Y1483426D03*
X525630Y1489331D03*
Y1494449D03*
X534292Y1493662D03*
Y1498780D03*
X525630Y1504685D03*
Y1509804D03*
X534292Y1509016D03*
Y1514134D03*
X525630Y1560985D03*
Y1566103D03*
X534292Y1565315D03*
Y1570434D03*
X525630Y1576339D03*
Y1581457D03*
X534292Y1580670D03*
Y1585788D03*
X525630Y1591693D03*
X534292Y1596024D03*
X525630Y1596811D03*
X534292Y1601142D03*
X525630Y1607048D03*
Y1612166D03*
X534292Y1611378D03*
Y1616496D03*
X525630Y1622402D03*
X629567Y1458622D03*
Y1463741D03*
Y1473977D03*
Y1479095D03*
Y1489331D03*
Y1494449D03*
Y1504685D03*
Y1509804D03*
Y1560985D03*
Y1566103D03*
Y1576339D03*
Y1581457D03*
Y1591693D03*
Y1596811D03*
Y1607048D03*
Y1612166D03*
Y1622402D03*
X646890Y1458622D03*
Y1463741D03*
X638228Y1452717D03*
Y1462953D03*
X646890Y1473977D03*
Y1479095D03*
X638228Y1468071D03*
Y1478308D03*
X646890Y1489331D03*
Y1494449D03*
X638228Y1483426D03*
Y1493662D03*
Y1498780D03*
X646890Y1504685D03*
Y1509804D03*
X638228Y1509016D03*
Y1514134D03*
X646890Y1560985D03*
Y1566103D03*
Y1576339D03*
X638228Y1565315D03*
Y1570434D03*
X646890Y1581457D03*
Y1591693D03*
X638228Y1580670D03*
Y1585788D03*
Y1596024D03*
X646890Y1596811D03*
Y1607048D03*
Y1612166D03*
X638228Y1601142D03*
Y1611378D03*
X646890Y1622402D03*
X638228Y1616496D03*
X664213Y1458622D03*
Y1463741D03*
X655551Y1452717D03*
Y1462953D03*
X664213Y1473977D03*
Y1479095D03*
X655551Y1468071D03*
Y1478308D03*
X664213Y1489331D03*
Y1494449D03*
X655551Y1483426D03*
Y1493662D03*
Y1498780D03*
X664213Y1504685D03*
Y1509804D03*
X655551Y1509016D03*
Y1514134D03*
X664213Y1560985D03*
Y1566103D03*
Y1576339D03*
X655551Y1565315D03*
Y1570434D03*
X664213Y1581457D03*
Y1591693D03*
X655551Y1580670D03*
Y1585788D03*
Y1596024D03*
X664213Y1596811D03*
Y1607048D03*
Y1612166D03*
X655551Y1601142D03*
Y1611378D03*
X664213Y1622402D03*
X655551Y1616496D03*
X681535Y1458622D03*
Y1463741D03*
X672874Y1452717D03*
Y1462953D03*
X681535Y1473977D03*
Y1479095D03*
X672874Y1468071D03*
Y1478308D03*
X681535Y1489331D03*
Y1494449D03*
X672874Y1483426D03*
Y1493662D03*
Y1498780D03*
X681535Y1504685D03*
Y1509804D03*
X672874Y1509016D03*
Y1514134D03*
X681535Y1560985D03*
Y1566103D03*
Y1576339D03*
X672874Y1565315D03*
Y1570434D03*
X681535Y1581457D03*
Y1591693D03*
X672874Y1580670D03*
Y1585788D03*
Y1596024D03*
X681535Y1596811D03*
Y1607048D03*
Y1612166D03*
X672874Y1601142D03*
Y1611378D03*
X681535Y1622402D03*
X672874Y1616496D03*
X698858Y1458622D03*
Y1463741D03*
X690197Y1452717D03*
Y1462953D03*
X698858Y1473977D03*
Y1479095D03*
X690197Y1468071D03*
Y1478308D03*
X698858Y1489331D03*
Y1494449D03*
X690197Y1483426D03*
Y1493662D03*
Y1498780D03*
X698858Y1504685D03*
Y1509804D03*
X690197Y1509016D03*
Y1514134D03*
X698858Y1560985D03*
Y1566103D03*
Y1576339D03*
X690197Y1565315D03*
Y1570434D03*
X698858Y1581457D03*
Y1591693D03*
X690197Y1580670D03*
Y1585788D03*
Y1596024D03*
X698858Y1596811D03*
Y1607048D03*
Y1612166D03*
X690197Y1601142D03*
Y1611378D03*
X698858Y1622402D03*
X690197Y1616496D03*
X707520Y1452717D03*
Y1462953D03*
Y1468071D03*
Y1478308D03*
Y1483426D03*
Y1493662D03*
Y1498780D03*
Y1509016D03*
Y1514134D03*
Y1565315D03*
Y1570434D03*
Y1580670D03*
Y1585788D03*
Y1596024D03*
Y1601142D03*
Y1611378D03*
Y1616496D03*
X1140511Y1452717D03*
X1131850Y1458622D03*
X1140511Y1462953D03*
X1131850Y1463741D03*
X1140511Y1468071D03*
X1131850Y1473977D03*
X1140511Y1478308D03*
X1131850Y1479095D03*
X1140511Y1483426D03*
X1131850Y1489331D03*
X1140511Y1493662D03*
X1131850Y1494449D03*
X1140511Y1498780D03*
X1131850Y1504685D03*
X1140511Y1509016D03*
X1131850Y1509804D03*
X1140511Y1514134D03*
X1131850Y1560985D03*
X1140511Y1565315D03*
X1131850Y1566103D03*
X1140511Y1570434D03*
X1131850Y1576339D03*
X1140511Y1580670D03*
X1131850Y1581457D03*
X1140511Y1585788D03*
X1131850Y1591693D03*
X1140511Y1596024D03*
X1131850Y1596811D03*
X1140511Y1601142D03*
X1131850Y1607048D03*
X1140511Y1611378D03*
X1131850Y1612166D03*
X1140511Y1616496D03*
X1131850Y1622402D03*
X1149173Y1458622D03*
Y1463741D03*
Y1473977D03*
Y1479095D03*
Y1489331D03*
Y1494449D03*
Y1504685D03*
Y1509804D03*
Y1560985D03*
Y1566103D03*
Y1576339D03*
Y1581457D03*
Y1591693D03*
Y1596811D03*
Y1607048D03*
Y1612166D03*
Y1622402D03*
X1166496Y1458622D03*
Y1463741D03*
X1157834Y1452717D03*
Y1462953D03*
X1166496Y1473977D03*
Y1479095D03*
X1157834Y1468071D03*
Y1478308D03*
X1166496Y1489331D03*
Y1494449D03*
X1157834Y1483426D03*
Y1493662D03*
Y1498780D03*
X1166496Y1504685D03*
Y1509804D03*
X1157834Y1509016D03*
Y1514134D03*
X1166496Y1560985D03*
Y1566103D03*
Y1576339D03*
X1157834Y1565315D03*
Y1570434D03*
X1166496Y1581457D03*
Y1591693D03*
X1157834Y1580670D03*
Y1585788D03*
Y1596024D03*
X1166496Y1596811D03*
Y1607048D03*
Y1612166D03*
X1157834Y1601142D03*
Y1611378D03*
X1166496Y1622402D03*
X1157834Y1616496D03*
X1183818Y1458622D03*
Y1463741D03*
X1175157Y1452717D03*
Y1462953D03*
X1183818Y1473977D03*
Y1479095D03*
X1175157Y1468071D03*
Y1478308D03*
X1183818Y1489331D03*
Y1494449D03*
X1175157Y1483426D03*
Y1493662D03*
Y1498780D03*
X1183818Y1504685D03*
Y1509804D03*
X1175157Y1509016D03*
Y1514134D03*
X1183818Y1560985D03*
Y1566103D03*
Y1576339D03*
X1175157Y1565315D03*
Y1570434D03*
X1183818Y1581457D03*
Y1591693D03*
X1175157Y1580670D03*
Y1585788D03*
Y1596024D03*
X1183818Y1596811D03*
Y1607048D03*
Y1612166D03*
X1175157Y1601142D03*
Y1611378D03*
X1183818Y1622402D03*
X1175157Y1616496D03*
X1201141Y1458622D03*
Y1463741D03*
X1192480Y1452717D03*
Y1462953D03*
X1201141Y1473977D03*
Y1479095D03*
X1192480Y1468071D03*
Y1478308D03*
X1201141Y1489331D03*
Y1494449D03*
X1192480Y1483426D03*
Y1493662D03*
Y1498780D03*
X1201141Y1504685D03*
Y1509804D03*
X1192480Y1509016D03*
Y1514134D03*
X1201141Y1560985D03*
Y1566103D03*
Y1576339D03*
X1192480Y1565315D03*
Y1570434D03*
X1201141Y1581457D03*
Y1591693D03*
X1192480Y1580670D03*
Y1585788D03*
Y1596024D03*
X1201141Y1596811D03*
Y1607048D03*
Y1612166D03*
X1192480Y1601142D03*
Y1611378D03*
X1201141Y1622402D03*
X1192480Y1616496D03*
X1209803Y1452717D03*
Y1462953D03*
Y1468071D03*
Y1478308D03*
Y1483426D03*
Y1493662D03*
Y1498780D03*
Y1509016D03*
Y1514134D03*
Y1565315D03*
Y1570434D03*
Y1580670D03*
Y1585788D03*
Y1596024D03*
Y1601142D03*
Y1611378D03*
Y1616496D03*
X1313740Y1452717D03*
X1305079Y1458622D03*
X1313740Y1462953D03*
X1305079Y1463741D03*
X1313740Y1468071D03*
X1305079Y1473977D03*
X1313740Y1478308D03*
X1305079Y1479095D03*
X1313740Y1483426D03*
X1305079Y1489331D03*
X1313740Y1493662D03*
X1305079Y1494449D03*
X1313740Y1498780D03*
X1305079Y1504685D03*
X1313740Y1509016D03*
X1305079Y1509804D03*
X1313740Y1514134D03*
X1305079Y1560985D03*
X1313740Y1565315D03*
X1305079Y1566103D03*
X1313740Y1570434D03*
X1305079Y1576339D03*
X1313740Y1580670D03*
X1305079Y1581457D03*
X1313740Y1585788D03*
X1305079Y1591693D03*
X1313740Y1596024D03*
X1305079Y1596811D03*
X1313740Y1601142D03*
X1305079Y1607048D03*
X1313740Y1611378D03*
X1305079Y1612166D03*
X1313740Y1616496D03*
X1305079Y1622402D03*
X1331063Y1452717D03*
X1322402Y1458622D03*
X1331063Y1462953D03*
X1322402Y1463741D03*
X1331063Y1468071D03*
X1322402Y1473977D03*
X1331063Y1478308D03*
X1322402Y1479095D03*
X1331063Y1483426D03*
X1322402Y1489331D03*
X1331063Y1493662D03*
X1322402Y1494449D03*
X1331063Y1498780D03*
X1322402Y1504685D03*
X1331063Y1509016D03*
X1322402Y1509804D03*
X1331063Y1514134D03*
X1322402Y1560985D03*
X1331063Y1565315D03*
X1322402Y1566103D03*
X1331063Y1570434D03*
X1322402Y1576339D03*
X1331063Y1580670D03*
X1322402Y1581457D03*
X1331063Y1585788D03*
X1322402Y1591693D03*
X1331063Y1596024D03*
X1322402Y1596811D03*
X1331063Y1601142D03*
X1322402Y1607048D03*
X1331063Y1611378D03*
X1322402Y1612166D03*
X1331063Y1616496D03*
X1322402Y1622402D03*
X1348386Y1452717D03*
X1339725Y1458622D03*
X1348386Y1462953D03*
X1339725Y1463741D03*
X1348386Y1468071D03*
X1339725Y1473977D03*
X1348386Y1478308D03*
X1339725Y1479095D03*
X1348386Y1483426D03*
X1339725Y1489331D03*
X1348386Y1493662D03*
X1339725Y1494449D03*
X1348386Y1498780D03*
X1339725Y1504685D03*
X1348386Y1509016D03*
X1339725Y1509804D03*
X1348386Y1514134D03*
X1339725Y1560985D03*
X1348386Y1565315D03*
X1339725Y1566103D03*
X1348386Y1570434D03*
X1339725Y1576339D03*
X1348386Y1580670D03*
X1339725Y1581457D03*
X1348386Y1585788D03*
X1339725Y1591693D03*
X1348386Y1596024D03*
X1339725Y1596811D03*
X1348386Y1601142D03*
X1339725Y1607048D03*
X1348386Y1611378D03*
X1339725Y1612166D03*
X1348386Y1616496D03*
X1339725Y1622402D03*
X1365709Y1452717D03*
X1357047Y1458622D03*
X1365709Y1462953D03*
X1357047Y1463741D03*
X1365709Y1468071D03*
X1357047Y1473977D03*
X1365709Y1478308D03*
X1357047Y1479095D03*
X1365709Y1483426D03*
X1357047Y1489331D03*
X1365709Y1493662D03*
X1357047Y1494449D03*
X1365709Y1498780D03*
X1357047Y1504685D03*
X1365709Y1509016D03*
X1357047Y1509804D03*
X1365709Y1514134D03*
X1357047Y1560985D03*
X1365709Y1565315D03*
X1357047Y1566103D03*
X1365709Y1570434D03*
X1357047Y1576339D03*
X1365709Y1580670D03*
X1357047Y1581457D03*
X1365709Y1585788D03*
X1357047Y1591693D03*
X1365709Y1596024D03*
X1357047Y1596811D03*
X1365709Y1601142D03*
X1357047Y1607048D03*
X1365709Y1611378D03*
X1357047Y1612166D03*
X1365709Y1616496D03*
X1357047Y1622402D03*
X1383032Y1452717D03*
X1374370Y1458622D03*
Y1463741D03*
X1383032Y1462953D03*
Y1468071D03*
X1374370Y1473977D03*
Y1479095D03*
X1383032Y1478308D03*
Y1483426D03*
X1374370Y1489331D03*
Y1494449D03*
X1383032Y1493662D03*
Y1498780D03*
X1374370Y1504685D03*
Y1509804D03*
X1383032Y1509016D03*
Y1514134D03*
X1374370Y1560985D03*
Y1566103D03*
X1383032Y1565315D03*
Y1570434D03*
X1374370Y1576339D03*
Y1581457D03*
X1383032Y1580670D03*
Y1585788D03*
X1374370Y1591693D03*
X1383032Y1596024D03*
X1374370Y1596811D03*
X1383032Y1601142D03*
X1374370Y1607048D03*
Y1612166D03*
X1383032Y1611378D03*
Y1616496D03*
X1374370Y1622402D03*
X1478307Y1458622D03*
Y1463741D03*
Y1473977D03*
Y1479095D03*
Y1489331D03*
Y1494449D03*
Y1504685D03*
Y1509804D03*
Y1560985D03*
Y1566103D03*
Y1576339D03*
Y1581457D03*
Y1591693D03*
Y1596811D03*
Y1607048D03*
Y1612166D03*
Y1622402D03*
X1495630Y1458622D03*
Y1463741D03*
X1486968Y1452717D03*
Y1462953D03*
X1495630Y1473977D03*
Y1479095D03*
X1486968Y1468071D03*
Y1478308D03*
X1495630Y1489331D03*
Y1494449D03*
X1486968Y1483426D03*
Y1493662D03*
Y1498780D03*
X1495630Y1504685D03*
Y1509804D03*
X1486968Y1509016D03*
Y1514134D03*
X1495630Y1560985D03*
Y1566103D03*
Y1576339D03*
X1486968Y1565315D03*
Y1570434D03*
X1495630Y1581457D03*
Y1591693D03*
X1486968Y1580670D03*
Y1585788D03*
Y1596024D03*
X1495630Y1596811D03*
Y1607048D03*
Y1612166D03*
X1486968Y1601142D03*
Y1611378D03*
X1495630Y1622402D03*
X1486968Y1616496D03*
X1512953Y1458622D03*
Y1463741D03*
X1504291Y1452717D03*
Y1462953D03*
X1512953Y1473977D03*
Y1479095D03*
X1504291Y1468071D03*
Y1478308D03*
X1512953Y1489331D03*
Y1494449D03*
X1504291Y1483426D03*
Y1493662D03*
Y1498780D03*
X1512953Y1504685D03*
Y1509804D03*
X1504291Y1509016D03*
Y1514134D03*
X1512953Y1560985D03*
Y1566103D03*
Y1576339D03*
X1504291Y1565315D03*
Y1570434D03*
X1512953Y1581457D03*
Y1591693D03*
X1504291Y1580670D03*
Y1585788D03*
Y1596024D03*
X1512953Y1596811D03*
Y1607048D03*
Y1612166D03*
X1504291Y1601142D03*
Y1611378D03*
X1512953Y1622402D03*
X1504291Y1616496D03*
X1530275Y1458622D03*
Y1463741D03*
X1521614Y1452717D03*
Y1462953D03*
X1530275Y1473977D03*
Y1479095D03*
X1521614Y1468071D03*
Y1478308D03*
X1530275Y1489331D03*
Y1494449D03*
X1521614Y1483426D03*
Y1493662D03*
Y1498780D03*
X1530275Y1504685D03*
Y1509804D03*
X1521614Y1509016D03*
Y1514134D03*
X1530275Y1560985D03*
Y1566103D03*
Y1576339D03*
X1521614Y1565315D03*
Y1570434D03*
X1530275Y1581457D03*
Y1591693D03*
X1521614Y1580670D03*
Y1585788D03*
Y1596024D03*
X1530275Y1596811D03*
Y1607048D03*
Y1612166D03*
X1521614Y1601142D03*
Y1611378D03*
X1530275Y1622402D03*
X1521614Y1616496D03*
X1538937Y1452717D03*
Y1462953D03*
Y1468071D03*
Y1478308D03*
Y1483426D03*
Y1493662D03*
Y1498780D03*
Y1509016D03*
Y1514134D03*
Y1565315D03*
Y1570434D03*
Y1580670D03*
Y1585788D03*
Y1596024D03*
Y1601142D03*
Y1611378D03*
Y1616496D03*
X1556260Y1452717D03*
X1547598Y1458622D03*
Y1463741D03*
X1556260Y1462953D03*
Y1468071D03*
X1547598Y1473977D03*
Y1479095D03*
X1556260Y1478308D03*
Y1483426D03*
X1547598Y1489331D03*
Y1494449D03*
X1556260Y1493662D03*
Y1498780D03*
X1547598Y1504685D03*
Y1509804D03*
X1556260Y1509016D03*
Y1514134D03*
X1547598Y1560985D03*
Y1566103D03*
X1556260Y1565315D03*
Y1570434D03*
X1547598Y1576339D03*
Y1581457D03*
X1556260Y1580670D03*
Y1585788D03*
X1547598Y1591693D03*
X1556260Y1596024D03*
X1547598Y1596811D03*
X1556260Y1601142D03*
X1547598Y1607048D03*
Y1612166D03*
X1556260Y1611378D03*
Y1616496D03*
X1547598Y1622402D03*
X1660196Y1452717D03*
X1651535Y1458622D03*
X1660196Y1462953D03*
X1651535Y1463741D03*
X1660196Y1468071D03*
X1651535Y1473977D03*
X1660196Y1478308D03*
X1651535Y1479095D03*
X1660196Y1483426D03*
X1651535Y1489331D03*
X1660196Y1493662D03*
X1651535Y1494449D03*
X1660196Y1498780D03*
X1651535Y1504685D03*
X1660196Y1509016D03*
X1651535Y1509804D03*
X1660196Y1514134D03*
X1651535Y1560985D03*
X1660196Y1565315D03*
X1651535Y1566103D03*
X1660196Y1570434D03*
X1651535Y1576339D03*
X1660196Y1580670D03*
X1651535Y1581457D03*
X1660196Y1585788D03*
X1651535Y1591693D03*
X1660196Y1596024D03*
X1651535Y1596811D03*
X1660196Y1601142D03*
X1651535Y1607048D03*
X1660196Y1611378D03*
X1651535Y1612166D03*
X1660196Y1616496D03*
X1651535Y1622402D03*
X1668858Y1458622D03*
Y1463741D03*
Y1473977D03*
Y1479095D03*
Y1489331D03*
Y1494449D03*
Y1504685D03*
Y1509804D03*
Y1560985D03*
Y1566103D03*
Y1576339D03*
Y1581457D03*
Y1591693D03*
Y1596811D03*
Y1607048D03*
Y1612166D03*
Y1622402D03*
X1686181Y1458622D03*
Y1463741D03*
X1677519Y1452717D03*
Y1462953D03*
X1686181Y1473977D03*
Y1479095D03*
X1677519Y1468071D03*
Y1478308D03*
X1686181Y1489331D03*
Y1494449D03*
X1677519Y1483426D03*
Y1493662D03*
Y1498780D03*
X1686181Y1504685D03*
Y1509804D03*
X1677519Y1509016D03*
Y1514134D03*
X1686181Y1560985D03*
Y1566103D03*
Y1576339D03*
X1677519Y1565315D03*
Y1570434D03*
X1686181Y1581457D03*
Y1591693D03*
X1677519Y1580670D03*
Y1585788D03*
Y1596024D03*
X1686181Y1596811D03*
Y1607048D03*
Y1612166D03*
X1677519Y1601142D03*
Y1611378D03*
X1686181Y1622402D03*
X1677519Y1616496D03*
X1703503Y1458622D03*
Y1463741D03*
X1694842Y1452717D03*
Y1462953D03*
X1703503Y1473977D03*
Y1479095D03*
X1694842Y1468071D03*
Y1478308D03*
X1703503Y1489331D03*
Y1494449D03*
X1694842Y1483426D03*
Y1493662D03*
Y1498780D03*
X1703503Y1504685D03*
Y1509804D03*
X1694842Y1509016D03*
Y1514134D03*
X1703503Y1560985D03*
Y1566103D03*
Y1576339D03*
X1694842Y1565315D03*
Y1570434D03*
X1703503Y1581457D03*
Y1591693D03*
X1694842Y1580670D03*
Y1585788D03*
Y1596024D03*
X1703503Y1596811D03*
Y1607048D03*
Y1612166D03*
X1694842Y1601142D03*
Y1611378D03*
X1703503Y1622402D03*
X1694842Y1616496D03*
X1720826Y1458622D03*
Y1463741D03*
X1712165Y1452717D03*
Y1462953D03*
X1720826Y1473977D03*
Y1479095D03*
X1712165Y1468071D03*
Y1478308D03*
X1720826Y1489331D03*
Y1494449D03*
X1712165Y1483426D03*
Y1493662D03*
Y1498780D03*
X1720826Y1504685D03*
Y1509804D03*
X1712165Y1509016D03*
Y1514134D03*
X1720826Y1560985D03*
Y1566103D03*
Y1576339D03*
X1712165Y1565315D03*
Y1570434D03*
X1720826Y1581457D03*
Y1591693D03*
X1712165Y1580670D03*
Y1585788D03*
Y1596024D03*
X1720826Y1596811D03*
Y1607048D03*
Y1612166D03*
X1712165Y1601142D03*
Y1611378D03*
X1720826Y1622402D03*
X1712165Y1616496D03*
X1729488Y1452717D03*
Y1462953D03*
Y1468071D03*
Y1478308D03*
Y1483426D03*
Y1493662D03*
Y1498780D03*
Y1509016D03*
Y1514134D03*
Y1565315D03*
Y1570434D03*
Y1580670D03*
Y1585788D03*
Y1596024D03*
Y1601142D03*
Y1611378D03*
Y1616496D03*
G54D52*
X1030635Y754546D03*
Y774546D03*
Y784546D03*
Y794546D03*
Y804546D03*
Y814546D03*
Y824546D03*
G54D27*
X76112Y1348187D03*
X79512D03*
X76112Y1360099D03*
X79512D03*
Y1372385D03*
X76112D03*
Y1384297D03*
X79512D03*
X88352Y1348187D03*
X91752D03*
X100592D03*
X91752Y1360099D03*
X88352D03*
X100592D03*
Y1384297D03*
Y1372385D03*
X91752D03*
X88352D03*
Y1384297D03*
X91752D03*
Y1396583D03*
X88352D03*
X100592D03*
X91752Y1408495D03*
X88352D03*
X100592D03*
X116232Y1348187D03*
X112832D03*
X103992D03*
X112832Y1360099D03*
X116232D03*
X103992D03*
Y1372385D03*
Y1384297D03*
X112832D03*
X116232Y1372385D03*
Y1384297D03*
X112832Y1372385D03*
X116232Y1396583D03*
X112832D03*
X103992D03*
X112832Y1408495D03*
X116232D03*
X103992D03*
X125072Y1348187D03*
X128472D03*
Y1360099D03*
X125072D03*
Y1384297D03*
X128472D03*
X125072Y1372385D03*
X128472D03*
X125072Y1396583D03*
X128472D03*
X125072Y1408495D03*
X128472D03*
X140712Y1348187D03*
X137312D03*
X149552D03*
X137312Y1360099D03*
X140712D03*
X149552D03*
Y1384297D03*
Y1372385D03*
X140712D03*
Y1384297D03*
X137312D03*
Y1372385D03*
X140712Y1396583D03*
X137312D03*
X149552D03*
X140712Y1408495D03*
X137312D03*
X149552D03*
X165192Y1348187D03*
X161792D03*
X152952D03*
X165192Y1360099D03*
X161792D03*
X152952D03*
Y1384297D03*
Y1372385D03*
X161792Y1384297D03*
X165192Y1372385D03*
Y1384297D03*
X161792Y1372385D03*
X165192Y1396583D03*
X161792D03*
X152952D03*
X165192Y1408495D03*
X161792D03*
X152952D03*
X177432Y1348187D03*
X174032D03*
Y1360099D03*
X177432D03*
Y1384297D03*
X174032D03*
Y1372385D03*
X177432D03*
Y1396583D03*
X174032D03*
X177432Y1408495D03*
X174032D03*
X189672Y1348187D03*
X186272D03*
X198512D03*
X189672Y1360099D03*
X186272D03*
X198512D03*
Y1384297D03*
Y1372385D03*
X186272Y1384297D03*
X189672D03*
Y1372385D03*
X186272D03*
Y1396583D03*
X189672D03*
X198512D03*
X189672Y1408495D03*
X186272D03*
X198512D03*
X201912Y1348187D03*
Y1360099D03*
Y1384297D03*
Y1372385D03*
Y1396583D03*
Y1408495D03*
X241623Y1348187D03*
X245023D03*
Y1360099D03*
X241623D03*
X245023Y1372385D03*
X241623D03*
Y1384297D03*
X245023D03*
X253863Y1348187D03*
X257263D03*
X253863Y1360099D03*
X257263D03*
X253863Y1372385D03*
X257263D03*
X253863Y1384297D03*
X257263D03*
X253863Y1396583D03*
X257263D03*
Y1408495D03*
X253863D03*
X281594Y1211712D03*
X270374Y1215452D03*
X269503Y1348187D03*
X278343D03*
X266103D03*
X278343Y1360099D03*
X266103D03*
X269503D03*
Y1372385D03*
X266103D03*
X278343D03*
X266103Y1384297D03*
X269503D03*
X278343D03*
Y1396583D03*
X269503D03*
X266103D03*
X278343Y1408495D03*
X269503D03*
X266103D03*
X281743Y1348187D03*
X293983D03*
X290583D03*
X281743Y1360099D03*
X293983D03*
X290583D03*
X293983Y1372385D03*
X281743D03*
X290583Y1384297D03*
X293983D03*
X290583Y1372385D03*
X281743Y1384297D03*
X293983Y1396583D03*
X290583D03*
X281743D03*
Y1408495D03*
X293983D03*
X290583D03*
X302823Y1348187D03*
X306223D03*
Y1360099D03*
X302823D03*
X306223Y1372385D03*
X302823D03*
X306223Y1384297D03*
X302823D03*
Y1396583D03*
X306223D03*
X302823Y1408495D03*
X306223D03*
X327303Y1348187D03*
X315063D03*
X318463D03*
X327303Y1360099D03*
X315063D03*
X318463D03*
X315063Y1372385D03*
X318463Y1384297D03*
X315063D03*
X327303Y1372385D03*
X318463D03*
X327303Y1384297D03*
Y1396583D03*
X315063D03*
X318463D03*
X327303Y1408495D03*
X318463D03*
X315063D03*
X339543Y1348187D03*
X342943D03*
X330703D03*
Y1360099D03*
X342943D03*
X339543D03*
Y1372385D03*
X342943D03*
X330703D03*
X342943Y1384297D03*
X339543D03*
X330703D03*
Y1396583D03*
X339543D03*
X342943D03*
X330703Y1408495D03*
X342943D03*
X339543D03*
X351783Y1348187D03*
X355183D03*
Y1360099D03*
X351783D03*
Y1372385D03*
X355183D03*
Y1384297D03*
X351783D03*
Y1396583D03*
X355183D03*
X351783Y1408495D03*
X355183D03*
X364023Y1348187D03*
X367423D03*
Y1360099D03*
X364023D03*
Y1372385D03*
X367423Y1384297D03*
X364023D03*
X367423Y1372385D03*
X364023Y1396583D03*
X367423D03*
X364023Y1408495D03*
X367423D03*
X393094Y1423600D03*
X395894D03*
X440402Y1348187D03*
Y1360099D03*
Y1372385D03*
Y1384297D03*
X452642Y1348187D03*
X456042D03*
X443802D03*
X456042Y1360099D03*
X452642D03*
X443802D03*
Y1372385D03*
X452642D03*
X456042D03*
X452642Y1384297D03*
X456042D03*
X443802D03*
X452642Y1396583D03*
X456042D03*
X452642Y1408495D03*
X456042D03*
X468282Y1348187D03*
X464882D03*
X468282Y1360099D03*
X464882D03*
Y1372385D03*
X468282D03*
X464882Y1384297D03*
X468282D03*
Y1396583D03*
X464882D03*
Y1408495D03*
X468282D03*
X489362Y1348187D03*
X480522D03*
X477122D03*
X480522Y1360099D03*
X477122D03*
X489362D03*
X477122Y1372385D03*
X480522D03*
X489362D03*
Y1384297D03*
X480522D03*
X477122D03*
X480522Y1396583D03*
X477122D03*
X489362D03*
X477122Y1408495D03*
X480522D03*
X489362D03*
X492762Y1348187D03*
X501602D03*
X505002D03*
X501602Y1360099D03*
X505002D03*
X492762D03*
X505002Y1372385D03*
X492762D03*
X501602D03*
X492762Y1384297D03*
X505002D03*
X501602D03*
X505002Y1396583D03*
X492762D03*
X501602D03*
X505002Y1408495D03*
X501602D03*
X492762D03*
X517242Y1348187D03*
X513842D03*
Y1360099D03*
X517242D03*
Y1372385D03*
X513842D03*
X517242Y1384297D03*
X513842D03*
X517242Y1396583D03*
X513842D03*
X517242Y1408495D03*
X513842D03*
X529482Y1348187D03*
X526082D03*
X538322D03*
Y1360099D03*
X529482D03*
X526082D03*
X529482Y1372385D03*
X538322Y1384297D03*
X529482D03*
X538322Y1372385D03*
X526082D03*
Y1384297D03*
Y1396583D03*
X538322D03*
X529482D03*
Y1408495D03*
X526082D03*
X538322D03*
X553962Y1348187D03*
X541722D03*
X550562D03*
X553962Y1360099D03*
X550562D03*
X541722D03*
Y1372385D03*
X550562D03*
X541722Y1384297D03*
X553962D03*
X550562D03*
X553962Y1372385D03*
Y1396583D03*
X541722D03*
X550562D03*
X553962Y1408495D03*
X550562D03*
X541722D03*
X562802Y1348187D03*
X566202D03*
Y1360099D03*
X562802D03*
X566202Y1372385D03*
Y1384297D03*
X562802D03*
Y1372385D03*
X566202Y1396583D03*
X562802D03*
X566202Y1408495D03*
X562802D03*
X629688Y1396583D03*
X626288D03*
Y1408495D03*
X629688D03*
X650768Y1348187D03*
Y1360099D03*
Y1384297D03*
Y1372385D03*
X638528D03*
X641928D03*
X638528Y1384297D03*
X641928D03*
Y1396583D03*
X638528D03*
X650768D03*
X638528Y1408495D03*
X641928D03*
X650768D03*
X666408Y1348187D03*
X663008D03*
X654168D03*
X666408Y1360099D03*
X663008D03*
X654168D03*
Y1384297D03*
Y1372385D03*
X663008D03*
X666408D03*
X663008Y1384297D03*
X666408D03*
Y1396583D03*
X663008D03*
X654168D03*
X666408Y1408495D03*
X663008D03*
X654168D03*
X678648Y1348187D03*
X675248D03*
X678648Y1360099D03*
X675248D03*
Y1384297D03*
X678648D03*
Y1372385D03*
X675248D03*
Y1396583D03*
X678648D03*
Y1408495D03*
X675248D03*
X690888Y1348187D03*
X687488D03*
X699728D03*
X687488Y1360099D03*
X690888D03*
X699728D03*
Y1372385D03*
Y1384297D03*
X690888Y1372385D03*
X687488D03*
Y1384297D03*
X690888D03*
Y1396583D03*
X687488D03*
X699728D03*
X687488Y1408495D03*
X690888D03*
X699728D03*
X715368Y1348187D03*
X711968D03*
X703128D03*
X715368Y1360099D03*
X711968D03*
X703128D03*
Y1372385D03*
Y1384297D03*
X715368Y1372385D03*
X711968D03*
X715368Y1384297D03*
X711968D03*
X715368Y1396583D03*
X711968D03*
X703128D03*
X715368Y1408495D03*
X711968D03*
X703128D03*
X727608Y1348187D03*
X724208D03*
Y1360099D03*
X727608D03*
X724208Y1372385D03*
Y1384297D03*
X727608D03*
Y1372385D03*
X724208Y1396489D03*
X727608D03*
X724208Y1408401D03*
X727608D03*
X739848Y1348187D03*
X736448D03*
X748688D03*
X736448Y1360099D03*
X739848D03*
X748688D03*
Y1372385D03*
Y1384297D03*
X739848Y1372385D03*
X736448D03*
X739848Y1384297D03*
X736448D03*
X739848Y1396489D03*
X736448D03*
X739848Y1408401D03*
X736448D03*
X760928Y1348187D03*
X764328D03*
X752088D03*
X764328Y1360099D03*
X760928D03*
X752088D03*
Y1372385D03*
Y1384297D03*
X764328Y1372385D03*
X760928D03*
X764328Y1384297D03*
X760928D03*
X776568Y1348187D03*
X773168D03*
Y1360099D03*
X776568D03*
X878220Y848442D03*
Y845293D03*
Y835844D03*
Y851592D03*
X877800Y876500D03*
X897118Y848442D03*
X881370Y835844D03*
X893968Y845293D03*
X884519Y848442D03*
X897118Y842143D03*
X893968D03*
X887669Y848442D03*
X886093Y835318D03*
X897118Y845293D03*
X893968Y838994D03*
X890818Y842143D03*
X893968Y835846D03*
X887669Y845293D03*
X890818D03*
X893968Y848442D03*
X884519Y845293D03*
X881370D03*
X884519Y842143D03*
X887669D03*
X881370Y848442D03*
X890818D03*
X887669Y851592D03*
X890818Y854742D03*
X887669D03*
X897118Y851592D03*
X890818Y864189D03*
Y857891D03*
X887669Y864189D03*
X884519Y854742D03*
Y851592D03*
Y857891D03*
X887669D03*
X890818Y851592D03*
X893967Y851591D03*
X881370Y851592D03*
X887669Y867338D03*
X890818Y870488D03*
X887669D03*
X897118Y876787D03*
X890818Y867338D03*
X881370D03*
X897118Y879937D03*
X884519Y873638D03*
X887669D03*
X884519Y876787D03*
X890818Y879937D03*
X881370Y876787D03*
X887669Y879937D03*
X884519Y867338D03*
X890818Y873638D03*
X893968Y876787D03*
Y879937D03*
X890818Y876787D03*
X884519Y879937D03*
Y870488D03*
X881370D03*
Y883086D03*
X884585Y886354D03*
X885126Y889742D03*
X881370Y886236D03*
X906565Y848442D03*
X900267D03*
X906565Y838994D03*
X900267Y838992D03*
X909714Y848442D03*
X906565Y842143D03*
X900267Y845293D03*
Y842143D03*
X906565Y845293D03*
X900266Y835844D03*
X900267Y851592D03*
X906565D03*
X909714D03*
Y876787D03*
X900267Y879937D03*
Y876787D03*
X906565D03*
X912864Y873638D03*
Y879937D03*
X909714D03*
X906565D03*
X912864Y876787D03*
X922313Y845293D03*
X919163Y848442D03*
X916014D03*
Y842143D03*
X919163Y845293D03*
X922313Y842143D03*
X916014Y845293D03*
X919163Y835844D03*
Y838994D03*
Y842143D03*
X925462Y845293D03*
X919163Y854742D03*
Y857891D03*
X922313Y854742D03*
X916014Y857891D03*
Y854742D03*
X919163Y851592D03*
X916014D03*
Y864189D03*
X925462Y851592D03*
X922313Y864189D03*
Y857891D03*
X925462D03*
X928612Y864189D03*
X919163D03*
X925462D03*
X916014Y870488D03*
X925462Y873638D03*
X922313Y876787D03*
X928612Y870488D03*
X925462D03*
X916014Y873638D03*
X922313D03*
X916014Y876787D03*
X928612Y873638D03*
X925462Y876787D03*
X928612D03*
Y879937D03*
X916014D03*
X922313D03*
X919163D03*
X925462D03*
X916014Y867338D03*
X919163Y873638D03*
Y870488D03*
X922313D03*
X919163Y876787D03*
X922313Y867338D03*
X919163D03*
X925462D03*
X922313Y883086D03*
Y886236D03*
X925462D03*
X919163Y883086D03*
X928612Y886236D03*
X925462Y883086D03*
X928612D03*
X1058113Y1348187D03*
X1054713D03*
X1058113Y1360099D03*
X1054713D03*
X1058113Y1372385D03*
X1054713D03*
Y1384297D03*
X1058113D03*
X1066953Y1348187D03*
X1070353D03*
X1066953Y1360099D03*
X1070353D03*
X1066953Y1384297D03*
Y1372385D03*
X1070353D03*
Y1384297D03*
Y1396583D03*
X1066953D03*
Y1408495D03*
X1070353D03*
X1091433Y1348187D03*
X1082593D03*
X1079193D03*
X1091433Y1360099D03*
X1082593D03*
X1079193D03*
Y1372385D03*
X1082593D03*
Y1384297D03*
X1079193D03*
X1091433D03*
Y1372385D03*
Y1396583D03*
X1082593D03*
X1079193D03*
X1091433Y1408495D03*
X1082593D03*
X1079193D03*
X1094833Y1348187D03*
X1107073D03*
X1103673D03*
X1094833Y1360099D03*
X1103673D03*
X1107073D03*
Y1372385D03*
X1103673D03*
X1107073Y1384297D03*
X1103673D03*
X1094833D03*
Y1372385D03*
Y1396583D03*
X1107073D03*
X1103673D03*
X1094833Y1408495D03*
X1107073D03*
X1103673D03*
X1115913Y1348187D03*
X1119313D03*
X1115913Y1360099D03*
X1119313D03*
Y1384297D03*
X1115913Y1372385D03*
X1119313D03*
X1115913Y1384297D03*
Y1396583D03*
X1119313D03*
X1115913Y1408495D03*
X1119313D03*
X1140393Y1348187D03*
X1131553D03*
X1128153D03*
X1140393Y1360099D03*
X1131553D03*
X1128153D03*
Y1384297D03*
X1131553D03*
X1128153Y1372385D03*
X1131553D03*
X1140393Y1384297D03*
Y1372385D03*
Y1396583D03*
X1131553D03*
X1128153D03*
X1140393Y1408495D03*
X1128153D03*
X1131553D03*
X1143793Y1348187D03*
X1156033D03*
X1152633D03*
X1143793Y1360099D03*
X1152633D03*
X1156033D03*
Y1384297D03*
X1152633D03*
X1156033Y1372385D03*
X1152633D03*
X1143793D03*
Y1384297D03*
Y1396583D03*
X1156033D03*
X1152633D03*
X1143793Y1408495D03*
X1152633D03*
X1156033D03*
X1168273Y1348187D03*
X1164873D03*
Y1360099D03*
X1168273D03*
Y1384297D03*
X1164873D03*
X1168273Y1372385D03*
X1164873D03*
Y1396583D03*
X1168273D03*
Y1408495D03*
X1164873D03*
X1184547Y1215452D03*
X1177113Y1348187D03*
X1180513D03*
X1177113Y1360099D03*
X1180513D03*
X1177113Y1384297D03*
X1180513D03*
X1177113Y1372385D03*
X1180513D03*
Y1396583D03*
X1177113D03*
Y1408495D03*
X1180513D03*
X1230326Y1348187D03*
X1233726D03*
X1230326Y1360099D03*
X1233726D03*
X1230326Y1372385D03*
X1233726D03*
X1230326Y1384297D03*
X1233726D03*
X1245966Y1348187D03*
X1242566D03*
X1254806D03*
Y1360099D03*
X1242566D03*
X1245966D03*
X1254806Y1372385D03*
X1242566D03*
X1245966D03*
X1242566Y1384297D03*
X1245966D03*
X1254806D03*
X1245966Y1396583D03*
X1254806D03*
X1242566D03*
X1254806Y1408495D03*
X1242566D03*
X1245966D03*
X1267046Y1348187D03*
X1270446D03*
X1258206D03*
Y1360099D03*
X1270446D03*
X1267046D03*
X1258206Y1372385D03*
X1270446D03*
X1267046D03*
X1270446Y1384297D03*
X1267046D03*
X1258206D03*
X1267046Y1396583D03*
X1270446D03*
X1258206D03*
Y1408495D03*
X1270446D03*
X1267046D03*
X1282686Y1348187D03*
X1279286D03*
Y1360099D03*
X1282686D03*
X1279286Y1372385D03*
X1282686D03*
Y1384297D03*
X1279286D03*
Y1396583D03*
X1282686D03*
X1279286Y1408495D03*
X1282686D03*
X1291526Y1348187D03*
X1294926D03*
X1291526Y1360099D03*
X1294926D03*
X1291526Y1372385D03*
X1294926D03*
X1291526Y1384297D03*
X1294926D03*
Y1396583D03*
X1291526D03*
Y1408495D03*
X1294926D03*
X1316906Y829871D03*
Y833021D03*
Y848769D03*
X1313756Y833021D03*
Y836170D03*
X1316906Y839320D03*
X1310555Y848675D03*
X1313756Y848769D03*
X1316906Y836170D03*
X1313756Y842470D03*
Y858218D03*
X1316906Y855068D03*
X1313756Y855066D03*
X1316906Y858218D03*
X1319406Y1348187D03*
X1316006D03*
X1307166D03*
X1303766D03*
X1319406Y1360099D03*
X1316006D03*
X1307166D03*
X1303766D03*
X1316006Y1372385D03*
X1307166D03*
X1303766D03*
Y1384297D03*
X1307166D03*
X1319406Y1372385D03*
X1316006Y1384297D03*
X1319406D03*
Y1396583D03*
X1316006D03*
X1303766D03*
X1307166D03*
X1316006Y1408495D03*
X1319406D03*
X1307166D03*
X1303766D03*
X1335803Y829871D03*
X1323205D03*
X1326355Y839320D03*
X1335803D03*
X1329504Y833021D03*
X1332654Y842470D03*
X1329504Y845619D03*
X1332654D03*
X1326355Y836170D03*
X1335803Y842470D03*
X1329504Y836170D03*
X1335803Y845619D03*
Y848769D03*
X1329504Y839320D03*
X1323205Y836170D03*
X1335803D03*
X1329504Y842470D03*
X1335803Y833021D03*
X1323205D03*
X1320055Y845619D03*
X1326355D03*
X1320055Y836170D03*
X1326355Y842470D03*
X1320055Y848769D03*
X1323205Y845619D03*
X1332654Y848769D03*
X1320055Y839320D03*
X1326355Y848769D03*
X1323205D03*
X1329504D03*
X1323204Y839319D03*
X1332654Y839320D03*
X1320055Y842470D03*
X1323205D03*
X1329504Y855068D03*
Y858218D03*
X1320055Y851918D03*
X1332654Y855068D03*
X1326355D03*
Y858218D03*
X1329504Y861367D03*
X1323205Y858218D03*
X1320055D03*
X1332654Y861367D03*
X1329504Y851918D03*
X1323205D03*
X1326355Y861367D03*
X1320055Y855068D03*
X1332654Y858218D03*
X1335803Y855068D03*
Y858218D03*
Y861367D03*
X1320055D03*
X1323204Y855067D03*
X1326355Y851918D03*
X1332654D03*
X1326355Y880263D03*
X1329504Y877114D03*
X1335803Y880263D03*
X1326355Y867665D03*
Y870814D03*
X1323205D03*
X1320055D03*
X1329504Y867665D03*
X1326355Y873964D03*
X1332654Y880263D03*
X1329504D03*
X1332654Y877114D03*
X1326355D03*
X1329504Y870814D03*
X1320055Y873964D03*
X1332654Y870814D03*
X1323204Y873965D03*
X1332654Y867665D03*
X1320055Y880263D03*
Y867665D03*
X1323205Y880263D03*
Y877114D03*
X1320055D03*
X1335803Y867665D03*
Y873964D03*
Y870814D03*
X1332654Y873964D03*
X1329504D03*
X1323205Y867665D03*
Y886562D03*
X1326355Y889712D03*
X1335803Y883413D03*
X1329504Y892862D03*
X1332654Y889712D03*
X1335803Y892862D03*
Y889712D03*
X1326355Y892862D03*
X1329504Y889712D03*
X1320055Y892862D03*
X1323205D03*
X1329504Y886562D03*
X1332654Y883413D03*
X1320055Y886562D03*
X1326355Y883413D03*
X1323205D03*
X1332654Y892862D03*
X1320055Y883413D03*
X1332654Y886562D03*
X1335803D03*
X1320055Y889712D03*
X1323204Y889713D03*
X1329504Y883413D03*
X1328246Y1348187D03*
X1331646D03*
X1328246Y1360099D03*
X1331646D03*
Y1384297D03*
Y1372385D03*
X1328246D03*
Y1384297D03*
X1331646Y1396583D03*
X1328246D03*
X1331646Y1408495D03*
X1328246D03*
X1342103Y845619D03*
X1345252Y836170D03*
X1338953Y845619D03*
X1345252Y833021D03*
X1342103Y836170D03*
X1351550D03*
X1342103Y842470D03*
X1345252Y845619D03*
X1342103Y839320D03*
X1338953Y848769D03*
X1338952Y839319D03*
X1345252Y842470D03*
X1342103Y848769D03*
X1338953Y842470D03*
X1345252Y848769D03*
X1338953Y836170D03*
X1351550Y842470D03*
Y848769D03*
Y845619D03*
X1345252Y839320D03*
X1351550Y858218D03*
X1345252D03*
Y861367D03*
X1342103Y858218D03*
X1351550Y861367D03*
X1338953Y851918D03*
X1342103D03*
X1345252D03*
X1351550D03*
X1338953Y880263D03*
X1351550D03*
X1345252D03*
X1342103Y870814D03*
X1345252D03*
Y867665D03*
X1351550Y870814D03*
Y867665D03*
X1338953Y877114D03*
X1345252D03*
X1351550D03*
X1342103Y880263D03*
X1338953Y883413D03*
X1345252Y889712D03*
Y886562D03*
X1342103Y883413D03*
X1345252D03*
X1338952Y889713D03*
X1338953Y892862D03*
X1342103Y886562D03*
Y892862D03*
Y889712D03*
X1338953Y886562D03*
X1351550Y883413D03*
Y889712D03*
Y886562D03*
Y892862D03*
X1343886Y1348187D03*
X1340486D03*
X1343886Y1360099D03*
X1340486D03*
X1343886Y1372385D03*
X1340486D03*
Y1384297D03*
X1343886D03*
X1340486Y1396583D03*
X1343886D03*
Y1408495D03*
X1340486D03*
X1364148Y829871D03*
X1367298D03*
X1359425Y829000D03*
X1354699Y842470D03*
Y848769D03*
X1357849D03*
X1364148Y845619D03*
X1354699Y836170D03*
X1357849Y833021D03*
X1367298Y845619D03*
X1364148Y842470D03*
X1357850Y839319D03*
X1357849Y836170D03*
X1360999Y842470D03*
X1354699Y845619D03*
X1357849D03*
X1360999Y839320D03*
X1367298Y842470D03*
X1360999Y848769D03*
Y845619D03*
X1367298Y833021D03*
X1354699Y839320D03*
X1360999Y836170D03*
X1367298Y848769D03*
X1364148Y839320D03*
X1357849Y842470D03*
X1364148Y833021D03*
X1367298Y836170D03*
Y839320D03*
X1364148Y848769D03*
Y851918D03*
X1367298Y861367D03*
X1364148Y858218D03*
Y855068D03*
Y861367D03*
X1367298Y858218D03*
Y851918D03*
X1354699Y858218D03*
X1367298Y855068D03*
X1360999D03*
Y858218D03*
Y861367D03*
X1354699Y851918D03*
X1357849D03*
X1364148Y867665D03*
X1367298Y877114D03*
X1364148Y870814D03*
X1367298Y873964D03*
X1364148D03*
Y877114D03*
X1367298Y870814D03*
X1364148Y880263D03*
X1367298D03*
X1357849D03*
X1360999D03*
X1367298Y867665D03*
X1354699Y870814D03*
X1357849Y877114D03*
X1354699Y880263D03*
X1360999Y867665D03*
Y870814D03*
Y873964D03*
X1367298Y883413D03*
X1354699Y892862D03*
X1360999D03*
X1367298D03*
X1360999Y883413D03*
X1357850Y889713D03*
X1364148Y889712D03*
X1357849Y883413D03*
X1367298Y889712D03*
X1354699D03*
X1357849Y886562D03*
X1364148D03*
X1357849Y892862D03*
X1360999Y889712D03*
X1354699Y883413D03*
X1360999Y886562D03*
X1364148Y892862D03*
Y883413D03*
X1367298Y886562D03*
X1354699D03*
X1356126Y1348187D03*
X1352726D03*
X1356126Y1360099D03*
X1352726D03*
Y1384297D03*
X1356126Y1372385D03*
Y1384297D03*
X1352726Y1372385D03*
X1356126Y1396583D03*
X1352726D03*
Y1408495D03*
X1356126D03*
X1370447Y829871D03*
Y839320D03*
X1383046Y845619D03*
X1379896D03*
X1373597D03*
Y842470D03*
X1370447Y848769D03*
X1379896D03*
Y839320D03*
X1373597Y848769D03*
X1376747D03*
X1373597Y833021D03*
X1370447D03*
X1373597Y836170D03*
X1370447D03*
X1373598Y839319D03*
X1370447Y842470D03*
Y845619D03*
X1383046Y842470D03*
X1376747Y836170D03*
Y842470D03*
X1379896Y833021D03*
X1383046Y839320D03*
X1376747Y845619D03*
Y839320D03*
X1379896Y855068D03*
Y861367D03*
X1376747Y858218D03*
Y851918D03*
X1373597Y861367D03*
X1376747Y855068D03*
X1373597Y858218D03*
X1376747Y861367D03*
X1383046Y851918D03*
X1373597D03*
X1373598Y855067D03*
X1379896Y851918D03*
X1370447D03*
Y858218D03*
X1383046D03*
Y861367D03*
X1370447Y855068D03*
Y861367D03*
X1383046Y873964D03*
X1376747Y880263D03*
X1370447Y877114D03*
X1373598Y873965D03*
X1370447Y873964D03*
X1379896Y877114D03*
X1373597Y880263D03*
X1383046Y877114D03*
X1370447Y880263D03*
X1376747Y873964D03*
X1383046Y880263D03*
X1370447Y870814D03*
X1376747D03*
X1373597D03*
X1376747Y867665D03*
Y877114D03*
X1373597Y867665D03*
X1379896D03*
X1383046Y870814D03*
X1379896Y880263D03*
X1373597Y877114D03*
X1379896Y873964D03*
X1383046Y892862D03*
X1379896Y886562D03*
X1370447Y883413D03*
X1373598Y889713D03*
X1376747Y886562D03*
X1383046Y883413D03*
X1376747Y889712D03*
X1383046D03*
X1379896D03*
X1373597Y883413D03*
Y886562D03*
X1370447Y892862D03*
X1376747D03*
X1370447Y889712D03*
X1373597Y892862D03*
X1383046Y886562D03*
X1379896Y892862D03*
X1376747Y883413D03*
X1464770Y1348187D03*
X1461370D03*
X1464770Y1360099D03*
X1461370D03*
X1464770Y1372385D03*
X1461370D03*
X1464770Y1384297D03*
X1461370D03*
X1477010Y1348187D03*
X1473610D03*
Y1360099D03*
X1477010D03*
X1473610Y1372385D03*
X1477010D03*
X1473610Y1384297D03*
X1477010D03*
Y1396583D03*
X1473610D03*
Y1408495D03*
X1477010D03*
X1489250Y1348187D03*
X1485850D03*
X1498090D03*
Y1360099D03*
X1485850D03*
X1489250D03*
Y1372385D03*
X1485850D03*
X1498090D03*
X1485850Y1384297D03*
X1498090D03*
X1489250D03*
X1498090Y1396583D03*
X1485850D03*
X1489250D03*
X1498090Y1408495D03*
X1489250D03*
X1485850D03*
X1513730Y1348187D03*
X1510330D03*
X1501490D03*
X1510330Y1360099D03*
X1501490D03*
X1513730D03*
X1510330Y1372385D03*
X1513730D03*
X1501490D03*
Y1384297D03*
X1513730D03*
X1510330D03*
Y1396583D03*
X1513730D03*
X1501490D03*
X1510330Y1408495D03*
X1513730D03*
X1501490D03*
X1525970Y1348187D03*
X1522570D03*
Y1360099D03*
X1525970D03*
Y1372385D03*
X1522570D03*
X1525970Y1384297D03*
X1522570D03*
Y1396583D03*
X1525970D03*
Y1408495D03*
X1522570D03*
X1538210Y1348187D03*
X1547050D03*
X1534810D03*
X1538210Y1360099D03*
X1534810D03*
X1547050D03*
X1538210Y1372385D03*
X1534810D03*
X1547050D03*
Y1384297D03*
X1534810D03*
X1538210D03*
Y1396583D03*
X1534810D03*
X1547050D03*
X1538210Y1408495D03*
X1534810D03*
X1547050D03*
X1550450Y1348187D03*
X1559290D03*
X1562690D03*
X1559290Y1360099D03*
X1562690D03*
X1550450D03*
X1562690Y1372385D03*
X1559290D03*
X1550450D03*
X1562690Y1384297D03*
X1559290D03*
X1550450D03*
Y1396583D03*
X1562690D03*
X1559290D03*
Y1408495D03*
X1562690D03*
X1550450D03*
X1574930Y1348187D03*
X1571530D03*
X1574930Y1360099D03*
X1571530D03*
X1574930Y1372385D03*
X1571530D03*
Y1384297D03*
X1574930D03*
X1571530Y1396583D03*
X1574930D03*
X1571530Y1408495D03*
X1574930D03*
X1587170Y1348187D03*
X1583770D03*
X1587170Y1360099D03*
X1583770D03*
X1587170Y1372385D03*
X1583770D03*
Y1384297D03*
X1587170D03*
X1583770Y1396583D03*
X1587170D03*
X1583770Y1408495D03*
X1587170D03*
X1611398Y1348187D03*
Y1360099D03*
Y1384297D03*
Y1372385D03*
X1614798Y1348187D03*
X1623638D03*
X1627038D03*
X1614798Y1360099D03*
X1623638D03*
X1627038D03*
Y1372385D03*
X1623638D03*
X1627038Y1384297D03*
X1623638D03*
X1614798Y1372385D03*
Y1384297D03*
X1627038Y1396583D03*
X1623638D03*
X1627038Y1408495D03*
X1623638D03*
X1641634Y1215452D03*
X1639278Y1348187D03*
X1635878D03*
X1639278Y1360099D03*
X1635878D03*
Y1384297D03*
X1639278D03*
Y1372385D03*
X1635878D03*
X1639278Y1396583D03*
X1635878D03*
Y1408495D03*
X1639278D03*
X1660358Y1348187D03*
X1651518D03*
X1648118D03*
X1660358Y1360099D03*
X1651518D03*
X1648118D03*
Y1372385D03*
X1651518D03*
X1648118Y1384297D03*
X1651518D03*
X1660358D03*
Y1372385D03*
Y1396583D03*
X1651518D03*
X1648118D03*
X1660358Y1408495D03*
X1648118D03*
X1651518D03*
X1663758Y1348187D03*
X1672598D03*
X1675998D03*
X1663758Y1360099D03*
X1675998D03*
X1672598D03*
X1675998Y1372385D03*
X1672598D03*
Y1384297D03*
X1675998D03*
X1663758D03*
Y1372385D03*
Y1396583D03*
X1675998D03*
X1672598D03*
X1663758Y1408495D03*
X1675998D03*
X1672598D03*
X1688238Y1348187D03*
X1684838D03*
X1688238Y1360099D03*
X1684838D03*
Y1384297D03*
X1688238D03*
X1684838Y1372385D03*
X1688238D03*
X1684838Y1396583D03*
X1688238D03*
Y1408495D03*
X1684838D03*
X1709318Y1348187D03*
X1700478D03*
X1697078D03*
X1709318Y1360099D03*
X1697078D03*
X1700478D03*
X1697078Y1372385D03*
X1700478D03*
X1697078Y1384297D03*
X1700478D03*
X1709318D03*
Y1372385D03*
Y1396583D03*
X1700478D03*
X1697078D03*
X1709318Y1408495D03*
X1697078D03*
X1700478D03*
X1712718Y1348187D03*
X1721558D03*
X1724958D03*
X1712718Y1360099D03*
X1724958D03*
X1721558D03*
Y1372385D03*
X1724958D03*
Y1384297D03*
X1721558D03*
X1712718Y1372385D03*
Y1384297D03*
Y1396583D03*
X1721558D03*
X1724958D03*
X1712718Y1408495D03*
X1721558D03*
X1724958D03*
X1733798Y1348187D03*
X1737198D03*
X1733798Y1360099D03*
X1737198D03*
Y1384297D03*
X1733798D03*
Y1372385D03*
X1737198D03*
Y1396583D03*
X1733798D03*
X1737198Y1408495D03*
X1733798D03*
G54D28*
X116731Y1052235D03*
X106619Y1056423D03*
X102431Y1066535D03*
X106619Y1076647D03*
X116731Y1080835D03*
Y1249086D03*
X106619Y1253274D03*
X102431Y1263386D03*
X106619Y1273498D03*
X116731Y1277686D03*
X126843Y1056423D03*
Y1076647D03*
X131031Y1066535D03*
X126843Y1253274D03*
X131031Y1263386D03*
X126843Y1273498D03*
X342840Y1056423D03*
X338652Y1066535D03*
X342840Y1076647D03*
Y1253274D03*
X338652Y1263386D03*
X342840Y1273498D03*
X352952Y1052235D03*
Y1080835D03*
Y1249086D03*
Y1277686D03*
X363064Y1056423D03*
Y1076647D03*
X367252Y1066535D03*
X363064Y1253274D03*
X367252Y1263386D03*
X363064Y1273498D03*
X563706Y1056423D03*
X559518Y1066535D03*
X563706Y1076647D03*
Y1253274D03*
X559518Y1263386D03*
X563706Y1273498D03*
X583930Y1056423D03*
X573818Y1052235D03*
X583930Y1076647D03*
X588118Y1066535D03*
X573818Y1080835D03*
X583930Y1253274D03*
X573818Y1249086D03*
X588118Y1263386D03*
X573818Y1277686D03*
X583930Y1273498D03*
X760433Y1480906D03*
X756274Y1490945D03*
X760433Y1500984D03*
X780511Y1480906D03*
X770472Y1476747D03*
Y1505143D03*
X780511Y1500984D03*
X799926Y1056423D03*
X795738Y1066535D03*
X799926Y1076647D03*
Y1253274D03*
X795738Y1263386D03*
X799926Y1273498D03*
X784670Y1490945D03*
X810040Y378544D03*
X805881Y388583D03*
X810040Y398622D03*
X810038Y1052235D03*
Y1080835D03*
Y1249086D03*
Y1277686D03*
X820079Y374385D03*
X830118Y378544D03*
X820079Y402781D03*
X830118Y398622D03*
X820150Y1056423D03*
Y1076647D03*
X824338Y1066535D03*
X820150Y1253274D03*
X824338Y1263386D03*
X820150Y1273498D03*
X834277Y388583D03*
X1010827Y378544D03*
X1006668Y388583D03*
X1010827Y398622D03*
X1020866Y374385D03*
Y402781D03*
X1020793Y1056423D03*
X1016605Y1066535D03*
X1020793Y1076647D03*
Y1253274D03*
X1016605Y1263386D03*
X1020793Y1273498D03*
X1030905Y378544D03*
X1035064Y388583D03*
X1030905Y398622D03*
X1041017Y1056423D03*
X1030905Y1052235D03*
X1041017Y1076647D03*
X1030905Y1080835D03*
X1041017Y1253274D03*
X1030905Y1249086D03*
Y1277686D03*
X1041017Y1273498D03*
X1045205Y1066535D03*
Y1263386D03*
X1060433Y1480906D03*
X1056274Y1490945D03*
X1060433Y1500984D03*
X1070472Y1476747D03*
Y1505143D03*
X1080511Y1480906D03*
X1084670Y1490945D03*
X1080511Y1500984D03*
X1252825Y1066535D03*
Y1263386D03*
X1267125Y1052235D03*
X1257013Y1056423D03*
Y1076647D03*
X1267125Y1080835D03*
Y1249086D03*
X1257013Y1253274D03*
Y1273498D03*
X1267125Y1277686D03*
X1277237Y1056423D03*
Y1076647D03*
X1281425Y1066535D03*
X1277237Y1253274D03*
X1281425Y1263386D03*
X1277237Y1273498D03*
X1477879Y1056423D03*
X1473691Y1066535D03*
X1477879Y1076647D03*
Y1253274D03*
X1473691Y1263386D03*
X1477879Y1273498D03*
X1498103Y1056423D03*
X1487991Y1052235D03*
X1498103Y1076647D03*
X1487991Y1080835D03*
X1498103Y1253274D03*
X1487991Y1249086D03*
Y1277686D03*
X1498103Y1273498D03*
X1502291Y1066535D03*
Y1263386D03*
X1709912Y1066535D03*
Y1263386D03*
X1724212Y1052235D03*
X1714100Y1056423D03*
Y1076647D03*
X1724212Y1080835D03*
Y1249086D03*
X1714100Y1253274D03*
Y1273498D03*
X1724212Y1277686D03*
X1734324Y1056423D03*
Y1076647D03*
X1738512Y1066535D03*
X1734324Y1253274D03*
X1738512Y1263386D03*
X1734324Y1273498D03*
G54D42*
X710406Y-26826D03*
Y-36826D03*
D03*
Y-26826D03*
X735406D03*
Y-36826D03*
D03*
Y-26826D03*
X830406Y-76006D03*
D03*
Y-66006D03*
D03*
X855406Y-76006D03*
D03*
Y-66006D03*
D03*
X939542Y-36798D03*
Y-26798D03*
D03*
Y-36798D03*
X964386Y-75978D03*
D03*
Y-65978D03*
D03*
X964542Y-36798D03*
Y-26798D03*
D03*
Y-36798D03*
X989386Y-75978D03*
D03*
Y-65978D03*
D03*
X993906Y-46826D03*
Y-36826D03*
D03*
Y-26826D03*
X1018906Y-46826D03*
Y-36826D03*
D03*
Y-26826D03*
X1063906Y-76006D03*
Y-86006D03*
Y-76006D03*
Y-66006D03*
X1088906Y-76006D03*
Y-86006D03*
Y-76006D03*
Y-66006D03*
X1217686Y-85978D03*
Y-75978D03*
D03*
Y-65978D03*
X1223042Y-46928D03*
Y-36928D03*
Y-26928D03*
Y-36928D03*
X1242686Y-85978D03*
Y-75978D03*
D03*
Y-65978D03*
X1248042Y-46928D03*
Y-36928D03*
Y-26928D03*
Y-36928D03*
X1280406Y-46956D03*
Y-36956D03*
D03*
Y-26956D03*
X1305406Y-46956D03*
Y-36956D03*
D03*
Y-26956D03*
X1320406Y-76006D03*
Y-86006D03*
Y-76006D03*
Y-66006D03*
X1345406Y-76006D03*
Y-86006D03*
Y-76006D03*
Y-66006D03*
X1474186Y-85978D03*
Y-75978D03*
D03*
Y-65978D03*
X1499186Y-85978D03*
Y-75978D03*
D03*
Y-65978D03*
X1509542Y-47058D03*
Y-37058D03*
Y-27058D03*
Y-37058D03*
X1534542Y-47058D03*
Y-37058D03*
Y-27058D03*
Y-37058D03*
X1564906Y-47086D03*
Y-37086D03*
D03*
Y-27086D03*
X1574906Y-76006D03*
Y-86006D03*
Y-76006D03*
Y-66006D03*
X1589906Y-47086D03*
Y-37086D03*
D03*
Y-27086D03*
X1599906Y-76006D03*
Y-86006D03*
Y-76006D03*
Y-66006D03*
X1728686Y-85978D03*
Y-75978D03*
D03*
Y-65978D03*
X1753686Y-85978D03*
Y-75978D03*
D03*
Y-65978D03*
X1794042Y-47188D03*
Y-37188D03*
Y-27188D03*
Y-37188D03*
X1819042Y-47188D03*
Y-37188D03*
Y-27188D03*
Y-37188D03*
G54D10*
X3704Y5374D03*
X3017Y24773D03*
Y44773D03*
Y64773D03*
Y84773D03*
Y104773D03*
Y124773D03*
Y144773D03*
Y164773D03*
Y184773D03*
Y204773D03*
Y224773D03*
Y244773D03*
Y264773D03*
Y284773D03*
Y304773D03*
X3221Y324773D03*
X3035Y978036D03*
Y998036D03*
Y1018036D03*
Y1038036D03*
Y1058036D03*
Y1078036D03*
Y1098036D03*
Y1118036D03*
Y1138036D03*
Y1158036D03*
Y1178036D03*
Y1198036D03*
Y1238036D03*
Y1258036D03*
Y1278036D03*
Y1298036D03*
Y1318036D03*
Y1338036D03*
Y1358036D03*
Y1378036D03*
Y1398036D03*
Y1418036D03*
Y1438036D03*
Y1458036D03*
Y1478036D03*
Y1498036D03*
Y1538036D03*
Y1558036D03*
X15972Y3000D03*
X10971Y333342D03*
X17964Y349298D03*
Y369298D03*
Y389298D03*
Y409298D03*
Y429298D03*
Y449298D03*
Y469298D03*
Y489298D03*
Y509298D03*
Y529298D03*
Y549298D03*
Y569298D03*
Y589298D03*
Y609298D03*
Y629298D03*
Y649298D03*
Y669298D03*
Y689298D03*
Y709298D03*
Y729298D03*
Y749298D03*
Y769298D03*
Y789298D03*
Y809298D03*
Y829298D03*
Y849298D03*
Y869298D03*
Y889298D03*
Y909298D03*
Y929298D03*
X9554Y961954D03*
X17964Y949298D03*
X6161Y1075991D03*
X6108Y1070611D03*
Y1065318D03*
X6059Y1091964D03*
X6055Y1086546D03*
X6053Y1081305D03*
X8042Y1522199D03*
X7922Y1532494D03*
X26956Y4469D03*
X28317Y24773D03*
Y44773D03*
X35638Y53597D03*
X36692Y641817D03*
X27934Y1204311D03*
X30934D03*
X27934Y1215511D03*
X30934D03*
X27934Y1212711D03*
Y1209911D03*
Y1207111D03*
X30934Y1212711D03*
Y1209911D03*
Y1207111D03*
X21544Y1479662D03*
X33536Y1467485D03*
X21544Y1489648D03*
X42192Y641817D03*
X51449Y822718D03*
X47949D03*
X44960Y1190619D03*
X49638Y1203884D03*
X40996Y1467703D03*
X40195Y1511279D03*
X55638Y53597D03*
X66371Y482134D03*
Y484634D03*
X60233Y521804D03*
X68202Y522129D03*
X60233Y524304D03*
X56540Y531378D03*
Y528878D03*
X68202Y527129D03*
Y524629D03*
Y529629D03*
X62789Y608311D03*
X66510Y628242D03*
X60849Y826818D03*
X64649D03*
X58949Y821018D03*
X64849Y840418D03*
X60249D03*
X74432Y5374D03*
X73745Y24773D03*
Y44773D03*
X73509Y110445D03*
Y115401D03*
X83911Y117557D03*
X80660Y103783D03*
X73509Y129574D03*
Y124618D03*
X83911Y122513D03*
Y131731D03*
Y136687D03*
X69816Y475946D03*
Y478446D03*
X78033Y478586D03*
Y481086D03*
Y476086D03*
Y483586D03*
X72549Y838818D03*
X93334Y3000D03*
X95943Y377953D03*
X113334Y3000D03*
X129318Y4469D03*
X130679Y24773D03*
Y44773D03*
X138000Y53597D03*
X146196Y390223D03*
X138194Y397335D03*
X146196Y395179D03*
Y404396D03*
Y409352D03*
X138194Y402291D03*
X135794Y416465D03*
Y411509D03*
X146196Y418569D03*
Y423525D03*
X135794Y425682D03*
Y430638D03*
X146196Y432743D03*
Y437699D03*
X135794Y439855D03*
Y444811D03*
Y468609D03*
Y473565D03*
X146196Y489895D03*
X135794Y487738D03*
X146196Y480677D03*
Y475721D03*
X135794Y482782D03*
X146196Y494851D03*
X135794Y512743D03*
Y517699D03*
X146196Y519855D03*
X135794Y526916D03*
Y531872D03*
X146196Y524811D03*
Y538984D03*
Y534028D03*
X158000Y53597D03*
X176794Y5374D03*
X176107Y24773D03*
Y44773D03*
X195697Y3000D03*
X183022Y103783D03*
X215697Y3000D03*
X231681Y4469D03*
X229745Y1446675D03*
X224753D03*
Y1462631D03*
X229745Y1457675D03*
X224753D03*
X229745Y1451631D03*
Y1462631D03*
X224753Y1451631D03*
X233042Y24773D03*
Y44773D03*
X240363Y53597D03*
X260363D03*
X279156Y5374D03*
X278469Y24773D03*
Y44773D03*
X265945Y440098D03*
Y437598D03*
Y435098D03*
Y432598D03*
Y430098D03*
X294959Y11097D03*
X285384Y103783D03*
X298059Y3000D03*
X301943Y332017D03*
X318059Y3000D03*
X318497Y466528D03*
Y471484D03*
X328899Y473640D03*
Y487813D03*
Y478596D03*
X318497Y480701D03*
Y485657D03*
X328899Y492769D03*
Y517774D03*
X318497Y510661D03*
Y515617D03*
X328899Y522730D03*
X318497Y524835D03*
X328899Y536903D03*
Y531947D03*
X318497Y529791D03*
X328899Y572769D03*
X318497Y565657D03*
Y560701D03*
X328899Y567813D03*
X318497Y579830D03*
Y574874D03*
X328899Y581987D03*
X318497Y589047D03*
X328899Y586943D03*
X318497Y594003D03*
X328899Y596160D03*
X318497Y603221D03*
X328899Y601116D03*
Y610333D03*
X318497Y608177D03*
X328899Y615289D03*
X334043Y4469D03*
X335404Y24773D03*
Y44773D03*
X342725Y53597D03*
X348737Y375386D03*
X354486Y377173D03*
X357173Y392183D03*
X357218Y396866D03*
X361234Y402867D03*
X358042Y442518D03*
Y439718D03*
X362725Y53597D03*
X361767Y392228D03*
X376992Y395248D03*
X368587Y409016D03*
X364551Y409032D03*
X361811Y396866D03*
X375919Y449118D03*
Y446318D03*
X367919Y449118D03*
Y446318D03*
X376099Y458309D03*
Y454309D03*
Y462309D03*
X369282Y468088D03*
Y465288D03*
X367816Y1310586D03*
Y1315542D03*
X388059Y3000D03*
X381518Y5374D03*
X388487Y24069D03*
X380831Y24773D03*
X383612Y30618D03*
X380831Y44773D03*
X387746Y103783D03*
X389237Y371070D03*
X385237Y370976D03*
X396373Y407104D03*
X385584Y450041D03*
Y452841D03*
Y455641D03*
X387587Y1296675D03*
X387644Y1302089D03*
X389458Y1365466D03*
X389188Y1369033D03*
X388600Y1395500D03*
X389985Y1405762D03*
X408059Y3000D03*
X396373Y409904D03*
X395577Y455641D03*
Y450041D03*
Y452841D03*
X397315Y479560D03*
X400914Y762675D03*
X408300Y755487D03*
X407965Y770196D03*
X408400Y795200D03*
Y792200D03*
X406600Y789000D03*
X402376Y842677D03*
X399876D03*
X402376Y850677D03*
X399876D03*
X395959Y1352153D03*
X403029Y1379716D03*
X403111Y1384920D03*
X408212Y1379695D03*
X394657Y1377875D03*
X403111Y1390103D03*
X408212Y1390083D03*
X410152Y1410928D03*
X398112Y1403741D03*
X415453Y455039D03*
X419040Y533690D03*
Y528390D03*
Y530990D03*
Y536290D03*
Y538890D03*
X423266Y631438D03*
X420266D03*
X417666D03*
X420266Y637038D03*
Y634238D03*
X417666Y637038D03*
Y634238D03*
X423266Y637038D03*
Y634238D03*
Y642638D03*
X420266D03*
X417666D03*
X423266Y639838D03*
X420266D03*
X417666D03*
X415696Y762466D03*
X424649Y842644D03*
X422149D03*
Y850644D03*
X424649D03*
X422149Y858644D03*
X424649D03*
X414280Y1362561D03*
X413437Y1379736D03*
Y1384899D03*
X413395Y1390062D03*
X428059Y3000D03*
X433724Y433975D03*
X432310Y436164D03*
X428740Y533690D03*
X442704Y533790D03*
X428740Y528390D03*
Y530990D03*
X442704Y528490D03*
Y531090D03*
X428740Y536290D03*
Y538890D03*
X442704Y536390D03*
Y538990D03*
X436369Y622883D03*
X441612Y631011D03*
X435881Y1394934D03*
Y1398800D03*
X448059Y3000D03*
X452404Y533690D03*
Y528390D03*
Y530990D03*
Y536290D03*
Y538890D03*
X468059Y3000D03*
X468850Y537507D03*
X461849Y668016D03*
X459349D03*
X466849D03*
X469349D03*
X464349D03*
X469349Y678016D03*
X466849D03*
X459349D03*
X461849D03*
X464349D03*
X484043Y4469D03*
X485404Y24773D03*
Y44773D03*
X482193Y472784D03*
Y468784D03*
Y476784D03*
X484341Y700528D03*
Y705484D03*
X492725Y53597D03*
X499278Y641817D03*
X493778D03*
X512725Y53597D03*
X523457Y482134D03*
Y484634D03*
X517319Y521804D03*
X513626Y528578D03*
Y531378D03*
X517319Y524304D03*
X519875Y608311D03*
X523596Y628242D03*
X531518Y5374D03*
X530831Y24773D03*
Y44773D03*
X537747Y103783D03*
X535119Y483886D03*
Y481086D03*
Y478586D03*
X526902Y478446D03*
Y475946D03*
X535119Y476086D03*
X525288Y522129D03*
Y524629D03*
Y527129D03*
Y529929D03*
X542275Y760782D03*
X532449Y782389D03*
X534672Y785037D03*
X536641Y838649D03*
X550421Y3000D03*
X542599Y782389D03*
X542546Y784911D03*
X554357Y784889D03*
X551524D03*
X570421Y3000D03*
X562231Y784911D03*
X558294D03*
X560263Y829989D03*
X568503Y936807D03*
X565003D03*
X586405Y4469D03*
X587766Y24773D03*
Y44773D03*
X583501Y800831D03*
X577903Y940907D03*
X581703D03*
X576003Y935107D03*
X581903Y954507D03*
X577303D03*
X595087Y53597D03*
X603282Y390223D03*
Y395179D03*
Y404396D03*
Y409352D03*
X595280Y402291D03*
Y397335D03*
X592880Y416465D03*
Y411509D03*
X603282Y418569D03*
Y423525D03*
X592880Y425682D03*
X603282Y432743D03*
Y437699D03*
X592880Y439855D03*
Y430638D03*
Y444811D03*
Y468609D03*
Y473565D03*
X603282Y489895D03*
X592880Y487738D03*
X603282Y480677D03*
Y475721D03*
X592880Y482782D03*
X603282Y494851D03*
X592880Y517699D03*
X603282Y519855D03*
X592880Y526916D03*
Y531872D03*
X603282Y524811D03*
Y538984D03*
Y534028D03*
X589603Y952907D03*
X615087Y53597D03*
X633248Y44884D03*
X640109Y103783D03*
X690073Y44662D03*
X697387Y53619D03*
X717387D03*
X723031Y440098D03*
Y437598D03*
Y435098D03*
Y432598D03*
Y430098D03*
X736242Y5374D03*
X735555Y24773D03*
Y44773D03*
X742471Y103783D03*
X755145Y3000D03*
X759029Y332017D03*
X775145Y3000D03*
X775584Y466528D03*
X775583Y471484D03*
Y480701D03*
Y485657D03*
Y515617D03*
Y510661D03*
Y524835D03*
Y529791D03*
Y560701D03*
Y565657D03*
Y579830D03*
Y574874D03*
Y589047D03*
Y594003D03*
Y603221D03*
Y608177D03*
X791129Y4469D03*
X792490Y24773D03*
Y44773D03*
X799811Y53597D03*
X785985Y473640D03*
Y487813D03*
Y478596D03*
Y492769D03*
Y517774D03*
Y522730D03*
Y531947D03*
Y536903D03*
Y572769D03*
Y567813D03*
Y581987D03*
Y586943D03*
Y601116D03*
Y596160D03*
Y615289D03*
Y610333D03*
X806318Y1401661D03*
X806874Y1447457D03*
X812474D03*
X806874Y1452587D03*
Y1457717D03*
X812474D03*
X815096Y1464387D03*
X812009Y1473432D03*
Y1470432D03*
X815096Y1467387D03*
X812096Y1479587D03*
Y1476587D03*
X815096Y1473387D03*
Y1479587D03*
Y1476587D03*
Y1470387D03*
X819811Y53597D03*
X829791Y839020D03*
X825721Y836666D03*
X823234Y867680D03*
X825774Y895553D03*
X816648Y1377608D03*
X817974Y1447457D03*
Y1452587D03*
Y1457717D03*
X818096Y1464387D03*
X821096D03*
X818096Y1473387D03*
X821096D03*
X824096D03*
X818096Y1479587D03*
X821096D03*
X824096D03*
X818096Y1476587D03*
X821096D03*
X824096D03*
X818096Y1467387D03*
Y1470387D03*
X821096D03*
Y1467387D03*
X824096D03*
Y1470387D03*
X838606Y5374D03*
X837919Y24773D03*
Y44773D03*
X844833Y103783D03*
X833185Y456309D03*
Y452309D03*
Y448309D03*
X850145Y3000D03*
X857973Y404867D03*
X862522Y400229D03*
X862566Y404867D03*
X857928Y400184D03*
X862020Y410899D03*
X862882Y468791D03*
Y465991D03*
X854882D03*
Y468791D03*
X861468Y491303D03*
X859071Y1447459D03*
X864671D03*
X859071Y1452589D03*
Y1457719D03*
X864671D03*
X864644Y1464759D03*
X861644D03*
X855644D03*
X858644D03*
Y1467759D03*
X855644Y1470759D03*
X858644D03*
X864644Y1467759D03*
Y1470759D03*
X861644Y1467759D03*
Y1470759D03*
X855644Y1467759D03*
Y1473759D03*
X858644D03*
X864644D03*
X861644D03*
X855644Y1476759D03*
X858644D03*
X864644D03*
X861644D03*
X872736Y383125D03*
X872318Y408589D03*
X866128Y417532D03*
X869342Y417399D03*
X880910Y471982D03*
Y469182D03*
Y466382D03*
X870882Y465991D03*
Y468791D03*
X878610Y747171D03*
X871294Y771809D03*
X871624Y1213314D03*
X874624D03*
X871624Y1221714D03*
Y1218914D03*
Y1216114D03*
X874624Y1221714D03*
Y1218914D03*
Y1216114D03*
X871624Y1224514D03*
X874624D03*
X870171Y1447459D03*
Y1452589D03*
Y1457719D03*
X867644Y1464759D03*
X870644D03*
X867644Y1467759D03*
X870644D03*
X867644Y1470759D03*
X870644D03*
X867644Y1473759D03*
X870644D03*
X867644Y1476759D03*
X870644D03*
X884736Y383125D03*
X893736D03*
X888736D03*
X891699Y420445D03*
Y423245D03*
X890903Y469182D03*
Y471982D03*
Y466382D03*
X896431Y534093D03*
X897118Y857891D03*
Y864189D03*
Y854742D03*
X893968Y864189D03*
Y857891D03*
Y854742D03*
X897118Y873638D03*
Y870488D03*
Y867338D03*
X893968Y870488D03*
Y873638D03*
Y867338D03*
X887669Y876787D03*
X888650Y1199622D03*
X893328Y1212887D03*
X912278Y343881D03*
X910779Y471380D03*
X903431Y534093D03*
X912462Y695770D03*
X912864Y848442D03*
Y845293D03*
Y842143D03*
X909714Y845293D03*
Y842143D03*
X900267Y864189D03*
X909714Y854742D03*
X906565Y857891D03*
X909714D03*
X906565Y864189D03*
X909714D03*
X906565Y854742D03*
X900267Y857891D03*
Y854742D03*
X912864Y851592D03*
Y857891D03*
Y854742D03*
X909714Y873638D03*
Y870488D03*
X906565Y873638D03*
Y870488D03*
Y867338D03*
X900267Y873638D03*
Y870488D03*
Y867338D03*
X909714D03*
X912171Y1447459D03*
X906671D03*
X901071D03*
X912171Y1457719D03*
Y1452589D03*
X906671Y1457719D03*
X901071D03*
Y1452589D03*
X908370Y1464583D03*
X905370D03*
X899370D03*
X902370D03*
X911370D03*
X905370Y1476583D03*
X908370D03*
X902370D03*
X899370D03*
X905370Y1473583D03*
X908370D03*
X902370D03*
X899370D03*
X902370Y1467583D03*
X899370Y1470583D03*
X902370D03*
X908370Y1467583D03*
Y1470583D03*
X905370Y1467583D03*
Y1470583D03*
X899370Y1467583D03*
X911370Y1476583D03*
Y1473583D03*
Y1467583D03*
Y1470583D03*
X930145Y3000D03*
X921847Y346622D03*
X927636Y452505D03*
X929050Y450316D03*
X928612Y835844D03*
X922313Y851592D03*
X929611Y858669D03*
X914370Y1464583D03*
Y1476583D03*
Y1473583D03*
Y1467583D03*
Y1470583D03*
X941129Y4469D03*
X942490Y24773D03*
Y44773D03*
X931620Y584417D03*
X931594Y599420D03*
X931647Y593271D03*
X931578Y590669D03*
X933810Y972433D03*
X935601Y1221714D03*
Y1218914D03*
Y1216114D03*
Y1213314D03*
X938601Y1221714D03*
Y1218914D03*
Y1216114D03*
Y1213314D03*
X935601Y1224514D03*
X938601D03*
X949811Y53597D03*
X956365Y641817D03*
X950865D03*
X950567Y927654D03*
X952627Y1199622D03*
X957305Y1212887D03*
X969811Y53597D03*
X976763Y307303D03*
X969623Y405614D03*
X963577Y426391D03*
X974406Y521804D03*
Y524304D03*
X970713Y531378D03*
Y528878D03*
X976962Y608311D03*
X980683Y628242D03*
X972278Y934429D03*
X988606Y5374D03*
X987919Y24773D03*
Y44773D03*
X994833Y103783D03*
X993132Y310942D03*
X993243Y321325D03*
X987055Y320273D03*
X993920Y335454D03*
X993420Y337954D03*
X992206Y478586D03*
Y481086D03*
Y483886D03*
X980544Y482134D03*
Y484634D03*
X992206Y476086D03*
X983989Y475946D03*
Y478446D03*
X982375Y522129D03*
Y527129D03*
Y524629D03*
Y529929D03*
X1007508Y3000D03*
X1004635Y300276D03*
X1008635D03*
X998667Y322239D03*
X1000420Y348954D03*
X1010119Y933822D03*
X1006619D03*
X1013683Y-44304D03*
Y-39348D03*
Y-29348D03*
Y-34304D03*
X1027508Y3000D03*
X1021895Y771974D03*
X1019519Y937922D03*
X1023319D03*
X1017619Y932122D03*
X1023519Y951522D03*
X1018919D03*
X1043492Y4469D03*
X1041496Y300276D03*
X1031354Y322905D03*
X1031219Y949922D03*
X1044853Y24773D03*
Y44773D03*
X1052174Y53597D03*
X1046674Y340031D03*
X1045966Y346808D03*
X1052367Y402291D03*
Y397335D03*
X1049967Y416465D03*
Y411509D03*
Y425682D03*
Y439855D03*
Y430638D03*
Y444811D03*
Y468609D03*
Y473565D03*
Y487738D03*
Y482782D03*
Y512743D03*
Y517699D03*
Y526916D03*
Y531872D03*
X1072174Y53597D03*
X1060369Y390223D03*
Y395179D03*
Y404396D03*
Y409352D03*
Y418569D03*
Y423525D03*
Y432743D03*
Y437699D03*
Y489895D03*
Y480677D03*
Y475721D03*
Y494851D03*
Y519855D03*
Y524811D03*
Y538984D03*
Y534028D03*
X1083683Y-78528D03*
Y-83484D03*
Y-73484D03*
Y-68528D03*
X1090280Y44773D03*
X1083483Y1523433D03*
X1097195Y103783D03*
X1147214Y44773D03*
X1154535Y53597D03*
X1174535D03*
X1176858Y306534D03*
X1180118Y430098D03*
Y440098D03*
Y437598D03*
Y435098D03*
Y432598D03*
X1193330Y5374D03*
X1192643Y24773D03*
Y44773D03*
X1199557Y103783D03*
X1192500Y322400D03*
X1199615Y950670D03*
X1201794Y985289D03*
X1212232Y3000D03*
X1221337Y332017D03*
X1232232Y3000D03*
X1232670Y466528D03*
Y471484D03*
Y480701D03*
Y485657D03*
Y515617D03*
Y510661D03*
Y524835D03*
Y529791D03*
Y565657D03*
Y560701D03*
Y579830D03*
Y589047D03*
Y574874D03*
Y603221D03*
Y594003D03*
Y608177D03*
X1248216Y4469D03*
X1249577Y24773D03*
Y44773D03*
X1243072Y473640D03*
Y487813D03*
Y478596D03*
Y492769D03*
Y522730D03*
Y517774D03*
Y536903D03*
Y531947D03*
Y567813D03*
Y572769D03*
Y586943D03*
Y581987D03*
Y601116D03*
Y596160D03*
Y610333D03*
Y615289D03*
X1256898Y53597D03*
X1266219Y374300D03*
X1268659Y377173D03*
X1276898Y53597D03*
X1275940Y392228D03*
X1271346Y392183D03*
X1275407Y402867D03*
X1271391Y396866D03*
X1275984D03*
X1282760Y409016D03*
X1278724Y409032D03*
X1272215Y442518D03*
Y439718D03*
X1282092Y449118D03*
Y446318D03*
X1283455Y468088D03*
Y465288D03*
X1300183Y-44434D03*
Y-29478D03*
Y-34434D03*
Y-39478D03*
X1302232Y3000D03*
X1295692Y5374D03*
X1303229Y23274D03*
X1295005Y24773D03*
X1297785Y30618D03*
X1295005Y44773D03*
X1301919Y103783D03*
X1303158Y371043D03*
X1299410Y370976D03*
X1291165Y395248D03*
X1290092Y449118D03*
Y446318D03*
X1299757Y450041D03*
Y452841D03*
Y455641D03*
X1290272Y458309D03*
Y454309D03*
Y462309D03*
X1310546Y409904D03*
Y407104D03*
X1309750Y455641D03*
Y450041D03*
Y452841D03*
X1311488Y479560D03*
X1309856Y899161D03*
X1305761D03*
X1313756D03*
X1322232Y3000D03*
X1320903Y370995D03*
X1333331Y370905D03*
X1329064Y370951D03*
X1329626Y455039D03*
X1340183Y-83484D03*
Y-78528D03*
Y-68528D03*
Y-73484D03*
X1342232Y3000D03*
X1338287Y370905D03*
X1347897Y433975D03*
X1346483Y436164D03*
X1362232Y3000D03*
X1382232D03*
X1373748Y397758D03*
X1375375Y428995D03*
X1398216Y4469D03*
X1399577Y24773D03*
Y44773D03*
X1397550Y390484D03*
X1387814Y397136D03*
X1389295Y408443D03*
X1386809Y414173D03*
X1388788Y428348D03*
X1406898Y53597D03*
X1416830Y407134D03*
X1411400Y398032D03*
X1413889Y415642D03*
X1413452Y641817D03*
X1407952D03*
X1426898Y53597D03*
X1431493Y521804D03*
X1427800Y528578D03*
X1431493Y524304D03*
X1427800Y531378D03*
X1422176Y1491198D03*
X1423806Y1524252D03*
X1445692Y5374D03*
X1445005Y24773D03*
Y44773D03*
X1440568Y369566D03*
X1449619Y363290D03*
X1438588Y380589D03*
X1437631Y482134D03*
Y484634D03*
X1449293Y476086D03*
X1441076Y475946D03*
Y478446D03*
X1449293Y478586D03*
Y481086D03*
Y483886D03*
X1439462Y522129D03*
Y529929D03*
Y527129D03*
Y524629D03*
X1434049Y608311D03*
X1437770Y628242D03*
X1464594Y3000D03*
X1462675Y14334D03*
X1451920Y103783D03*
X1455979Y391756D03*
X1458212Y403374D03*
X1473364Y410724D03*
X1472403Y417338D03*
X1469293Y428815D03*
X1484594Y3000D03*
X1498446Y912370D03*
X1497208Y909740D03*
X1500578Y4469D03*
X1501939Y24773D03*
Y44773D03*
X1509260Y53597D03*
X1509454Y402291D03*
Y397335D03*
X1507054Y416465D03*
Y411509D03*
Y425682D03*
Y439855D03*
Y430638D03*
Y444811D03*
Y468609D03*
Y473565D03*
Y487738D03*
Y482782D03*
Y517699D03*
Y512743D03*
Y526916D03*
Y531872D03*
X1507034Y888133D03*
X1507358Y909740D03*
X1507305Y912262D03*
X1501400Y966000D03*
X1529260Y53597D03*
X1517456Y390223D03*
Y395179D03*
Y404396D03*
Y409352D03*
Y418569D03*
Y423525D03*
Y432743D03*
Y437699D03*
Y489895D03*
Y480677D03*
Y475721D03*
Y494851D03*
Y519855D03*
Y538984D03*
Y524811D03*
Y534028D03*
X1516283Y912240D03*
X1519116D03*
X1523053Y912262D03*
X1525022Y957340D03*
X1547367Y44773D03*
X1554282Y103783D03*
X1594683Y-83484D03*
Y-78528D03*
Y-68528D03*
Y-73484D03*
X1584683Y-44564D03*
Y-29608D03*
Y-34564D03*
Y-39608D03*
X1604301Y44773D03*
X1611622Y53597D03*
X1631622D03*
X1637205Y440098D03*
Y437598D03*
Y435098D03*
Y432598D03*
Y430098D03*
X1650417Y5374D03*
X1649730Y24773D03*
Y44773D03*
X1656644Y103783D03*
X1669319Y3001D03*
X1673203Y332017D03*
X1689319Y3001D03*
X1689757Y466528D03*
Y471484D03*
Y480701D03*
Y485657D03*
Y515617D03*
Y510661D03*
Y524835D03*
Y529791D03*
Y565657D03*
Y560701D03*
Y589047D03*
Y574874D03*
Y579830D03*
Y603221D03*
Y594003D03*
Y608177D03*
X1705303Y4470D03*
X1706664Y24774D03*
Y44774D03*
X1700159Y473640D03*
Y487813D03*
Y478596D03*
Y492769D03*
Y517774D03*
Y522730D03*
Y536903D03*
Y531947D03*
Y572769D03*
Y567813D03*
Y586943D03*
Y581987D03*
Y601116D03*
Y596160D03*
Y610333D03*
Y615289D03*
X1713985Y53598D03*
X1725746Y377173D03*
X1723964Y370935D03*
X1733985Y53598D03*
X1733027Y392228D03*
X1728433Y392183D03*
X1739847Y409016D03*
X1735811Y409032D03*
X1732494Y402867D03*
X1728478Y396866D03*
X1733071D03*
X1729302Y439718D03*
Y442518D03*
X1739179Y449118D03*
Y446318D03*
X1740542Y468088D03*
Y465288D03*
X1752778Y5374D03*
X1752091Y24773D03*
Y44773D03*
X1756497Y370976D03*
X1748252Y395248D03*
X1756844Y450041D03*
Y452841D03*
Y455641D03*
X1747179Y449118D03*
Y446318D03*
X1747359Y454309D03*
Y458309D03*
Y462309D03*
X1765559Y3001D03*
X1759006Y103783D03*
X1760497Y371070D03*
X1767633Y409904D03*
Y407104D03*
X1766837Y450041D03*
Y452841D03*
Y455641D03*
X1768575Y479560D03*
X1773600Y888100D03*
X1773614Y895275D03*
X1773600Y902800D03*
X1786713Y455039D03*
X1788400Y888100D03*
X1781000Y888087D03*
X1788396Y895066D03*
X1788300Y902800D03*
X1780665Y902796D03*
X1781263Y964660D03*
X1784763D03*
X1779581Y1222200D03*
Y1219400D03*
Y1216600D03*
Y1213800D03*
X1782581Y1222200D03*
Y1219400D03*
Y1216600D03*
Y1213800D03*
X1779581Y1225000D03*
X1782581D03*
X1804984Y433975D03*
X1803570Y436164D03*
X1794163Y968760D03*
X1797963D03*
X1792263Y962960D03*
X1798163Y982360D03*
X1793563D03*
X1805863Y980760D03*
X1796607Y1200108D03*
X1801285Y1213373D03*
X1822983Y346053D03*
Y366053D03*
Y386053D03*
Y406053D03*
Y426053D03*
Y446053D03*
Y466053D03*
Y486053D03*
Y506053D03*
Y526053D03*
Y546053D03*
Y566053D03*
Y586053D03*
Y606053D03*
Y626053D03*
Y646053D03*
Y666053D03*
Y686053D03*
Y706053D03*
Y726053D03*
Y746053D03*
Y766053D03*
Y786053D03*
Y806053D03*
Y826053D03*
Y846053D03*
Y866053D03*
Y886053D03*
Y906053D03*
Y926053D03*
Y946053D03*
X1825559Y3001D03*
X1836543Y4470D03*
X1837904Y24774D03*
Y44774D03*
Y64774D03*
Y84774D03*
Y104774D03*
Y124774D03*
Y144774D03*
Y164774D03*
Y184774D03*
Y204774D03*
Y224774D03*
Y244774D03*
Y264774D03*
Y284774D03*
Y304774D03*
X1837728Y324733D03*
X1830094Y333210D03*
X1830472Y960970D03*
X1837937Y973244D03*
Y993244D03*
Y1013244D03*
Y1033244D03*
Y1053244D03*
Y1073244D03*
X1824733Y1102830D03*
X1837937Y1093244D03*
X1825832Y1097589D03*
X1837937Y1113244D03*
Y1133244D03*
Y1153244D03*
Y1173244D03*
Y1193244D03*
Y1213244D03*
Y1253244D03*
Y1273244D03*
Y1293244D03*
Y1313244D03*
Y1333244D03*
Y1353244D03*
Y1373244D03*
Y1393244D03*
Y1433244D03*
Y1453244D03*
Y1473244D03*
Y1493244D03*
Y1513244D03*
Y1533244D03*
Y1553244D03*
Y1573244D03*
G54D14*
X20408Y51296D03*
Y55296D03*
X9057Y138939D03*
X19184Y144728D03*
X15184D03*
X15520Y195176D03*
X18320D03*
X13020D03*
X10520D03*
X12880Y203393D03*
X10380D03*
X19068Y206838D03*
X16568D03*
X13606Y1476707D03*
X19365Y1494298D03*
X24316Y67527D03*
Y63527D03*
Y59527D03*
X23184Y144728D03*
X35650Y487982D03*
Y478982D03*
Y483982D03*
Y499982D03*
X25819Y531726D03*
Y536726D03*
Y552726D03*
Y540726D03*
X30410Y1218497D03*
Y1220997D03*
Y1234797D03*
Y1232297D03*
Y1227897D03*
Y1225397D03*
Y1241697D03*
Y1239197D03*
X25674Y1486291D03*
X32195Y1511279D03*
X32079Y1521641D03*
X31237Y1532096D03*
X46240Y109410D03*
X45988Y102323D03*
X46240Y116496D03*
X46931Y130670D03*
X49236Y121658D03*
X46932Y137756D03*
X49839Y546830D03*
X44195Y1511279D03*
X39237Y1532096D03*
X64098Y102323D03*
Y109410D03*
Y116496D03*
Y123583D03*
Y130670D03*
Y137756D03*
X69139Y236611D03*
X68841Y248891D03*
X66224Y473045D03*
X58224D03*
X53643Y472905D03*
X59670Y500086D03*
X64495Y527449D03*
X61695D03*
X60554Y1612002D03*
X66291Y1633801D03*
X74139Y236611D03*
X71639D03*
X71341Y248891D03*
X73841D03*
X74326Y480705D03*
X71995Y532749D03*
X74795D03*
X74291Y1633801D03*
X86291D03*
X119582Y102249D03*
X111582D03*
X115582D03*
X115382Y195176D03*
X112882D03*
X117882D03*
X115242Y203393D03*
X112742D03*
X120682Y195176D03*
X118930Y206838D03*
X121430D03*
X148602Y109410D03*
Y116496D03*
X148350Y102323D03*
X148774Y124576D03*
X149827Y130670D03*
X149822Y137756D03*
X166460Y116496D03*
Y109410D03*
Y102323D03*
Y123583D03*
Y130670D03*
Y137756D03*
X174001Y236611D03*
X176501D03*
X171501D03*
X176203Y248891D03*
X173703D03*
X171203D03*
X185169Y389154D03*
Y396240D03*
X186448Y404911D03*
X186589Y426299D03*
X185402Y412571D03*
X186900Y445847D03*
X185169Y467539D03*
Y474626D03*
X185430Y480828D03*
X187380Y498834D03*
X185169Y518760D03*
Y511673D03*
Y525847D03*
X191125Y602400D03*
Y598400D03*
Y594400D03*
Y606400D03*
Y614400D03*
X203591Y91951D03*
X213944Y102249D03*
X215244Y195176D03*
X215104Y203393D03*
X203280Y389154D03*
Y396240D03*
Y403327D03*
Y410413D03*
Y417500D03*
Y424586D03*
Y431673D03*
Y438760D03*
Y445847D03*
Y467539D03*
Y474626D03*
Y488799D03*
Y481713D03*
Y495886D03*
Y511673D03*
Y518760D03*
Y525847D03*
Y532933D03*
Y540020D03*
Y547106D03*
Y554193D03*
Y602205D03*
Y595118D03*
X221944Y102249D03*
X217944D03*
X220244Y195176D03*
X217744D03*
X223044D03*
X223792Y206838D03*
X221292D03*
X217604Y203393D03*
X228267Y392718D03*
Y408718D03*
Y400718D03*
Y404718D03*
Y412718D03*
X250964Y109410D03*
X250712Y102323D03*
X250964Y116496D03*
X251136Y124576D03*
X252189Y130670D03*
X252184Y137756D03*
X268822Y116496D03*
Y109410D03*
Y102323D03*
Y130670D03*
Y123583D03*
Y137756D03*
X276363Y236611D03*
X278863D03*
X273863D03*
X276065Y248891D03*
X273565D03*
X278565D03*
X274205Y466027D03*
X274347Y475262D03*
Y489435D03*
Y482666D03*
X274163Y495088D03*
X274205Y509626D03*
X274820Y522134D03*
X274898Y514608D03*
X275463Y529136D03*
X275302Y535677D03*
X274586Y565574D03*
X274205Y559665D03*
X274233Y574338D03*
X274332Y616358D03*
X292500Y410394D03*
Y403307D03*
X284295Y430760D03*
X284316Y433570D03*
X284132Y437072D03*
X284173Y439963D03*
X284417Y443180D03*
X284437Y454744D03*
X284379Y452018D03*
X292316Y458406D03*
Y465492D03*
Y472579D03*
Y479665D03*
Y486752D03*
Y493839D03*
Y523799D03*
Y516713D03*
Y509626D03*
Y537973D03*
Y530886D03*
Y559665D03*
Y566752D03*
Y573839D03*
Y588012D03*
Y580925D03*
Y595099D03*
Y602185D03*
Y616358D03*
Y609272D03*
X324306Y102249D03*
X320306D03*
X316306D03*
X322606Y195176D03*
X325406D03*
X320106D03*
X317606D03*
X323654Y206838D03*
X319966Y203393D03*
X317466D03*
X326154Y206838D03*
X319857Y321649D03*
X324291Y556775D03*
X353074Y102323D03*
X353326Y109410D03*
Y116496D03*
X353498Y124576D03*
X354551Y130670D03*
X354546Y137756D03*
X371184Y116496D03*
Y109410D03*
Y102323D03*
Y130670D03*
Y123583D03*
Y137756D03*
X376225Y236611D03*
X375927Y248891D03*
X373101Y779608D03*
X376300Y779800D03*
X370214Y959812D03*
Y967812D03*
X381225Y236611D03*
X378725D03*
X378427Y248891D03*
X380927D03*
X379800Y778000D03*
X387692Y790056D03*
X393547D03*
X386614Y868286D03*
X385512Y955356D03*
X390150Y955312D03*
Y959905D03*
X385467Y959950D03*
X409268Y408240D03*
X409386Y420393D03*
X400900Y755400D03*
Y770100D03*
X407193Y883566D03*
X396182Y955858D03*
X402682Y948536D03*
X402815Y951750D03*
X404004Y1198321D03*
Y1200821D03*
X407469Y1495035D03*
X407854Y1492118D03*
X406377Y1499142D03*
X411768Y408240D03*
X414268D03*
X411847Y424240D03*
X414386Y420393D03*
X411886D03*
X411847Y426740D03*
X415700Y755400D03*
Y770200D03*
X422430Y834800D03*
X422379Y867229D03*
X420661Y1119422D03*
X423141Y1113822D03*
Y1119422D03*
X418181Y1113822D03*
Y1119422D03*
X420661Y1113822D03*
X417469Y1200821D03*
Y1198321D03*
X439804Y536682D03*
Y539182D03*
X430934Y1200821D03*
Y1198321D03*
X430657Y1563562D03*
X446179Y447101D03*
X448726Y653288D03*
Y646480D03*
Y648980D03*
Y655788D03*
X450244Y1090268D03*
Y1093068D03*
X455269Y1119422D03*
X450309Y1113822D03*
Y1119422D03*
X452789Y1113822D03*
Y1119422D03*
X455269Y1113822D03*
X474307Y102249D03*
X470307D03*
X466307D03*
X470107Y195176D03*
X467607D03*
X472607D03*
X475407D03*
X473655Y206838D03*
X467467Y203393D03*
X469967D03*
X463104Y536582D03*
Y539082D03*
X476155Y206838D03*
X492736Y478982D03*
X482905Y531726D03*
X482737Y537215D03*
X482905Y552726D03*
Y540726D03*
X488728Y1119422D03*
X483768Y1113822D03*
X486248D03*
Y1119422D03*
X483768D03*
X488728Y1113822D03*
X477206Y1198321D03*
X490671D03*
Y1200821D03*
X477206D03*
X503075Y102323D03*
X503327Y109410D03*
Y116496D03*
X506653Y121652D03*
X504552Y130670D03*
X504547Y137756D03*
X493485Y439903D03*
X492736Y487982D03*
Y483982D03*
Y499982D03*
X506925Y546830D03*
X504136Y1198321D03*
Y1200821D03*
X521185Y116496D03*
Y109410D03*
Y102323D03*
Y130670D03*
Y123583D03*
Y137756D03*
X508729Y469905D03*
X521310Y470045D03*
X513310D03*
X516756Y500086D03*
X518781Y527449D03*
X521581D03*
X518812Y665867D03*
X515831Y1090568D03*
Y1093068D03*
X518376Y1113822D03*
Y1119422D03*
X520856Y1113822D03*
Y1119422D03*
X515896Y1113822D03*
Y1119422D03*
X526226Y236611D03*
X531226D03*
X528726D03*
X528428Y248891D03*
X530928D03*
X525928D03*
X531412Y480705D03*
X528612D03*
X529481Y532849D03*
X532281D03*
X533486Y664052D03*
X538442D03*
X524941Y661387D03*
X530796D03*
X572669Y102249D03*
X568669D03*
X572469Y195176D03*
X572329Y203393D03*
X567559Y812850D03*
X576669Y102249D03*
X574969Y195176D03*
X577769D03*
X578517Y206838D03*
X576017D03*
X605437Y102323D03*
X605689Y109410D03*
Y116496D03*
X605861Y124576D03*
X606914Y130670D03*
X606909Y137756D03*
X623547Y109410D03*
Y116496D03*
Y102323D03*
Y123583D03*
Y130670D03*
Y137756D03*
X633588Y236611D03*
X631088D03*
X628588D03*
X630790Y248891D03*
X633290D03*
X628290D03*
X642255Y389154D03*
Y396240D03*
X643534Y404911D03*
X642488Y412571D03*
X643675Y426299D03*
X643986Y445847D03*
X642255Y467539D03*
Y474626D03*
X642516Y480828D03*
X644466Y498834D03*
X642255Y518760D03*
Y511673D03*
Y525847D03*
X648211Y602400D03*
Y598400D03*
Y594400D03*
Y606400D03*
Y614400D03*
X660366Y389154D03*
Y403327D03*
Y410413D03*
Y396240D03*
Y417500D03*
Y424586D03*
Y431673D03*
Y438760D03*
Y445847D03*
Y467539D03*
Y474626D03*
Y488799D03*
Y481713D03*
Y495886D03*
Y511673D03*
Y518760D03*
Y525847D03*
Y532933D03*
Y540020D03*
Y554193D03*
Y547106D03*
Y602205D03*
Y595118D03*
X679031Y102249D03*
X672331Y195176D03*
X674831D03*
X680131D03*
X672191Y203393D03*
X674691D03*
X678379Y206838D03*
X680879D03*
X685353Y392718D03*
Y408718D03*
Y400718D03*
Y404718D03*
Y412718D03*
X707799Y102323D03*
X708051Y109410D03*
Y116496D03*
X708223Y124576D03*
X709276Y130670D03*
X709271Y137756D03*
X725909Y102323D03*
Y116496D03*
Y109410D03*
Y130670D03*
Y123583D03*
Y137756D03*
X733450Y236611D03*
X730950D03*
X733152Y248891D03*
X730652D03*
X731291Y466027D03*
X731433Y475262D03*
Y489435D03*
Y482666D03*
X731249Y495088D03*
X731984Y514608D03*
X731906Y522134D03*
X731291Y509626D03*
X732549Y529136D03*
X732388Y535677D03*
X731291Y559665D03*
X731672Y565574D03*
X731319Y574338D03*
X731418Y616358D03*
X735950Y236611D03*
X735652Y248891D03*
X749586Y410394D03*
Y403307D03*
X741259Y439963D03*
X741381Y430760D03*
X741402Y433570D03*
X741218Y437072D03*
X741503Y443180D03*
X741523Y454744D03*
X741465Y452018D03*
X749402Y458406D03*
Y465492D03*
Y472579D03*
Y479665D03*
Y486752D03*
Y493839D03*
Y523799D03*
Y516713D03*
Y509626D03*
Y537973D03*
Y530886D03*
Y559665D03*
Y566752D03*
Y573839D03*
Y588012D03*
Y580925D03*
Y602185D03*
Y595099D03*
Y609272D03*
Y616358D03*
X751140Y1581335D03*
X740640Y1586885D03*
X748924Y1617709D03*
X735878Y1617010D03*
X763040Y91951D03*
X781393Y102249D03*
X777393D03*
X773393D03*
X779693Y195176D03*
X777193D03*
X782493D03*
X774693D03*
X780741Y206838D03*
X783241D03*
X777053Y203393D03*
X774553D03*
X776943Y321649D03*
X778985Y442498D03*
X778881Y446510D03*
X779029Y450510D03*
X777033Y1595215D03*
X781545Y1602835D03*
X774658Y1601012D03*
X792564Y406410D03*
X784586Y421000D03*
Y418500D03*
Y413500D03*
Y416000D03*
X784665Y564843D03*
X787447Y1593586D03*
X791610Y1593708D03*
X810161Y102323D03*
X810413Y109410D03*
Y116496D03*
X810585Y124576D03*
X811638Y130670D03*
X811633Y137756D03*
X828271Y116496D03*
Y109410D03*
Y102323D03*
Y130670D03*
Y123583D03*
Y137756D03*
X835812Y236611D03*
X838312D03*
X833312D03*
X833014Y248891D03*
X838014D03*
X835514D03*
X867093Y570703D03*
Y582828D03*
Y558703D03*
Y562703D03*
Y566703D03*
Y578703D03*
X872440Y1230083D03*
Y1227583D03*
Y1234483D03*
Y1236983D03*
Y1243883D03*
Y1241383D03*
Y1248283D03*
Y1250783D03*
X889436Y715970D03*
X905094Y424581D03*
X902594D03*
X907594D03*
X905212Y436734D03*
X902712D03*
X907712D03*
X907173Y440581D03*
Y443081D03*
X909024Y578394D03*
Y574394D03*
X909714Y838994D03*
X931393Y102249D03*
X923393D03*
X927393D03*
X925359Y180347D03*
X927859D03*
X925219Y188564D03*
X927719D03*
X919606Y231000D03*
X919577Y245669D03*
Y233858D03*
X919682Y236921D03*
X919577Y259843D03*
Y255118D03*
X919729Y274580D03*
X930359Y180347D03*
X933159D03*
X931407Y192009D03*
X933907D03*
X941505Y463442D03*
X939827Y531104D03*
X939992Y536726D03*
Y540726D03*
Y552726D03*
X936417Y1234483D03*
Y1236983D03*
Y1230083D03*
Y1227583D03*
Y1243883D03*
Y1241383D03*
Y1248283D03*
Y1250783D03*
X956460Y-35982D03*
X953207Y-35996D03*
X956445Y-38497D03*
X953192Y-38511D03*
X950167Y-37191D03*
X960161Y102323D03*
X960413Y109410D03*
Y116496D03*
X961638Y130670D03*
X961633Y137756D03*
X950315Y464851D03*
X949823Y487982D03*
X949876Y478486D03*
X949823Y483982D03*
Y499982D03*
X978036Y-77691D03*
X978051Y-75176D03*
X975011Y-76371D03*
X978271Y109410D03*
Y102323D03*
Y116496D03*
Y130670D03*
Y123583D03*
X963360Y121459D03*
X978271Y137756D03*
X977150Y328472D03*
Y335472D03*
X967816Y472905D03*
X972397Y472954D03*
X973843Y500086D03*
X978668Y527449D03*
X975868D03*
X964012Y546830D03*
X978857Y1360945D03*
X981289Y-77677D03*
X981304Y-75162D03*
X985812Y236611D03*
X988312D03*
X983312D03*
X983014Y248891D03*
X988014D03*
X985514D03*
X980397Y473045D03*
X985699Y480705D03*
X988499D03*
X989068Y532949D03*
X986268D03*
X981857Y1360945D03*
X978944Y1413859D03*
X981944D03*
X1007611Y1561247D03*
Y1558247D03*
Y1555247D03*
Y1552247D03*
X1004611Y1561247D03*
Y1558247D03*
Y1555247D03*
Y1552247D03*
X1015402Y91951D03*
X1025755Y102249D03*
X1027055Y195176D03*
X1033755Y102249D03*
X1029755D03*
X1032055Y195176D03*
X1029555D03*
X1034855D03*
X1033103Y206838D03*
X1035603D03*
X1029415Y203393D03*
X1062523Y102323D03*
X1062775Y109410D03*
Y116496D03*
X1062947Y124576D03*
X1064000Y130670D03*
X1063995Y137756D03*
X1080633Y102323D03*
Y116496D03*
Y109410D03*
Y130670D03*
Y123583D03*
Y137756D03*
X1085674Y236611D03*
X1088174D03*
X1090674D03*
X1090376Y248891D03*
X1087876D03*
X1085376D03*
X1077855Y327478D03*
X1077252Y323521D03*
Y318565D03*
X1077855Y332434D03*
X1099342Y389154D03*
Y396240D03*
X1100621Y404911D03*
X1099575Y412571D03*
X1100762Y426299D03*
X1101073Y445847D03*
X1099342Y467539D03*
Y474626D03*
X1099603Y480828D03*
X1101553Y498834D03*
X1099342Y518760D03*
Y511673D03*
Y525847D03*
X1105298Y598400D03*
Y602400D03*
Y594400D03*
Y614400D03*
Y606400D03*
X1117764Y91951D03*
X1117453Y389154D03*
Y396240D03*
Y403327D03*
Y410413D03*
Y417500D03*
Y424586D03*
Y431673D03*
Y438760D03*
Y445847D03*
Y467539D03*
Y474626D03*
Y488799D03*
Y481713D03*
Y495886D03*
Y511673D03*
Y518760D03*
Y525847D03*
Y532933D03*
Y540020D03*
Y554193D03*
Y547106D03*
Y602205D03*
Y595118D03*
X1136117Y102249D03*
X1132117D03*
X1128117D03*
X1134417Y195176D03*
X1131917D03*
X1137217D03*
X1129417D03*
X1137965Y206838D03*
X1131777Y203393D03*
X1135465Y206838D03*
X1142440Y404718D03*
Y412718D03*
X1125287Y592897D03*
X1142440Y392718D03*
Y400718D03*
Y408718D03*
X1164885Y102323D03*
X1165137Y109410D03*
Y116496D03*
X1165309Y124576D03*
X1166362Y130670D03*
X1166357Y137756D03*
X1182995Y116496D03*
Y109410D03*
Y102323D03*
Y130670D03*
Y123583D03*
Y137756D03*
X1188036Y236611D03*
X1187738Y248891D03*
X1188378Y466027D03*
X1188520Y475262D03*
Y489435D03*
Y482666D03*
X1188336Y495088D03*
X1189071Y514608D03*
X1188993Y522134D03*
X1188378Y509626D03*
X1189475Y535677D03*
X1189636Y529136D03*
X1188378Y559665D03*
X1188759Y565574D03*
X1188406Y574338D03*
X1188505Y616358D03*
X1190536Y236611D03*
X1193036D03*
X1192738Y248891D03*
X1190238D03*
X1198468Y430760D03*
X1198489Y433570D03*
X1198305Y437072D03*
X1198346Y439963D03*
X1198552Y452018D03*
X1198590Y443180D03*
X1198610Y454744D03*
X1220126Y91951D03*
X1206673Y410394D03*
Y403307D03*
X1206489Y458406D03*
Y465492D03*
Y472579D03*
Y479665D03*
Y486752D03*
Y493839D03*
Y523799D03*
Y516713D03*
Y509626D03*
Y537973D03*
Y530886D03*
Y566752D03*
Y559665D03*
Y580925D03*
Y588012D03*
Y573839D03*
Y602185D03*
Y595099D03*
Y616358D03*
Y609272D03*
X1231336Y-87691D03*
X1234589Y-87777D03*
X1231351Y-85176D03*
X1234604Y-85262D03*
X1228311Y-86371D03*
X1236692Y-48727D03*
X1236707Y-46212D03*
X1233667Y-47421D03*
X1238479Y102249D03*
X1230479D03*
X1234479D03*
X1236779Y195176D03*
X1234279D03*
X1239579D03*
X1231779D03*
X1234139Y203393D03*
X1231639D03*
X1237827Y206838D03*
X1234100Y322924D03*
X1239945Y-48727D03*
X1239960Y-46212D03*
X1240327Y206838D03*
X1241752Y564843D03*
X1267499Y116496D03*
X1267247Y102323D03*
X1267499Y109410D03*
X1267671Y124576D03*
X1268724Y130670D03*
X1268719Y137756D03*
X1259500Y330000D03*
X1285357Y116496D03*
Y109410D03*
Y102323D03*
Y123583D03*
Y130670D03*
Y137756D03*
X1281834Y374839D03*
X1290398Y236611D03*
X1295398D03*
X1292898D03*
X1290100Y248891D03*
X1292600D03*
X1295100D03*
X1301500Y329000D03*
X1292731Y331820D03*
X1300400Y339619D03*
Y344575D03*
X1290066Y804246D03*
X1319000Y566500D03*
Y582500D03*
Y613000D03*
Y629000D03*
Y657500D03*
Y673500D03*
Y704500D03*
Y720500D03*
X1305412Y799061D03*
X1318178Y1198321D03*
Y1200821D03*
X1325941Y408240D03*
X1328441D03*
X1323441D03*
X1326059Y420393D03*
X1326020Y424240D03*
X1323559Y420393D03*
X1328559D03*
X1326020Y426740D03*
X1335802Y896011D03*
X1332355Y1113822D03*
Y1119422D03*
X1334835Y1113822D03*
Y1119422D03*
X1331643Y1200821D03*
Y1198321D03*
X1344768Y769675D03*
X1337315Y1113822D03*
Y1119422D03*
X1345108Y1200821D03*
Y1198321D03*
X1361039Y327099D03*
Y332055D03*
X1364039Y334973D03*
Y339929D03*
X1361039Y342847D03*
X1364039Y350721D03*
X1361039Y347803D03*
X1364039Y355677D03*
X1360352Y447101D03*
X1364148Y896011D03*
X1364418Y1090568D03*
Y1093068D03*
X1366963Y1119422D03*
Y1113822D03*
X1364483Y1119422D03*
Y1113822D03*
X1380480Y102249D03*
X1384480D03*
X1384280Y195176D03*
X1381780D03*
X1384140Y203393D03*
X1381640D03*
X1384253Y346826D03*
X1384447Y356871D03*
X1384174Y362641D03*
X1379896Y870814D03*
Y883413D03*
X1383046Y899161D03*
X1369443Y1119422D03*
Y1113822D03*
X1388480Y102249D03*
X1389580Y195176D03*
X1386780D03*
X1390328Y206838D03*
X1387828D03*
X1385943Y323222D03*
X1385971Y327688D03*
X1386143Y331982D03*
X1386057Y341200D03*
X1385971Y336791D03*
X1386286Y350218D03*
X1397079Y531726D03*
Y536726D03*
Y552726D03*
Y540726D03*
X1397942Y1119422D03*
X1400422D03*
Y1113822D03*
X1397942D03*
X1391380Y1200821D03*
Y1198321D03*
X1417248Y102323D03*
X1416347Y384373D03*
X1406910Y487982D03*
Y478982D03*
Y483982D03*
Y499982D03*
X1410000Y689000D03*
Y705000D03*
Y733000D03*
Y749000D03*
X1402902Y1119422D03*
Y1113822D03*
X1404845Y1198321D03*
Y1200821D03*
X1404239Y1547755D03*
X1403747Y1570433D03*
X1417500Y109410D03*
Y116496D03*
X1421700Y122900D03*
X1418725Y130670D03*
X1418720Y137756D03*
X1427484Y470045D03*
X1422903Y469905D03*
X1430930Y500086D03*
X1432955Y527449D03*
X1421099Y546830D03*
X1427000Y774500D03*
Y790500D03*
Y818500D03*
Y834500D03*
X1430005Y1090568D03*
Y1093068D03*
X1432550Y1119422D03*
Y1113822D03*
X1430070Y1119422D03*
Y1113822D03*
X1418310Y1198321D03*
Y1200821D03*
X1435358Y116496D03*
Y109410D03*
Y102323D03*
Y130670D03*
Y123583D03*
Y137756D03*
X1440399Y236611D03*
X1442899D03*
X1445399D03*
X1440101Y248891D03*
X1442601D03*
X1445101D03*
X1435484Y470045D03*
X1442786Y480705D03*
X1445586D03*
X1435755Y527449D03*
X1443555Y532949D03*
X1446355D03*
X1435030Y1119422D03*
Y1113822D03*
X1437293Y1546125D03*
X1436801Y1568803D03*
X1451215Y323193D03*
X1451330Y327588D03*
X1451272Y340971D03*
X1451344Y336620D03*
X1451300Y332225D03*
X1451387Y345609D03*
X1451186Y350447D03*
X1472489Y91951D03*
X1479500Y706500D03*
Y750500D03*
X1487836Y-87777D03*
X1491089D03*
X1487851Y-85262D03*
X1491104D03*
X1484811Y-86371D03*
X1490842Y102249D03*
X1486842D03*
X1482842D03*
X1486642Y195176D03*
X1489142D03*
X1484142D03*
X1491942D03*
X1492690Y206838D03*
X1490190D03*
X1484002Y203393D03*
X1486502D03*
X1484796Y320359D03*
X1484968Y325025D03*
X1484876Y329377D03*
X1488255Y342921D03*
X1484682Y338394D03*
X1497760Y336543D03*
X1487926Y347387D03*
X1496500Y792000D03*
Y836000D03*
X1500480Y295727D03*
X1523192Y-48857D03*
X1526445D03*
X1523207Y-46342D03*
X1526460D03*
X1520167Y-47451D03*
X1519610Y102323D03*
X1519862Y109410D03*
Y116496D03*
X1520034Y124576D03*
X1521087Y130670D03*
X1521082Y137756D03*
X1527876Y939439D03*
X1537720Y116496D03*
Y109410D03*
Y102323D03*
Y130670D03*
Y123583D03*
Y137756D03*
X1542761Y236611D03*
X1545261D03*
X1542463Y248891D03*
X1544963D03*
X1541534Y322850D03*
X1547761Y236611D03*
X1547463Y248891D03*
X1547972Y304906D03*
X1556151Y318596D03*
X1556294Y327814D03*
X1556437Y332022D03*
X1556380Y336917D03*
X1556498Y340958D03*
X1556353Y345636D03*
X1556429Y389154D03*
Y396240D03*
X1557708Y404911D03*
X1556662Y412571D03*
X1557849Y426299D03*
X1558160Y445847D03*
X1556429Y467539D03*
Y474626D03*
X1556690Y480828D03*
X1558640Y498834D03*
X1556429Y518760D03*
Y511673D03*
Y525847D03*
X1562385Y598400D03*
Y602400D03*
Y594400D03*
Y614400D03*
Y606400D03*
X1574851Y91951D03*
X1574845Y338843D03*
X1574540Y389154D03*
Y396240D03*
Y403327D03*
Y410413D03*
Y417500D03*
Y424586D03*
Y438760D03*
Y431673D03*
Y445847D03*
Y467539D03*
Y474626D03*
Y488799D03*
Y481713D03*
Y495886D03*
Y511673D03*
Y518760D03*
Y540020D03*
Y525847D03*
Y532933D03*
Y547106D03*
Y554193D03*
Y602205D03*
Y595118D03*
X1593204Y102249D03*
X1585204D03*
X1589204D03*
X1586504Y195176D03*
X1594304D03*
X1589004D03*
X1591504D03*
X1586364Y203393D03*
X1588864D03*
X1595052Y206838D03*
X1592552D03*
X1593290Y339876D03*
X1597006Y290417D03*
X1599527Y392718D03*
Y408718D03*
Y400718D03*
Y404718D03*
Y412718D03*
X1621972Y102323D03*
X1622224Y109410D03*
Y116496D03*
X1622396Y124576D03*
X1623449Y130670D03*
X1623444Y137756D03*
X1640082Y116496D03*
Y109410D03*
Y102323D03*
Y130670D03*
Y123583D03*
Y137756D03*
X1644825Y248891D03*
X1632230Y330400D03*
X1645123Y236611D03*
X1650123D03*
X1647623D03*
X1647325Y248891D03*
X1649825D03*
X1655555Y430760D03*
X1655576Y433570D03*
X1655392Y437072D03*
X1655433Y439963D03*
X1655677Y443180D03*
X1655697Y454744D03*
X1655639Y452018D03*
X1645465Y466027D03*
X1645607Y475262D03*
Y489435D03*
Y482666D03*
X1645423Y495088D03*
X1646158Y514608D03*
X1646080Y522134D03*
X1645465Y509626D03*
X1646562Y535677D03*
X1646723Y529136D03*
X1645465Y559665D03*
X1645846Y565574D03*
X1645493Y574338D03*
X1645592Y616358D03*
X1677213Y91951D03*
X1663760Y410394D03*
Y403307D03*
X1663576Y458406D03*
Y465492D03*
Y472579D03*
Y479665D03*
Y486752D03*
Y493839D03*
Y523799D03*
Y516713D03*
Y509626D03*
Y537973D03*
Y530886D03*
Y559665D03*
Y566752D03*
Y580925D03*
Y588012D03*
Y573839D03*
Y602185D03*
Y595099D03*
Y616358D03*
Y609272D03*
X1695566Y102249D03*
X1687566D03*
X1691566D03*
X1691366Y195176D03*
X1688866D03*
X1691226Y203393D03*
X1688726D03*
X1691117Y321649D03*
X1696666Y195176D03*
X1693866D03*
X1697414Y206838D03*
X1694914D03*
X1698839Y564843D03*
X1724334Y102323D03*
X1724586Y109410D03*
Y116496D03*
X1724758Y124576D03*
X1725811Y130670D03*
X1725806Y137756D03*
X1715705Y328692D03*
X1712734Y340534D03*
X1742336Y-87777D03*
X1739311Y-86371D03*
X1734826Y376499D03*
X1745589Y-87777D03*
X1742351Y-85262D03*
X1745604D03*
X1742444Y102323D03*
Y116496D03*
Y109410D03*
Y130670D03*
Y123583D03*
Y137756D03*
X1752485Y236611D03*
X1749985D03*
X1747485D03*
X1747187Y248891D03*
X1749687D03*
X1752187D03*
X1747561Y385161D03*
X1758583Y1581027D03*
X1750685Y1618504D03*
X1756422Y1640303D03*
X1770680Y926322D03*
X1763818Y926241D03*
X1765294Y1575434D03*
X1759092Y1588137D03*
X1767142Y1588219D03*
X1764422Y1640303D03*
X1779575Y91951D03*
X1790533Y303750D03*
X1783028Y408240D03*
X1785528D03*
X1780528D03*
X1783107Y424240D03*
X1780646Y420393D03*
X1785646D03*
X1783146D03*
X1783107Y426740D03*
X1780397Y1237469D03*
Y1230569D03*
Y1228069D03*
Y1234969D03*
Y1241869D03*
Y1244369D03*
Y1248769D03*
Y1251269D03*
X1776422Y1640303D03*
X1804667Y-47581D03*
X1804993Y297591D03*
X1807692Y-49001D03*
X1810945Y-48987D03*
X1807707Y-46486D03*
X1810960Y-46472D03*
X1817439Y447101D03*
G54D30*
X106586Y1204932D03*
X563673D03*
X1020434Y1205579D03*
X1477846Y1204932D03*
G54D36*
X190325Y368760D03*
Y455492D03*
Y503760D03*
Y583957D03*
Y636752D03*
X647411Y368760D03*
Y455492D03*
Y503760D03*
Y583957D03*
Y636752D03*
X1104498Y368760D03*
Y455492D03*
Y503760D03*
Y583957D03*
Y636752D03*
X1561585Y368760D03*
Y455492D03*
Y503760D03*
Y583957D03*
Y636752D03*
G54D40*
X515573Y692515D03*
X518299Y692384D03*
X520799D03*
X529493Y692443D03*
Y697443D03*
Y699943D03*
X529501Y702622D03*
X526993Y692443D03*
X529493Y694943D03*
X524493Y692443D03*
X1809078Y2165771D03*
X1806706Y2180760D03*
X1812366Y2063809D03*
X1822066Y2054109D03*
X1812366D03*
X1813087Y2087512D03*
X1825427Y2104853D03*
X1817378Y2165771D03*
X1815006Y2180760D03*
X1841295Y2065122D03*
X1832995D03*
X1833649Y2057507D03*
X1830872Y2083503D03*
X1840875Y2083215D03*
X1837649Y2072324D03*
X1829349D03*
X1833727Y2104853D03*
X1835862Y2121040D03*
X1833506Y2185252D03*
X1852032Y2052576D03*
X1854559Y2077931D03*
X1851762Y2121040D03*
X1854796Y2170548D03*
X1846496D03*
X1855978Y2185118D03*
X1847678D03*
X1859032Y2052576D03*
X1870505Y2064156D03*
X1860338Y2071384D03*
X1874505Y2078973D03*
X1860234Y2157701D03*
X1867072Y2174962D03*
X1864547Y2185020D03*
X1890039Y2066092D03*
X1878805Y2064156D03*
X1886128Y2075919D03*
X1882805Y2078973D03*
X1876497Y2070684D03*
X1884535Y2155415D03*
X1882972Y2174962D03*
X1882111Y2179074D03*
X1874932Y2180585D03*
X1881852Y2196600D03*
X1886699Y2183170D03*
X1876697D03*
X1905939Y2066092D03*
X1893118Y2054585D03*
X1905944Y2055424D03*
X1898342Y2062143D03*
X1901295Y2072745D03*
X1892835Y2155415D03*
X1902872Y2178531D03*
X1894572D03*
X1893087Y2168011D03*
X1896403Y2185019D03*
X1917195Y2072745D03*
X1917550Y2158451D03*
X1909250D03*
X1922010Y2151829D03*
X1913710D03*
X1921855Y2172152D03*
X1936295Y2074343D03*
X1935195Y2155918D03*
X1936377Y2163810D03*
X1924735Y2178131D03*
X1936212Y2173508D03*
X1930155Y2172152D03*
X1931738Y2182647D03*
X1923438D03*
X1941040Y2070124D03*
X1951095Y2155918D03*
X1946077Y2163810D03*
X1969128Y2161283D03*
X1959428D03*
X1969128Y2151583D03*
X1959428D03*
G54D48*
X909360Y230906D03*
Y274606D03*
G54D21*
X51043Y144095D03*
X57933Y66811D03*
X160295D03*
X153405Y144095D03*
X183435Y630650D03*
X190325Y374862D03*
X262657Y66811D03*
X255767Y144095D03*
X279360Y630650D03*
X286250Y374862D03*
X358129Y144095D03*
X365019Y66811D03*
X508130Y144095D03*
X515020Y66811D03*
X617382D03*
X610492Y144095D03*
X647411Y374862D03*
X640521Y630650D03*
X719744Y66811D03*
X712854Y144095D03*
X736446Y630650D03*
X743336Y374862D03*
X815216Y144095D03*
X822106Y66811D03*
X972106D03*
X965216Y144095D03*
X1074468Y66811D03*
X1067578Y144095D03*
X1104498Y374862D03*
X1097608Y630650D03*
X1169940Y144095D03*
X1176830Y66811D03*
X1200423Y374862D03*
X1193533Y630650D03*
X1272302Y144095D03*
X1279192Y66811D03*
X1429193D03*
X1422303Y144095D03*
X1531555Y66811D03*
X1524665Y144095D03*
X1561585Y374862D03*
X1554695Y630650D03*
X1627027Y144095D03*
X1633917Y66811D03*
X1657510Y374862D03*
X1650620Y630650D03*
X1736279Y66811D03*
X1729389Y144095D03*
G54D24*
X46248Y1760941D03*
Y1750941D03*
Y1806941D03*
Y1796941D03*
X143208Y1084547D03*
Y1092027D03*
X146948Y1077066D03*
Y1084547D03*
Y1092027D03*
X143208Y1095767D03*
X146948D03*
X143208Y1110728D03*
Y1118208D03*
X146948Y1110728D03*
Y1118208D03*
X146949Y1166830D03*
X154429Y1073326D03*
X161909D03*
X154429Y1092027D03*
X161909Y1077066D03*
X165649Y1080807D03*
Y1088287D03*
X161909D03*
Y1092027D03*
X154429Y1077066D03*
X158169Y1080807D03*
X150689D03*
X158169Y1084547D03*
X150689D03*
X158169Y1088287D03*
X154429D03*
X150689D03*
X165649Y1084547D03*
X158169Y1099507D03*
X150689D03*
X158169Y1103247D03*
X150689D03*
X161909Y1095767D03*
X165649Y1099507D03*
Y1103247D03*
X154429Y1106988D03*
X150689D03*
X154429Y1095767D03*
X158169Y1110728D03*
Y1114468D03*
X154429D03*
X150689D03*
X158169Y1129429D03*
X165649Y1166830D03*
Y1170570D03*
Y1178050D03*
Y1174310D03*
X163779Y1213582D03*
X160039D03*
X214271Y1114468D03*
X238582Y1078936D03*
X242322Y1082677D03*
X238582Y1097637D03*
X246062Y1254724D03*
X238582D03*
Y1250984D03*
X234842Y1247243D03*
X242322Y1243503D03*
Y1247243D03*
X246062Y1250984D03*
X249803Y1082677D03*
X257283D03*
X249803Y1101377D03*
X253543Y1250984D03*
Y1254724D03*
X249803Y1247243D03*
X253543Y1239763D03*
X249803D03*
X257283Y1247243D03*
X261023Y1250984D03*
Y1239763D03*
Y1254724D03*
X279724Y1082677D03*
Y1086417D03*
X275984Y1078936D03*
X264763Y1082677D03*
X275984Y1097637D03*
X274114Y1121948D03*
X277854Y1133169D03*
Y1125688D03*
X274114Y1204232D03*
X279724Y1247243D03*
X272244Y1243503D03*
Y1247243D03*
X264763D03*
X268503Y1250984D03*
X264763Y1243503D03*
X272244Y1239763D03*
X275984Y1250984D03*
X279724Y1243503D03*
X268503Y1254724D03*
X275984D03*
X294684Y1082677D03*
Y1090157D03*
X294685Y1086417D03*
X290944Y1078936D03*
X287204Y1082677D03*
X283464Y1093897D03*
X290944Y1097637D03*
X294685Y1247243D03*
Y1243503D03*
X283464Y1250984D03*
X287204Y1247243D03*
Y1243503D03*
Y1239763D03*
X290944Y1250984D03*
X283464Y1254724D03*
X290944D03*
X302164Y1082677D03*
X302165Y1086417D03*
X309644Y1082677D03*
X309645Y1086417D03*
X298425Y1097637D03*
X305905D03*
X300295Y1155610D03*
X309645Y1247243D03*
Y1243503D03*
X298425Y1250984D03*
X302165Y1247243D03*
Y1243503D03*
Y1239763D03*
X305905Y1250984D03*
X298425Y1254724D03*
X305905D03*
X320866Y1086417D03*
X317126D03*
X317125Y1082677D03*
X324606Y1086417D03*
X320866Y1093897D03*
X324606D03*
Y1105117D03*
Y1097637D03*
X320866Y1105117D03*
Y1097637D03*
X313385D03*
X324606Y1112598D03*
Y1120078D03*
X320866Y1112598D03*
Y1120078D03*
X317125Y1108858D03*
X320866Y1127558D03*
Y1135039D03*
X322736Y1140649D03*
X324606Y1127558D03*
Y1135039D03*
X326476Y1140649D03*
X322736Y1155610D03*
X326476Y1148129D03*
Y1155610D03*
X322736Y1148129D03*
X326476Y1170570D03*
Y1178051D03*
Y1185531D03*
X320866Y1250984D03*
X313385D03*
X317125Y1247243D03*
Y1243503D03*
X313385Y1254724D03*
X317125Y1239763D03*
X320866Y1254724D03*
X333286Y1728583D03*
Y1738583D03*
X333212Y1774624D03*
Y1784624D03*
X438162Y1348187D03*
Y1360099D03*
Y1384297D03*
Y1372385D03*
X450402Y1348187D03*
Y1360099D03*
Y1384297D03*
Y1372385D03*
Y1396583D03*
Y1408495D03*
X462642Y1348187D03*
X474882D03*
X462642Y1360099D03*
X474882D03*
X462642Y1384297D03*
X474882D03*
X462642Y1372385D03*
X474882D03*
Y1396583D03*
X462642D03*
X474882Y1408495D03*
X462642D03*
X487122Y1348187D03*
Y1360099D03*
Y1372385D03*
Y1384297D03*
Y1396583D03*
Y1408495D03*
X499362Y1348187D03*
Y1360099D03*
Y1372385D03*
Y1384297D03*
Y1396583D03*
Y1408495D03*
X511602Y1348187D03*
Y1360099D03*
Y1372385D03*
Y1384297D03*
Y1396583D03*
Y1408495D03*
X536082Y1348187D03*
X523842D03*
X536082Y1360099D03*
X523842D03*
Y1384297D03*
Y1372385D03*
X536082Y1384297D03*
Y1372385D03*
Y1396583D03*
X523842D03*
X536082Y1408495D03*
X523842D03*
X548322Y1348187D03*
Y1360099D03*
Y1384297D03*
Y1372385D03*
Y1396583D03*
Y1408495D03*
X560562Y1348187D03*
Y1360099D03*
Y1384297D03*
Y1372385D03*
Y1396583D03*
Y1408495D03*
X600295Y1084547D03*
Y1092027D03*
X604035Y1077066D03*
Y1084547D03*
Y1092027D03*
X600295Y1095767D03*
X604035D03*
X600295Y1110728D03*
Y1118208D03*
X604035Y1110728D03*
Y1118208D03*
X604036Y1166830D03*
X611516Y1073326D03*
X618996D03*
Y1088287D03*
Y1092027D03*
X611516Y1077066D03*
X615256Y1080807D03*
X607776D03*
X615256Y1084547D03*
X607776D03*
X615256Y1088287D03*
X611516D03*
X607776D03*
X611516Y1092027D03*
X618996Y1077066D03*
X611516Y1106988D03*
X607776D03*
X611516Y1095767D03*
X615256Y1099507D03*
X607776D03*
X615256Y1103247D03*
X607776D03*
X618996Y1095767D03*
X615256Y1110728D03*
Y1114468D03*
X611516D03*
X607776D03*
X615256Y1129429D03*
X617126Y1213582D03*
X620866D03*
X620083Y1728286D03*
Y1738286D03*
X619711Y1775438D03*
Y1785438D03*
X626476Y1088287D03*
X622736Y1080807D03*
Y1084547D03*
Y1088287D03*
Y1099507D03*
Y1103247D03*
Y1166830D03*
Y1170570D03*
Y1174310D03*
Y1178050D03*
X636288Y1372385D03*
Y1384297D03*
Y1396583D03*
X624048D03*
X636288Y1408495D03*
X624048D03*
X648528Y1348187D03*
Y1360099D03*
Y1372385D03*
Y1384297D03*
Y1396583D03*
Y1408495D03*
X660768Y1348187D03*
Y1360099D03*
Y1372385D03*
Y1384297D03*
Y1396583D03*
Y1408495D03*
X671358Y1114468D03*
X673008Y1348187D03*
X685248D03*
X673008Y1360099D03*
X685248D03*
Y1372385D03*
Y1384297D03*
X673008Y1372385D03*
Y1384297D03*
X685248Y1396583D03*
X673008D03*
X685248Y1408495D03*
X673008D03*
X695669Y1078936D03*
X699409Y1082677D03*
X695669Y1097637D03*
X699409Y1247243D03*
Y1243503D03*
X691929Y1247243D03*
X695669Y1250984D03*
Y1254724D03*
X697488Y1348187D03*
Y1360099D03*
Y1384297D03*
Y1372385D03*
Y1396583D03*
Y1408495D03*
X706890Y1082677D03*
X714370D03*
X706890Y1101377D03*
X703149Y1254724D03*
Y1250984D03*
X718110D03*
Y1239763D03*
X714370Y1247243D03*
X710630Y1254724D03*
Y1250984D03*
Y1239763D03*
X706890Y1247243D03*
Y1239763D03*
X718110Y1254724D03*
X709728Y1348187D03*
Y1360099D03*
Y1384297D03*
Y1372385D03*
Y1396583D03*
Y1408495D03*
X721850Y1082677D03*
X733071Y1078936D03*
Y1097637D03*
X731201Y1121948D03*
X734941Y1125688D03*
Y1133169D03*
X731201Y1204232D03*
X729331Y1243503D03*
X721850D03*
X729331Y1239763D03*
Y1247243D03*
X733071Y1250984D03*
Y1254724D03*
X725590D03*
Y1250984D03*
X721850Y1247243D03*
X734208Y1348187D03*
X721968D03*
X734208Y1360099D03*
X721968D03*
Y1384297D03*
Y1372385D03*
X734208D03*
Y1384297D03*
X721968Y1396489D03*
X734208D03*
X721968Y1408401D03*
X734208D03*
X744291Y1082677D03*
X748031Y1078936D03*
X736811Y1086417D03*
Y1082677D03*
X748031Y1097637D03*
X740551Y1093897D03*
X736811Y1243503D03*
Y1247243D03*
X744291Y1243503D03*
Y1239763D03*
X748031Y1254724D03*
Y1250984D03*
X744291Y1247243D03*
X740551Y1254724D03*
Y1250984D03*
X746448Y1348187D03*
Y1360099D03*
Y1372385D03*
Y1384297D03*
X759251Y1082677D03*
X751772Y1086417D03*
X751771Y1090157D03*
Y1082677D03*
X759252Y1086417D03*
X766732D03*
X766731Y1082677D03*
X762992Y1097637D03*
X755512D03*
X757382Y1155610D03*
X755512Y1250984D03*
Y1254724D03*
X759252Y1247243D03*
Y1243503D03*
X762992Y1250984D03*
Y1254724D03*
X766732Y1247243D03*
Y1243503D03*
X759252Y1239763D03*
X751772Y1247243D03*
Y1243503D03*
X758688Y1348187D03*
Y1360099D03*
Y1372385D03*
Y1384297D03*
X774213Y1086417D03*
X774212Y1082677D03*
X781693Y1086417D03*
X777953D03*
X770472Y1097637D03*
X777953Y1093897D03*
Y1105117D03*
X781693Y1093897D03*
Y1097637D03*
X777953D03*
X781693Y1105117D03*
Y1112598D03*
X777953Y1120078D03*
X781693D03*
X774212Y1108858D03*
X777953Y1112598D03*
X783563Y1140649D03*
X779823D03*
X781693Y1127558D03*
X777953D03*
Y1135039D03*
X781693D03*
X783563Y1155610D03*
Y1148129D03*
X779823Y1155610D03*
Y1148129D03*
X783563Y1170570D03*
Y1185531D03*
Y1178051D03*
X770472Y1250984D03*
Y1254724D03*
X777953Y1250984D03*
X774212Y1247243D03*
Y1243503D03*
Y1239763D03*
X777953Y1254724D03*
X770928Y1348187D03*
Y1360099D03*
X907279Y1738990D03*
Y1728990D03*
X907073Y1776014D03*
Y1786014D03*
X1057381Y1092027D03*
Y1084547D03*
Y1095767D03*
Y1118208D03*
Y1110728D03*
X1068602Y1073326D03*
X1072342Y1088287D03*
Y1084547D03*
Y1080807D03*
X1061121Y1092027D03*
X1068602D03*
X1064862Y1088287D03*
X1068602D03*
X1061121Y1084547D03*
X1064862D03*
Y1080807D03*
X1061121Y1077066D03*
X1068602D03*
X1072342Y1099507D03*
Y1103247D03*
X1061121Y1095767D03*
X1068602D03*
X1064862Y1106988D03*
X1068602D03*
X1064862Y1103247D03*
Y1099507D03*
X1072342Y1114468D03*
Y1110728D03*
X1061121Y1118208D03*
X1064862Y1114468D03*
X1068602D03*
X1061121Y1110728D03*
X1072342Y1129429D03*
X1061122Y1166830D03*
X1074212Y1213582D03*
X1076082Y1073326D03*
X1083562Y1088287D03*
X1079822D03*
Y1084547D03*
Y1080807D03*
X1076082Y1092027D03*
Y1088287D03*
Y1077066D03*
X1079822Y1103247D03*
Y1099507D03*
X1076082Y1095767D03*
X1079822Y1170570D03*
Y1166830D03*
Y1174310D03*
Y1178050D03*
X1077952Y1213582D03*
X1128444Y1114468D03*
X1152755Y1078936D03*
X1156495Y1082677D03*
X1152755Y1097637D03*
Y1254724D03*
Y1250984D03*
X1149015Y1247243D03*
X1156495Y1243503D03*
Y1247243D03*
X1163976Y1082677D03*
X1171456D03*
X1163976Y1101377D03*
Y1239763D03*
Y1247243D03*
X1167716Y1239763D03*
Y1250984D03*
Y1254724D03*
X1171456Y1247243D03*
X1160235Y1250984D03*
Y1254724D03*
X1178936Y1082677D03*
X1188287Y1121948D03*
Y1204232D03*
X1175196Y1254724D03*
Y1239763D03*
Y1250984D03*
X1178936Y1247243D03*
X1182676Y1250984D03*
Y1254724D03*
X1186417Y1247243D03*
Y1239763D03*
X1178936Y1243503D03*
X1186417D03*
X1190157Y1078936D03*
X1201377Y1082677D03*
X1205117Y1078936D03*
X1193897Y1082677D03*
Y1086417D03*
X1190157Y1097637D03*
X1197637Y1093897D03*
X1205117Y1097637D03*
X1192027Y1133169D03*
Y1125688D03*
X1190157Y1254724D03*
Y1250984D03*
X1197637D03*
Y1254724D03*
X1201377Y1247243D03*
X1205117Y1250984D03*
Y1254724D03*
X1201377Y1239763D03*
Y1243503D03*
X1193897Y1247243D03*
Y1243503D03*
X1216337Y1082677D03*
X1216338Y1086417D03*
X1208857Y1082677D03*
X1208858Y1086417D03*
X1208857Y1090157D03*
X1212598Y1097637D03*
X1220078D03*
X1214468Y1155610D03*
X1212598Y1250984D03*
Y1254724D03*
X1216338Y1247243D03*
Y1243503D03*
X1220078Y1250984D03*
Y1254724D03*
X1216338Y1239763D03*
X1208858Y1247243D03*
Y1243503D03*
X1223817Y1082677D03*
X1223818Y1086417D03*
X1231298Y1082677D03*
X1235039Y1086417D03*
X1231299D03*
X1227558Y1097637D03*
X1235039Y1093897D03*
Y1097637D03*
Y1105117D03*
X1231298Y1108858D03*
X1235039Y1112598D03*
Y1120078D03*
X1236909Y1140649D03*
X1235039Y1127558D03*
Y1135039D03*
X1236909Y1148129D03*
Y1155610D03*
X1223818Y1247243D03*
Y1243503D03*
X1227558Y1250984D03*
Y1254724D03*
X1235039Y1250984D03*
X1231298Y1247243D03*
Y1243503D03*
Y1239763D03*
X1235039Y1254724D03*
X1238779Y1086417D03*
Y1093897D03*
Y1097637D03*
Y1105117D03*
Y1112598D03*
Y1120078D03*
X1240649Y1140649D03*
X1238779Y1127558D03*
Y1135039D03*
X1240649Y1148129D03*
Y1155610D03*
Y1170570D03*
Y1178051D03*
Y1185531D03*
X1514468Y1084547D03*
Y1092027D03*
Y1095767D03*
Y1110728D03*
Y1118208D03*
X1525689Y1073326D03*
Y1077066D03*
X1518208D03*
X1529429Y1080807D03*
X1521949D03*
X1529429Y1084547D03*
X1521949D03*
X1518208D03*
X1529429Y1088287D03*
X1525689D03*
X1521949D03*
X1525689Y1092027D03*
X1518208D03*
X1521949Y1103247D03*
X1525689Y1106988D03*
X1521949D03*
X1525689Y1095767D03*
X1518208D03*
X1529429Y1099507D03*
X1521949D03*
X1529429Y1103247D03*
Y1110728D03*
X1518208D03*
X1529429Y1114468D03*
X1525689D03*
X1521949D03*
X1518208Y1118208D03*
X1529429Y1129429D03*
X1518209Y1166830D03*
X1533169Y1073326D03*
X1540649Y1088287D03*
X1533169Y1077066D03*
X1536909Y1080807D03*
Y1084547D03*
Y1088287D03*
X1533169D03*
Y1092027D03*
Y1095767D03*
X1536909Y1099507D03*
Y1103247D03*
Y1166830D03*
Y1170570D03*
Y1174310D03*
X1535039Y1176180D03*
Y1213582D03*
X1531299D03*
X1585531Y1114468D03*
X1609842Y1078936D03*
Y1097637D03*
Y1254724D03*
Y1250984D03*
X1606102Y1247243D03*
X1613582Y1082677D03*
X1621063D03*
Y1101377D03*
X1613582Y1243503D03*
Y1247243D03*
X1621063Y1239763D03*
Y1247243D03*
X1624803Y1239763D03*
Y1250984D03*
Y1254724D03*
X1617322Y1250984D03*
Y1254724D03*
X1636023Y1082677D03*
X1628543D03*
X1632283Y1254724D03*
X1628543Y1247243D03*
X1632283Y1239763D03*
Y1250984D03*
X1636023Y1247243D03*
X1639763Y1250984D03*
Y1254724D03*
X1643504Y1247243D03*
Y1239763D03*
X1636023Y1243503D03*
X1643504D03*
X1658464Y1082677D03*
X1650984D03*
Y1086417D03*
X1647244Y1078936D03*
Y1097637D03*
X1654724Y1093897D03*
X1645374Y1121948D03*
X1649114Y1133169D03*
Y1125688D03*
X1645374Y1204232D03*
X1647244Y1254724D03*
Y1250984D03*
X1654724D03*
Y1254724D03*
X1658464Y1247243D03*
Y1239763D03*
Y1243503D03*
X1650984Y1247243D03*
Y1243503D03*
X1662204Y1078936D03*
X1673424Y1082677D03*
X1673425Y1086417D03*
X1665944Y1082677D03*
X1665945Y1086417D03*
X1665944Y1090157D03*
X1662204Y1097637D03*
X1669685D03*
X1671555Y1155610D03*
X1665945Y1247243D03*
Y1243503D03*
X1662204Y1250984D03*
Y1254724D03*
X1669685Y1250984D03*
Y1254724D03*
X1673425Y1247243D03*
Y1243503D03*
Y1239763D03*
X1680904Y1082677D03*
X1680905Y1086417D03*
X1688385Y1082677D03*
X1692126Y1086417D03*
X1688386D03*
X1677165Y1097637D03*
X1684645D03*
X1692126Y1093897D03*
Y1097637D03*
Y1105117D03*
X1688385Y1108858D03*
X1692126Y1112598D03*
Y1120078D03*
Y1127558D03*
Y1135039D03*
X1684645Y1250984D03*
Y1254724D03*
X1692126Y1250984D03*
X1688385Y1247243D03*
Y1243503D03*
Y1239763D03*
X1692126Y1254724D03*
X1677165Y1250984D03*
Y1254724D03*
X1680905Y1247243D03*
Y1243503D03*
X1695866Y1086417D03*
Y1093897D03*
Y1097637D03*
Y1105117D03*
Y1112598D03*
Y1120078D03*
X1697736Y1140649D03*
X1693996D03*
X1695866Y1127558D03*
Y1135039D03*
X1697736Y1148129D03*
X1693996D03*
X1697736Y1155610D03*
X1693996D03*
X1697736Y1170570D03*
Y1178051D03*
Y1185531D03*
G54D34*
X145078Y1228543D03*
X148818D03*
X145078Y1250984D03*
X148818Y1243503D03*
Y1250984D03*
X145078Y1243503D03*
X161909Y1125688D03*
X158169Y1151869D03*
X154429D03*
Y1166830D03*
X160039Y1194881D03*
Y1202362D03*
Y1209842D03*
Y1217322D03*
Y1236023D03*
Y1232283D03*
X152559Y1236023D03*
Y1232283D03*
X156299Y1250984D03*
X160039Y1247243D03*
X152559D03*
X156299Y1239763D03*
X163779Y1250984D03*
X156299Y1254724D03*
X163779D03*
X178740Y1075196D03*
X171259D03*
X174999D03*
X182480D03*
X178740Y1078936D03*
X174999Y1086417D03*
Y1082677D03*
X171259Y1078936D03*
X182480Y1086417D03*
Y1082677D03*
X174999Y1078936D03*
X182480D03*
X178740Y1082677D03*
Y1086417D03*
X174999Y1093897D03*
X182480D03*
X171259Y1097637D03*
X182480D03*
X174999D03*
X178740Y1101376D03*
Y1105117D03*
X173129Y1129428D03*
X169389D03*
X180610Y1170570D03*
X174999Y1209842D03*
X167519Y1221062D03*
X182480Y1236023D03*
Y1232283D03*
X174999D03*
Y1236023D03*
X167519Y1232283D03*
Y1236023D03*
X182480Y1239763D03*
Y1247243D03*
X178740Y1250984D03*
Y1239763D03*
X174999Y1243503D03*
X178740Y1254724D03*
X171259D03*
X167519Y1247243D03*
X186220Y1075196D03*
X193700D03*
X189960D03*
X197440D03*
X189960Y1086417D03*
Y1082677D03*
X193700Y1078936D03*
X186220D03*
X197440Y1086417D03*
Y1082677D03*
X186220D03*
Y1086417D03*
X189960Y1078936D03*
X193700Y1086417D03*
Y1082677D03*
X197440Y1078936D03*
X193700Y1105117D03*
X197440Y1093897D03*
X189960Y1097637D03*
X186220Y1105117D03*
X197440Y1097637D03*
X193700Y1101376D03*
X186220D03*
X188090Y1178051D03*
Y1193011D03*
X197440Y1236023D03*
Y1232283D03*
X189960Y1236023D03*
Y1232283D03*
X197440Y1247243D03*
X193700Y1254724D03*
X186220D03*
X189960Y1239763D03*
X186220Y1250984D03*
X189960Y1247243D03*
X193700Y1250984D03*
X201181Y1075196D03*
X208661D03*
X204921D03*
X212401D03*
X208661Y1078936D03*
X212401Y1086417D03*
Y1082677D03*
X204921Y1086417D03*
Y1082677D03*
X201181Y1078936D03*
X212401D03*
X208661Y1082677D03*
X201181D03*
Y1086417D03*
X208661D03*
X204921Y1078936D03*
Y1097637D03*
X208661Y1101376D03*
X212401Y1097637D03*
X208661Y1105117D03*
X212401Y1093897D03*
X201181Y1101376D03*
X204921Y1093897D03*
X201181Y1105117D03*
X204921Y1232283D03*
X212401D03*
Y1236023D03*
X204921D03*
X208661Y1250984D03*
X201181Y1239763D03*
X212401D03*
Y1247243D03*
X201181Y1254724D03*
X204921Y1239763D03*
X201181Y1250984D03*
X204921Y1247243D03*
X208661Y1254724D03*
X213969Y1445013D03*
Y1456013D03*
X223622Y1075196D03*
X231102D03*
X216141D03*
X227362D03*
X219881D03*
X227362Y1086417D03*
Y1082677D03*
X219881Y1086417D03*
Y1082677D03*
X223622Y1078936D03*
X231102D03*
X216141D03*
X219881D03*
X216141Y1086417D03*
X231102Y1082677D03*
Y1086417D03*
X223622Y1082677D03*
X227362Y1078936D03*
X216141Y1082677D03*
X223622Y1086417D03*
X216141Y1101376D03*
X231102D03*
X227362Y1093897D03*
X219881Y1097637D03*
X223621Y1101376D03*
Y1105117D03*
X216141D03*
X219881Y1093897D03*
X227362Y1097637D03*
X231102Y1105117D03*
Y1228543D03*
X219881Y1232283D03*
Y1236023D03*
X227362Y1232283D03*
Y1236023D03*
X223622Y1254724D03*
X231102D03*
X227362Y1247243D03*
X219881Y1239763D03*
X223622Y1250984D03*
X219881Y1247243D03*
X231102Y1250984D03*
X227362Y1239763D03*
X216141Y1250984D03*
Y1254724D03*
X227249Y1445013D03*
Y1456013D03*
X234841Y1093897D03*
X246062Y1105117D03*
X242321Y1097637D03*
X234841D03*
X238582Y1101376D03*
X246062D03*
X238582Y1105117D03*
X242321Y1093897D03*
X246062Y1221062D03*
X238582Y1224803D03*
Y1228543D03*
X242322Y1236023D03*
Y1232283D03*
X246062Y1228543D03*
X234842Y1232283D03*
X246062Y1224803D03*
X234842Y1236023D03*
Y1239763D03*
Y1243503D03*
X242322Y1239763D03*
X257283Y1101377D03*
X253543Y1105117D03*
Y1101376D03*
X261023Y1105117D03*
Y1101376D03*
X249803Y1221062D03*
X253543D03*
X261023D03*
X257283D03*
X261023Y1224803D03*
X253543Y1228543D03*
X249803Y1232283D03*
X257283D03*
Y1236023D03*
X261023Y1228543D03*
X253543Y1224803D03*
X249803Y1236023D03*
Y1243503D03*
X257283D03*
X272244Y1101377D03*
X279724D03*
X264763D03*
X264762Y1097637D03*
X268503Y1105117D03*
X272243Y1097637D03*
X275984Y1105117D03*
X279723Y1093897D03*
X272243D03*
X279723Y1097637D03*
X268503Y1101376D03*
X275984D03*
X264762Y1093897D03*
X277854Y1121948D03*
Y1129429D03*
X264763Y1221062D03*
Y1232283D03*
X268503Y1224803D03*
X275984D03*
X272244Y1236023D03*
X279724Y1232283D03*
Y1236023D03*
X275984Y1228543D03*
X272244Y1232283D03*
X268503Y1228543D03*
X264763Y1236023D03*
X279724Y1239763D03*
X275984D03*
X264763D03*
X287204Y1086417D03*
X283464Y1097637D03*
X294684Y1101377D03*
X283464Y1101376D03*
X294684Y1093897D03*
X287203D03*
X294684Y1097637D03*
X283464Y1105117D03*
X290944Y1101376D03*
Y1105117D03*
X287203Y1097637D03*
X294684Y1123818D03*
Y1116338D03*
Y1131299D03*
X289074Y1144389D03*
X294685Y1198621D03*
Y1213582D03*
Y1206102D03*
X287204Y1232283D03*
X283464Y1224803D03*
Y1228543D03*
X287204Y1236023D03*
X294685D03*
X290944Y1224803D03*
X294685Y1232283D03*
X290944Y1228543D03*
X294685Y1239763D03*
X302164Y1090157D03*
X305904D03*
X309644D03*
X302165Y1101377D03*
X309645D03*
X298425Y1105117D03*
Y1101376D03*
X309644Y1097637D03*
X302164D03*
X305905Y1105117D03*
X309644Y1093897D03*
X305905Y1101376D03*
X302164Y1093897D03*
X309645Y1123818D03*
X309644Y1108858D03*
X309645Y1116338D03*
X302165Y1120078D03*
X305905Y1112598D03*
X298425Y1116338D03*
X305905Y1120078D03*
X302165Y1112598D03*
X298425Y1123818D03*
X309645Y1131299D03*
X307775Y1140649D03*
X298425Y1135039D03*
Y1127558D03*
X305905Y1127559D03*
Y1135039D03*
X302165D03*
Y1127559D03*
X298425Y1131299D03*
X300295Y1151869D03*
Y1144389D03*
X307775Y1148129D03*
Y1155610D03*
Y1159350D03*
X298425Y1198621D03*
X305905Y1202362D03*
X302165D03*
X298425Y1213582D03*
X305905Y1209842D03*
Y1217322D03*
X302165Y1209842D03*
X298425Y1206102D03*
X302165Y1217322D03*
Y1232283D03*
X309645D03*
X298425Y1224803D03*
Y1228543D03*
X309645Y1236023D03*
X305905Y1228543D03*
Y1224803D03*
X302165Y1236023D03*
X305905Y1239763D03*
X317125Y1090157D03*
X320866D03*
X324606D03*
Y1082676D03*
X320866D03*
X317126Y1105117D03*
X317125Y1101377D03*
X313385D03*
X317125Y1093897D03*
X320866Y1101377D03*
X324606D03*
X317125Y1097637D03*
X313385Y1120078D03*
X324606Y1123818D03*
Y1108858D03*
X320866D03*
X317125Y1112598D03*
X324606Y1116338D03*
X313385Y1112598D03*
X317125Y1120078D03*
X320866Y1116338D03*
Y1123818D03*
X318996Y1136909D03*
X317125Y1131299D03*
X313385Y1127558D03*
X317125Y1135039D03*
X313385D03*
X324606Y1131299D03*
X317125Y1127558D03*
X320866Y1131299D03*
X318996Y1144389D03*
Y1151869D03*
X322736Y1166830D03*
X318996Y1159350D03*
Y1166830D03*
X326476D03*
X318996Y1189271D03*
Y1181791D03*
Y1174310D03*
X317125Y1198621D03*
X320866D03*
X313385Y1202362D03*
X324606Y1198621D03*
X317125Y1202362D03*
Y1206102D03*
Y1213582D03*
Y1217322D03*
Y1209842D03*
X324606Y1213582D03*
X313385Y1209842D03*
X320866Y1213582D03*
X324606Y1206102D03*
X313385Y1217322D03*
X317125Y1236023D03*
X313385Y1224803D03*
X324606Y1228543D03*
X317125Y1232283D03*
X313385Y1228543D03*
X320866D03*
Y1243503D03*
X313385Y1239763D03*
X320866Y1247243D03*
X324606D03*
X602165Y1228543D03*
Y1243503D03*
Y1250984D03*
X618996Y1125688D03*
Y1133169D03*
X615256Y1151869D03*
X611516D03*
Y1166830D03*
X617126Y1202362D03*
Y1194881D03*
Y1209842D03*
Y1217322D03*
X605905Y1228543D03*
X609646Y1232283D03*
X617126Y1236023D03*
Y1232283D03*
X609646Y1236023D03*
X613386Y1239763D03*
X620866Y1254724D03*
Y1250984D03*
X617126Y1247243D03*
X609646D03*
X613386Y1254724D03*
Y1250984D03*
X605905Y1243503D03*
Y1254724D03*
Y1250984D03*
X626476Y1073326D03*
X635827Y1075196D03*
X628346D03*
X632086D03*
X626476Y1077066D03*
X628346Y1078936D03*
X635827D03*
X632086Y1082677D03*
Y1086417D03*
Y1078936D03*
X635827Y1086417D03*
Y1082677D03*
X632086Y1097637D03*
X626476Y1099507D03*
X628346Y1097637D03*
X635827Y1105117D03*
X632086Y1093897D03*
X635827Y1101376D03*
X630216Y1129428D03*
X626476D03*
X630216Y1136909D03*
X626476D03*
X632086Y1209842D03*
X624606Y1221062D03*
X632086Y1232283D03*
Y1236023D03*
X624606Y1232283D03*
Y1236023D03*
X632086Y1243503D03*
X635827Y1239763D03*
Y1254724D03*
Y1250984D03*
X628346Y1254724D03*
X624606Y1247243D03*
X643307Y1075196D03*
X650787D03*
X639567D03*
X647047D03*
X650787Y1078936D03*
X647047Y1082677D03*
Y1086417D03*
X643307Y1078936D03*
X639567Y1086417D03*
Y1082677D03*
X643307Y1086417D03*
Y1082677D03*
X647047Y1078936D03*
X639567D03*
X650787Y1082677D03*
Y1086417D03*
Y1105117D03*
X639567Y1097637D03*
X643307Y1105117D03*
X647047Y1097637D03*
X639567Y1093897D03*
X643307Y1101376D03*
X650787D03*
X637697Y1170570D03*
X645177Y1178051D03*
Y1193011D03*
X639567Y1236023D03*
X647047D03*
X639567Y1232283D03*
X647047D03*
X639567Y1239763D03*
Y1247243D03*
X647047Y1239763D03*
X650787Y1254724D03*
Y1250984D03*
X647047Y1247243D03*
X643307Y1254724D03*
Y1250984D03*
X658268Y1075196D03*
X665748D03*
X662008D03*
X654527D03*
X669488D03*
Y1086417D03*
X665748Y1078936D03*
X669488Y1082677D03*
X654527D03*
Y1086417D03*
X662008Y1082677D03*
Y1086417D03*
X658268Y1078936D03*
X662008D03*
X665748Y1082677D03*
X658268D03*
X654527Y1078936D03*
X665748Y1086417D03*
X658268D03*
X669488Y1078936D03*
X662008Y1097637D03*
X654527Y1093897D03*
X669488D03*
X665748Y1105117D03*
X654527Y1097637D03*
X662008Y1093897D03*
X669488Y1097637D03*
X665748Y1101376D03*
X658268Y1105117D03*
Y1101376D03*
X669488Y1232283D03*
X654527Y1236023D03*
X662008Y1232283D03*
Y1236023D03*
X669488D03*
X654527Y1232283D03*
Y1247243D03*
X662008Y1239763D03*
X658268D03*
X669488D03*
X665748Y1250984D03*
Y1254724D03*
X669488Y1247243D03*
X662008D03*
X658268Y1254724D03*
Y1250984D03*
X680709Y1075196D03*
X673228D03*
X676968D03*
X684449D03*
Y1082677D03*
Y1086417D03*
X673228Y1078936D03*
X680709D03*
X676968Y1082677D03*
Y1086417D03*
Y1078936D03*
X680709Y1086417D03*
X684449Y1078936D03*
X673228Y1086417D03*
Y1082677D03*
X680709D03*
X673228Y1105117D03*
X684449Y1093897D03*
X676968D03*
X684449Y1097637D03*
X676968D03*
X680708Y1105117D03*
X673228Y1101376D03*
X680708D03*
X676968Y1236023D03*
X684449Y1232283D03*
Y1236023D03*
X676968Y1232283D03*
Y1239763D03*
X680709Y1254724D03*
Y1250984D03*
X676968Y1247243D03*
X673228Y1254724D03*
Y1250984D03*
X684449Y1247243D03*
Y1239763D03*
X688189Y1075196D03*
Y1078936D03*
Y1086417D03*
Y1082677D03*
Y1105117D03*
X695669Y1101376D03*
X699408Y1097637D03*
X695669Y1105117D03*
X691928Y1093897D03*
Y1097637D03*
X699408Y1093897D03*
X688189Y1101376D03*
Y1228543D03*
X691929Y1236023D03*
X699409Y1232283D03*
Y1236023D03*
X691929Y1232283D03*
X695669Y1228543D03*
Y1224803D03*
X688189Y1254724D03*
Y1250984D03*
X699409Y1239763D03*
X691929D03*
Y1243503D03*
X714370Y1101377D03*
X703149Y1105117D03*
X718110D03*
Y1101376D03*
X710630Y1105117D03*
X703149Y1101376D03*
X710630D03*
X706890Y1236023D03*
X718110Y1228543D03*
X714370Y1236023D03*
X710630Y1228543D03*
X703149D03*
X714370Y1232283D03*
X703149Y1224803D03*
X718110D03*
X710630D03*
X706890Y1232283D03*
X714370Y1243503D03*
X706890D03*
X729331Y1101377D03*
X721850D03*
X725590Y1101376D03*
X733071Y1105117D03*
X725590D03*
X721849Y1097637D03*
Y1093897D03*
X729330Y1097637D03*
X733071Y1101376D03*
X729330Y1093897D03*
X734941Y1121948D03*
Y1129429D03*
X725590Y1228543D03*
X733071D03*
X721850Y1236023D03*
X733071Y1224803D03*
X721850Y1232283D03*
X725590Y1224803D03*
X729331Y1236023D03*
Y1232283D03*
X733071Y1239763D03*
X721850D03*
X744291Y1086417D03*
X740551Y1097637D03*
X736811Y1101377D03*
X736810Y1097637D03*
X748031Y1105117D03*
X744290Y1093897D03*
X740551Y1105117D03*
X744290Y1097637D03*
X736810Y1093897D03*
X740551Y1101376D03*
X748031D03*
X746161Y1144389D03*
X744291Y1236023D03*
X736811Y1232283D03*
X744291D03*
X736811Y1236023D03*
X740551Y1224803D03*
Y1228543D03*
X748031Y1224803D03*
Y1228543D03*
X736811Y1239763D03*
X766731Y1090157D03*
X759251D03*
X762991D03*
X751771Y1101377D03*
X759252D03*
X766732D03*
X751771Y1097637D03*
X762992Y1101376D03*
Y1105117D03*
X755512D03*
X759251Y1097637D03*
Y1093897D03*
X766731Y1097637D03*
X755512Y1101376D03*
X766731Y1093897D03*
X751771D03*
X766731Y1108858D03*
X766732Y1116338D03*
Y1123818D03*
X755512D03*
X759252Y1112598D03*
X751771Y1123818D03*
X762992Y1112598D03*
X755512Y1116338D03*
X751771D03*
X759252Y1120078D03*
X762992D03*
X764862Y1140649D03*
X766732Y1131299D03*
X755512Y1127558D03*
Y1135039D03*
X751771Y1131299D03*
X762992Y1135039D03*
X755512Y1131299D03*
X762992Y1127559D03*
X759252Y1135039D03*
Y1127559D03*
X764862Y1155610D03*
Y1148129D03*
X757382Y1144389D03*
Y1151869D03*
X764862Y1159350D03*
X762992Y1202362D03*
X755512Y1198621D03*
X759252Y1202362D03*
X751772Y1198621D03*
X762992Y1217322D03*
X751772Y1213582D03*
X762992Y1209842D03*
X755512Y1213582D03*
X751772Y1206102D03*
X759252Y1217322D03*
Y1209842D03*
X755512Y1206102D03*
Y1228543D03*
X751772Y1236023D03*
X762992Y1228543D03*
X751772Y1232283D03*
X766732D03*
Y1236023D03*
X759252Y1232283D03*
X762992Y1224803D03*
X759252Y1236023D03*
X755512Y1224803D03*
X762992Y1239763D03*
X751772D03*
X774212Y1090157D03*
X781693D03*
X777953D03*
X781693Y1082676D03*
X777953D03*
X774212Y1101377D03*
X774213Y1105117D03*
X770472Y1101377D03*
X781693D03*
X777953D03*
X774212Y1097637D03*
Y1093897D03*
Y1112598D03*
X770472D03*
X781693Y1123818D03*
X777953D03*
X781693Y1116338D03*
X777953Y1108858D03*
X770472Y1120078D03*
X781693Y1108858D03*
X777953Y1116338D03*
X774212Y1120078D03*
Y1131299D03*
X770472Y1127558D03*
Y1135039D03*
X781693Y1131299D03*
X774212Y1127558D03*
Y1135039D03*
X777953Y1131299D03*
X776083Y1151869D03*
Y1144389D03*
X783563Y1166830D03*
X776083D03*
Y1159350D03*
X779823Y1166830D03*
X776083Y1174310D03*
Y1181791D03*
Y1196751D03*
X774212Y1198621D03*
X781693D03*
X774212Y1202362D03*
X770472D03*
X777953Y1198621D03*
X774212Y1213582D03*
Y1206102D03*
X770472Y1209842D03*
X781693Y1213582D03*
X774212Y1209842D03*
X781693Y1206102D03*
X770472Y1217322D03*
X774212D03*
X777953Y1213582D03*
X770472Y1228543D03*
X781693D03*
X770472Y1224803D03*
X777953Y1228543D03*
X774212Y1232283D03*
Y1236023D03*
X777953Y1243503D03*
X770472Y1239763D03*
X777953Y1247243D03*
X781693D03*
X1059251Y1228543D03*
Y1243503D03*
Y1250984D03*
X1072342Y1151869D03*
X1068602D03*
Y1166830D03*
X1074212Y1194881D03*
Y1202362D03*
Y1217322D03*
Y1209842D03*
X1066732Y1236023D03*
Y1232283D03*
X1074212Y1236023D03*
Y1232283D03*
X1062991Y1228543D03*
X1070472Y1250984D03*
Y1254724D03*
X1066732Y1247243D03*
X1074212D03*
X1070472Y1239763D03*
X1062991Y1250984D03*
Y1254724D03*
Y1243503D03*
X1083562Y1073326D03*
X1089172Y1075196D03*
X1083562Y1077066D03*
X1089172Y1082677D03*
Y1086417D03*
Y1078936D03*
Y1097637D03*
Y1093897D03*
X1083562Y1099507D03*
Y1136909D03*
X1087302D03*
X1083562Y1129428D03*
X1087302D03*
X1076082Y1133169D03*
Y1125688D03*
X1089172Y1209842D03*
X1081692Y1221062D03*
X1089172Y1232283D03*
X1081692D03*
Y1236023D03*
X1089172D03*
X1077952Y1250984D03*
Y1254724D03*
X1081692Y1247243D03*
X1085432Y1254724D03*
X1089172Y1243503D03*
X1092913Y1075196D03*
X1107873D03*
X1100393D03*
X1096653D03*
X1104133D03*
X1092913Y1078936D03*
X1104133Y1086417D03*
Y1082677D03*
X1107873Y1078936D03*
X1100393D03*
X1096653Y1082677D03*
Y1086417D03*
X1100393Y1082677D03*
X1104133Y1078936D03*
X1107873Y1082677D03*
Y1086417D03*
X1092913Y1082677D03*
X1100393Y1086417D03*
X1092913D03*
X1096653Y1078936D03*
X1092913Y1105117D03*
X1104133Y1097637D03*
X1096653D03*
X1100393Y1105117D03*
Y1101376D03*
X1096653Y1093897D03*
X1092913Y1101376D03*
X1107873Y1105117D03*
Y1101376D03*
X1094783Y1170570D03*
X1102263Y1178051D03*
Y1193011D03*
X1104133Y1236023D03*
Y1232283D03*
X1096653Y1236023D03*
Y1232283D03*
X1092913Y1250984D03*
Y1254724D03*
Y1239763D03*
X1100393Y1250984D03*
Y1254724D03*
X1104133Y1247243D03*
X1107873Y1250984D03*
Y1254724D03*
X1104133Y1239763D03*
X1096653Y1247243D03*
Y1239763D03*
X1115354Y1075196D03*
X1122834D03*
X1111613D03*
X1119094D03*
X1115354Y1078936D03*
X1119094Y1082677D03*
Y1086417D03*
X1122834Y1078936D03*
X1111613Y1082677D03*
Y1086417D03*
X1122834D03*
X1119094Y1078936D03*
X1115354Y1082677D03*
X1111613Y1078936D03*
X1115354Y1086417D03*
X1122834Y1082677D03*
X1119094Y1097637D03*
X1115354Y1101376D03*
X1111613Y1093897D03*
Y1097637D03*
X1122834Y1105117D03*
X1119094Y1093897D03*
X1122834Y1101376D03*
X1115354Y1105117D03*
X1119094Y1232283D03*
X1111613D03*
X1119094Y1236023D03*
X1111613D03*
X1115354Y1250984D03*
Y1254724D03*
X1119094Y1247243D03*
X1122834Y1254724D03*
Y1250984D03*
X1115354Y1239763D03*
X1119094D03*
X1111613Y1247243D03*
X1130314Y1075196D03*
X1137795D03*
X1126574D03*
X1134054D03*
X1126574Y1086417D03*
Y1082677D03*
X1130314Y1078936D03*
X1134054Y1082677D03*
Y1086417D03*
X1137795Y1078936D03*
X1134054D03*
X1126574D03*
X1130314Y1086417D03*
Y1082677D03*
X1137795Y1086417D03*
Y1082677D03*
X1126574Y1093897D03*
X1130314Y1105117D03*
X1134054Y1093897D03*
X1130314Y1101376D03*
X1134054Y1097637D03*
X1137794Y1105117D03*
X1126574Y1097637D03*
X1137794Y1101376D03*
X1134054Y1236023D03*
Y1232283D03*
X1126574D03*
Y1236023D03*
Y1247243D03*
Y1239763D03*
X1130314Y1250984D03*
Y1254724D03*
X1134054Y1247243D03*
X1137795Y1250984D03*
Y1254724D03*
X1134054Y1239763D03*
X1145275Y1075196D03*
X1141535D03*
Y1082677D03*
Y1086417D03*
X1145275Y1078936D03*
Y1086417D03*
Y1082677D03*
X1141535Y1078936D03*
X1145275Y1105117D03*
X1141535Y1093897D03*
X1145275Y1101376D03*
X1141535Y1097637D03*
X1149014D03*
X1156494Y1093897D03*
X1152755Y1101376D03*
X1156494Y1097637D03*
X1149014Y1093897D03*
X1152755Y1105117D03*
X1149015Y1236023D03*
Y1232283D03*
X1152755Y1228543D03*
X1156495Y1232283D03*
Y1236023D03*
X1141535D03*
X1145275Y1228543D03*
X1152755Y1224803D03*
X1141535Y1232283D03*
Y1239763D03*
Y1247243D03*
X1149015Y1243503D03*
Y1239763D03*
X1156495D03*
X1145275Y1250984D03*
Y1254724D03*
X1171456Y1101377D03*
X1160235Y1105117D03*
Y1101376D03*
X1167716Y1105117D03*
Y1101376D03*
X1160235Y1224803D03*
X1163976Y1232283D03*
X1167716Y1224803D03*
X1160235Y1228543D03*
X1171456Y1232283D03*
X1163976Y1236023D03*
X1171456D03*
X1167716Y1228543D03*
X1163976Y1243503D03*
X1171456D03*
X1178936Y1101377D03*
X1186417D03*
X1178935Y1097637D03*
X1186416Y1093897D03*
X1182676Y1105117D03*
X1175196D03*
X1178935Y1093897D03*
X1182676Y1101376D03*
X1175196D03*
X1186416Y1097637D03*
X1182676Y1228543D03*
X1186417Y1236023D03*
X1178936D03*
X1186417Y1232283D03*
X1175196Y1228543D03*
X1178936Y1232283D03*
X1182676Y1224803D03*
X1175196D03*
X1178936Y1239763D03*
X1201377Y1086417D03*
X1197637Y1097637D03*
X1193897Y1101377D03*
X1201376Y1093897D03*
X1193896Y1097637D03*
X1197637Y1105117D03*
X1205117D03*
X1197637Y1101376D03*
X1205117D03*
X1190157D03*
X1193896Y1093897D03*
X1201376Y1097637D03*
X1190157Y1105117D03*
X1192027Y1121948D03*
Y1129429D03*
X1203247Y1144389D03*
X1197637Y1224803D03*
X1193897Y1236023D03*
X1190157Y1228543D03*
X1201377Y1236023D03*
X1190157Y1224803D03*
X1193897Y1232283D03*
X1197637Y1228543D03*
X1201377Y1232283D03*
X1205117Y1228543D03*
Y1224803D03*
X1190157Y1239763D03*
X1193897D03*
X1216337Y1090157D03*
X1220077D03*
X1216338Y1101377D03*
X1208857D03*
X1220078Y1105117D03*
X1216337Y1093897D03*
X1212598Y1101376D03*
Y1105117D03*
X1208857Y1093897D03*
X1216337Y1097637D03*
X1220078Y1101376D03*
X1208857Y1097637D03*
X1212598Y1123818D03*
X1208857Y1116338D03*
X1212598D03*
X1216338Y1120078D03*
Y1112598D03*
X1208857Y1123818D03*
X1220078Y1112598D03*
Y1120078D03*
X1221948Y1140649D03*
X1212598Y1127558D03*
Y1135039D03*
X1216338Y1127559D03*
Y1135039D03*
X1212598Y1131299D03*
X1208857D03*
X1220078Y1135039D03*
Y1127559D03*
X1221948Y1155610D03*
X1214468Y1151869D03*
Y1144389D03*
X1221948Y1148129D03*
Y1159350D03*
X1212598Y1198621D03*
X1208858D03*
X1216338Y1202362D03*
X1220078D03*
Y1217322D03*
Y1209842D03*
X1212598Y1206102D03*
X1216338Y1217322D03*
X1212598Y1213582D03*
X1208858Y1206102D03*
Y1213582D03*
X1216338Y1209842D03*
X1220078Y1224803D03*
X1212598Y1228543D03*
X1208858Y1232283D03*
X1216338Y1236023D03*
Y1232283D03*
X1212598Y1224803D03*
X1220078Y1228543D03*
X1208858Y1236023D03*
X1220078Y1239763D03*
X1208858D03*
X1223817Y1090157D03*
X1231298D03*
X1235039D03*
Y1082676D03*
X1223818Y1101377D03*
X1231298D03*
X1231299Y1105117D03*
X1227558Y1101377D03*
X1231298Y1093897D03*
X1235039Y1101377D03*
X1223817Y1093897D03*
Y1097637D03*
X1231298D03*
X1223817Y1108858D03*
X1223818Y1116338D03*
Y1123818D03*
X1227558Y1112598D03*
X1235039Y1123818D03*
X1231298Y1120078D03*
Y1112598D03*
X1235039Y1108858D03*
Y1116338D03*
X1227558Y1120078D03*
X1233169Y1136909D03*
X1223818Y1131299D03*
X1231298D03*
Y1135039D03*
X1227558Y1127558D03*
X1235039Y1131299D03*
X1231298Y1127558D03*
X1227558Y1135039D03*
X1233169Y1144389D03*
Y1151869D03*
X1236909Y1166830D03*
X1233169Y1159350D03*
Y1166830D03*
Y1189271D03*
Y1181791D03*
Y1174310D03*
Y1196751D03*
X1231298Y1198621D03*
Y1202362D03*
X1235039Y1198621D03*
X1227558Y1202362D03*
X1231298Y1206102D03*
Y1213582D03*
X1235039D03*
X1231298Y1209842D03*
X1227558D03*
X1231298Y1217322D03*
X1227558D03*
X1231298Y1232283D03*
X1227558Y1228543D03*
Y1224803D03*
X1223818Y1236023D03*
X1231298D03*
X1235039Y1228543D03*
X1223818Y1232283D03*
X1235039Y1243503D03*
X1227558Y1239763D03*
X1235039Y1247243D03*
X1238779Y1090157D03*
Y1082676D03*
Y1101377D03*
Y1108858D03*
Y1116338D03*
Y1123818D03*
X1243149Y1136909D03*
X1238779Y1131299D03*
X1240649Y1166830D03*
X1238779Y1198621D03*
Y1206102D03*
Y1213582D03*
Y1228543D03*
Y1247243D03*
X1511968Y1170570D03*
Y1178050D03*
X1529429Y1151869D03*
X1525689D03*
Y1166830D03*
X1516338Y1228543D03*
X1523819Y1232283D03*
X1520078Y1228543D03*
X1523819Y1236023D03*
X1516338Y1243503D03*
Y1250984D03*
X1527559D03*
Y1254724D03*
X1523819Y1247243D03*
X1527559Y1239763D03*
X1520078Y1250984D03*
Y1254724D03*
Y1243503D03*
X1540649Y1073326D03*
X1546259Y1075196D03*
X1540649Y1077066D03*
X1546259Y1082677D03*
Y1086417D03*
Y1078936D03*
X1540649Y1099507D03*
X1546259Y1097637D03*
Y1093897D03*
X1533169Y1125688D03*
X1544389Y1129428D03*
X1540649D03*
X1544389Y1136909D03*
X1533169Y1133169D03*
X1540649Y1136909D03*
X1531299Y1194881D03*
Y1202362D03*
Y1217322D03*
Y1209842D03*
X1546259D03*
X1538779Y1221062D03*
X1546259Y1232283D03*
X1538779Y1236023D03*
X1531299Y1232283D03*
X1546259Y1236023D03*
X1531299D03*
X1538779Y1232283D03*
X1531299Y1247243D03*
X1535039Y1250984D03*
Y1254724D03*
X1538779Y1247243D03*
X1542519Y1254724D03*
X1546259Y1243503D03*
X1557480Y1075196D03*
X1550000D03*
X1553740D03*
X1561220D03*
Y1086417D03*
Y1082677D03*
X1557480Y1078936D03*
X1553740Y1082677D03*
Y1086417D03*
X1550000Y1078936D03*
X1557480Y1082677D03*
X1553740Y1078936D03*
X1561220D03*
X1550000Y1086417D03*
Y1082677D03*
X1557480Y1086417D03*
Y1101376D03*
Y1105117D03*
X1561220Y1097637D03*
X1550000Y1101376D03*
Y1105117D03*
X1553740Y1093897D03*
Y1097637D03*
X1551870Y1170570D03*
X1559350Y1178051D03*
Y1193011D03*
X1553740Y1232283D03*
Y1236023D03*
X1561220D03*
Y1232283D03*
X1550000Y1250984D03*
Y1254724D03*
Y1239763D03*
X1557480Y1250984D03*
Y1254724D03*
X1561220Y1247243D03*
Y1239763D03*
X1553740Y1247243D03*
Y1239763D03*
X1572441Y1075196D03*
X1564960D03*
X1576181D03*
X1568700D03*
X1564960Y1078936D03*
X1572441D03*
X1576181Y1082677D03*
Y1086417D03*
X1568700Y1082677D03*
Y1086417D03*
Y1078936D03*
X1572441Y1086417D03*
X1564960Y1082677D03*
Y1086417D03*
X1572441Y1082677D03*
X1576181Y1078936D03*
X1564960Y1105117D03*
X1576181Y1097637D03*
X1568700D03*
X1576181Y1093897D03*
X1568700D03*
X1572441Y1101376D03*
Y1105117D03*
X1564960Y1101376D03*
X1568700Y1236023D03*
X1576181D03*
Y1232283D03*
X1568700D03*
X1564960Y1250984D03*
Y1254724D03*
X1572441Y1250984D03*
Y1254724D03*
X1576181Y1247243D03*
X1572441Y1239763D03*
X1576181D03*
X1568700Y1247243D03*
X1579921Y1075196D03*
X1587401D03*
X1594882D03*
X1583661D03*
X1591141D03*
X1583661Y1086417D03*
Y1082677D03*
X1579921Y1078936D03*
X1587401D03*
X1591141Y1082677D03*
Y1086417D03*
X1594882Y1078936D03*
Y1082677D03*
X1579921D03*
X1583661Y1078936D03*
X1594882Y1086417D03*
X1587401Y1082677D03*
X1579921Y1086417D03*
X1587401D03*
X1591141Y1078936D03*
X1594881Y1105117D03*
X1591141Y1097637D03*
X1583661Y1093897D03*
X1594881Y1101376D03*
X1583661Y1097637D03*
X1587401Y1105117D03*
X1579921Y1101376D03*
X1591141Y1093897D03*
X1587401Y1101376D03*
X1579921Y1105117D03*
X1591141Y1232283D03*
X1583661Y1236023D03*
Y1232283D03*
X1591141Y1236023D03*
X1583661Y1247243D03*
X1579921Y1254724D03*
Y1250984D03*
X1583661Y1239763D03*
X1587401Y1250984D03*
Y1254724D03*
X1591141Y1247243D03*
X1594882Y1250984D03*
Y1254724D03*
X1591141Y1239763D03*
X1602362Y1075196D03*
X1598622D03*
Y1082677D03*
Y1086417D03*
X1602362Y1078936D03*
Y1082677D03*
Y1086417D03*
X1598622Y1078936D03*
X1606101Y1093897D03*
X1602362Y1101376D03*
X1598622Y1097637D03*
Y1093897D03*
X1602362Y1105117D03*
X1609842Y1101376D03*
Y1105117D03*
X1606101Y1097637D03*
X1598622Y1236023D03*
X1606102D03*
X1609842Y1228543D03*
X1606102Y1232283D03*
X1609842Y1224803D03*
X1602362Y1228543D03*
X1598622Y1232283D03*
Y1239763D03*
Y1247243D03*
X1606102Y1243503D03*
Y1239763D03*
X1602362Y1250984D03*
Y1254724D03*
X1617322Y1105117D03*
Y1101376D03*
X1613581Y1093897D03*
Y1097637D03*
X1624803Y1101376D03*
Y1105117D03*
X1617322Y1228543D03*
X1624803Y1224803D03*
X1617322D03*
X1621063Y1236023D03*
X1613582D03*
X1621063Y1232283D03*
X1624803Y1228543D03*
X1613582Y1232283D03*
Y1239763D03*
X1621063Y1243503D03*
X1639763Y1101376D03*
X1636022Y1093897D03*
X1636023Y1101377D03*
X1643504D03*
X1628543D03*
X1639763Y1105117D03*
X1632283D03*
Y1101376D03*
X1636022Y1097637D03*
X1643503D03*
Y1093897D03*
X1632283Y1228543D03*
X1628543Y1236023D03*
Y1232283D03*
X1639763Y1224803D03*
X1636023Y1236023D03*
X1643504Y1232283D03*
X1632283Y1224803D03*
X1643504Y1236023D03*
X1636023Y1232283D03*
X1639763Y1228543D03*
X1628543Y1243503D03*
X1636023Y1239763D03*
X1658464Y1086417D03*
X1658463Y1097637D03*
X1647244Y1101376D03*
X1654724Y1097637D03*
X1650984Y1101377D03*
X1658463Y1093897D03*
X1654724Y1105117D03*
X1650983Y1093897D03*
X1647244Y1105117D03*
X1654724Y1101376D03*
X1650983Y1097637D03*
X1649114Y1121948D03*
Y1129429D03*
X1660334Y1144389D03*
X1654724Y1228543D03*
X1647244D03*
X1658464Y1232283D03*
X1654724Y1224803D03*
X1658464Y1236023D03*
X1650984D03*
X1647244Y1224803D03*
X1650984Y1232283D03*
X1647244Y1239763D03*
X1650984D03*
X1673424Y1090157D03*
X1665944Y1093897D03*
X1662204Y1105117D03*
X1669685D03*
X1673424Y1097637D03*
X1669685Y1101376D03*
X1673425Y1101377D03*
X1665944D03*
X1673424Y1093897D03*
X1665944Y1097637D03*
X1662204Y1101376D03*
X1673425Y1112598D03*
X1665944Y1123818D03*
X1673425Y1120078D03*
X1669685Y1123818D03*
X1665944Y1116338D03*
X1669685D03*
X1665944Y1131299D03*
X1671555Y1136909D03*
X1669685Y1127558D03*
Y1135039D03*
Y1131299D03*
X1673425Y1127559D03*
Y1135039D03*
X1671555Y1151869D03*
Y1144389D03*
X1673425Y1202362D03*
X1665945Y1198621D03*
X1669685D03*
X1665945Y1206102D03*
X1669685Y1213582D03*
X1673425Y1209842D03*
X1669685Y1206102D03*
X1665945Y1213582D03*
X1673425Y1217322D03*
Y1236023D03*
X1662204Y1228543D03*
X1669685D03*
X1673425Y1232283D03*
X1665945D03*
Y1236023D03*
X1662204Y1224803D03*
X1669685D03*
X1665945Y1239763D03*
X1677164Y1090157D03*
X1680904D03*
X1688385D03*
X1692126D03*
Y1082676D03*
Y1101377D03*
X1684645D03*
X1677165Y1105117D03*
X1680905Y1101377D03*
X1688385D03*
X1688386Y1105117D03*
X1680904Y1097637D03*
X1677165Y1101376D03*
X1688385Y1097637D03*
X1680904Y1093897D03*
X1688385D03*
X1677165Y1120078D03*
Y1112598D03*
X1680904Y1108858D03*
X1680905Y1116338D03*
Y1123818D03*
X1692126Y1116338D03*
Y1108858D03*
X1684645Y1120078D03*
X1688385D03*
X1684645Y1112598D03*
X1692126Y1123818D03*
X1688385Y1112598D03*
X1690256Y1136909D03*
X1679035Y1140649D03*
X1680905Y1131299D03*
X1688385D03*
X1677165Y1135039D03*
Y1127559D03*
X1684645Y1135039D03*
Y1127558D03*
X1692126Y1131299D03*
X1688385Y1127558D03*
Y1135039D03*
X1690256Y1144389D03*
X1679035Y1148129D03*
Y1155610D03*
X1690256Y1151869D03*
Y1159350D03*
X1679035D03*
X1690256Y1166830D03*
Y1174310D03*
Y1189271D03*
Y1181791D03*
X1688385Y1198621D03*
X1684645Y1202362D03*
X1692126Y1198621D03*
X1688385Y1202362D03*
X1677165D03*
X1688385Y1213582D03*
Y1206102D03*
X1692126Y1213582D03*
X1684645Y1217322D03*
Y1209842D03*
X1677165D03*
X1688385D03*
X1677165Y1217322D03*
X1688385D03*
X1677165Y1228543D03*
X1680905Y1236023D03*
Y1232283D03*
X1692126Y1228543D03*
X1684645Y1224803D03*
Y1228543D03*
X1677165Y1224803D03*
X1688385Y1232283D03*
Y1236023D03*
X1692126Y1243503D03*
X1684645Y1239763D03*
X1677165D03*
X1692126Y1247243D03*
X1695866Y1090157D03*
Y1082676D03*
Y1101377D03*
Y1123818D03*
Y1116338D03*
Y1108858D03*
X1700236Y1136909D03*
X1695866Y1131299D03*
X1693996Y1166830D03*
X1697736D03*
X1695866Y1198621D03*
Y1213582D03*
Y1206102D03*
Y1228543D03*
Y1247243D03*
G54D43*
X718503Y-38525D03*
X718500Y-33320D03*
Y-30420D03*
X718488Y-36010D03*
X721756Y-38539D03*
X724781Y-37219D03*
X721741Y-36024D03*
X838503Y-77705D03*
X841756Y-77719D03*
X838500Y-72500D03*
X838488Y-75190D03*
X841741Y-75204D03*
X844781Y-76399D03*
X838500Y-69600D03*
X1005256Y-48539D03*
X1002003D03*
X1005241Y-46024D03*
X1001988D03*
X1008281Y-47219D03*
X1002000Y-40834D03*
X1005256Y-38239D03*
X1002003Y-38225D03*
X1002000Y-43334D03*
X1005241Y-35724D03*
X1002000Y-32720D03*
X1001988Y-35710D03*
X1002000Y-30120D03*
X1008281Y-36919D03*
X1075256Y-77419D03*
X1072003Y-77405D03*
X1071988Y-85290D03*
X1075241D03*
X1072000Y-82600D03*
X1072003Y-87805D03*
X1075256D03*
X1072000Y-80100D03*
Y-72000D03*
Y-69400D03*
X1075241Y-74904D03*
X1071988Y-74890D03*
X1078281Y-86399D03*
Y-76099D03*
X1291756Y-48669D03*
X1288503D03*
X1291741Y-46154D03*
X1288488D03*
X1294781Y-47349D03*
X1288500Y-40964D03*
X1291756Y-38369D03*
X1288503Y-38355D03*
X1288500Y-43464D03*
X1291741Y-35854D03*
X1288500Y-32950D03*
X1288488Y-35840D03*
X1288500Y-30350D03*
X1294781Y-37049D03*
X1328500Y-80100D03*
X1331756Y-77419D03*
X1328503Y-77405D03*
X1331756Y-87805D03*
X1328503D03*
X1328500Y-82600D03*
X1331741Y-85290D03*
X1328488D03*
X1334781Y-86499D03*
X1331741Y-74904D03*
X1328500Y-72000D03*
X1328488Y-74890D03*
X1328500Y-69400D03*
X1334781Y-76099D03*
X1576256Y-48799D03*
X1573003D03*
X1576241Y-46284D03*
X1572988D03*
X1579281Y-47479D03*
X1573000Y-41094D03*
X1576256Y-38499D03*
X1573003Y-38485D03*
X1573000Y-43594D03*
X1576241Y-35984D03*
X1573000Y-33080D03*
X1572988Y-35970D03*
X1573000Y-30480D03*
X1579281Y-37179D03*
X1583000Y-80014D03*
X1586256Y-77419D03*
X1583003Y-77405D03*
X1586256Y-87719D03*
X1583003D03*
X1583000Y-82514D03*
X1586241Y-85204D03*
X1582988D03*
X1589281Y-86399D03*
X1586241Y-74904D03*
X1583000Y-72000D03*
X1582988Y-74890D03*
X1583000Y-69400D03*
X1589281Y-76099D03*
G54D25*
X56348Y1727941D03*
Y1737941D03*
X56248Y1750941D03*
X56348Y1773941D03*
X56248Y1760941D03*
X56348Y1783941D03*
X56248Y1806941D03*
Y1796941D03*
X308448Y1737941D03*
Y1727941D03*
Y1750941D03*
Y1760941D03*
Y1773941D03*
Y1783941D03*
X308348Y1796941D03*
Y1806941D03*
X343286Y1738583D03*
Y1728583D03*
X343112Y1751624D03*
X343212Y1774624D03*
X343112Y1761624D03*
X343212Y1784624D03*
Y1797624D03*
Y1807624D03*
X595386Y1728583D03*
Y1738583D03*
X595312Y1751624D03*
Y1774624D03*
Y1761624D03*
Y1784624D03*
Y1807624D03*
Y1797624D03*
X630083Y1738286D03*
Y1728286D03*
X629861Y1751765D03*
X629711Y1775438D03*
X629861Y1761765D03*
X629711Y1785438D03*
X629475Y1798845D03*
Y1808845D03*
X882183Y1728286D03*
Y1738286D03*
X881911Y1751765D03*
X881761Y1775438D03*
X881911Y1761765D03*
X881761Y1785438D03*
X881525Y1798845D03*
Y1808845D03*
X917279Y1738990D03*
Y1728990D03*
X917163Y1752566D03*
Y1762566D03*
X917073Y1786014D03*
Y1776014D03*
X917166Y1800435D03*
Y1810435D03*
X1169329Y1728990D03*
Y1738990D03*
X1169263Y1752566D03*
Y1762566D03*
X1169123Y1776014D03*
Y1786014D03*
X1169216Y1800435D03*
Y1810435D03*
G54D39*
X318448Y1727941D03*
Y1737941D03*
Y1773941D03*
Y1783941D03*
X605312Y1751624D03*
Y1761624D03*
Y1807624D03*
Y1797624D03*
X891911Y1751765D03*
Y1761765D03*
X891525Y1808845D03*
Y1798845D03*
X1179263Y1752566D03*
Y1762566D03*
X1179216Y1800435D03*
Y1810435D03*
G54D56*
X1250055Y1710189D03*
Y1720189D03*
Y1739208D03*
Y1749208D03*
X1250048Y1768377D03*
Y1778377D03*
X1248555Y1797909D03*
Y1807909D03*
X1734069Y1710189D03*
Y1720189D03*
Y1739208D03*
Y1749208D03*
X1734062Y1768377D03*
Y1778377D03*
X1734069Y1797909D03*
Y1807909D03*
G54D51*
X1011187Y-43526D03*
Y-40126D03*
X1081187Y-79306D03*
Y-82706D03*
X1225405Y-79278D03*
Y-82678D03*
X1230761Y-43628D03*
Y-40228D03*
X1297687Y-40256D03*
Y-43656D03*
X1337687Y-79306D03*
Y-82706D03*
X1481905Y-79278D03*
Y-82678D03*
X1517261Y-40358D03*
Y-43758D03*
X1592187Y-79306D03*
Y-82706D03*
X1582187Y-43786D03*
Y-40386D03*
X1736405Y-79278D03*
Y-82678D03*
X1801761Y-43888D03*
Y-40488D03*
G54D11*
X13780Y1226024D03*
X79331Y1186654D03*
X390354Y1141024D03*
X536418Y1086654D03*
X854291Y1225118D03*
X993504Y1170748D03*
X1304528Y1141024D03*
X1450591Y1086654D03*
X1761614Y1215000D03*
X1827165Y1235630D03*
G54D41*
X661674Y23622D03*
G54D18*
X23622Y1604724D03*
X62205Y765197D03*
X74016Y333464D03*
X102224Y70866D03*
X409488Y1604724D03*
X433130Y70866D03*
X463387Y286221D03*
X463386Y765197D03*
X785039Y1547638D03*
X890217Y23622D03*
X920473Y765196D03*
X1055905Y1547637D03*
X1118760Y23622D03*
X1347303Y70866D03*
X1377559Y286220D03*
Y765197D03*
X1431457Y1604724D03*
X1575846Y23622D03*
X1766929Y333464D03*
X1778740Y765197D03*
X1795010Y23622D03*
X1817323Y1604724D03*
G54D19*
X28819Y81575D03*
X73307Y61614D03*
X131181Y81575D03*
X175669Y61614D03*
X233543Y81575D03*
X278032Y61614D03*
X335906Y81575D03*
X380394Y61614D03*
X485886Y81595D03*
X530394Y61614D03*
X588248Y81594D03*
X632756Y61614D03*
X690611Y81595D03*
X735118Y61614D03*
X792973Y81595D03*
X837480Y61614D03*
X942973Y81595D03*
X987480Y61614D03*
X1045335Y81595D03*
X1089843Y61614D03*
X1147697Y81595D03*
X1192205Y61614D03*
X1250060Y81595D03*
X1294567Y61614D03*
X1400060Y81595D03*
X1444567Y61614D03*
X1502441Y81575D03*
X1546929Y61614D03*
X1604784Y81595D03*
X1649291Y61614D03*
X1707146Y81595D03*
X1751654Y61614D03*
G54D35*
X173829Y455492D03*
Y583957D03*
X202844Y455492D03*
Y583957D03*
X630915Y455492D03*
Y583957D03*
X659930Y455492D03*
Y583957D03*
X1088002Y455492D03*
Y583957D03*
X1117017Y455492D03*
Y583957D03*
X1545089Y455492D03*
Y583957D03*
X1574104Y455492D03*
Y583957D03*
G54D59*
X1795453Y812874D03*
Y834922D03*
G54D45*
X849441Y1367717D03*
G54D47*
X895384Y228740D03*
Y276772D03*
X923336Y226772D03*
Y278740D03*
G54D53*
X1030635Y764546D03*
G54D60*
X1803917Y823898D03*
G54D57*
X1747253Y1715189D03*
Y1744208D03*
X1747246Y1773377D03*
G54D58*
X1747253Y1802909D03*
G54D61*
X1817323Y1567323D03*
G54D13*
X19685Y-83298D03*
Y1801195D03*
X1821260Y-83298D03*
Y1801195D03*
G54D29*
X116731Y1066535D03*
Y1263386D03*
X352952Y1066535D03*
Y1263386D03*
X573818Y1066535D03*
Y1263386D03*
X810038Y1066535D03*
Y1263386D03*
X1030905Y1066535D03*
Y1263386D03*
X1267125Y1066535D03*
Y1263386D03*
X1487991Y1066535D03*
Y1263386D03*
X1724212Y1066535D03*
Y1263386D03*
G54D17*
X26789Y1373669D03*
X184851Y334492D03*
X235433Y1580079D03*
Y1626339D03*
X581890Y1580079D03*
Y1626339D03*
X1259055Y1580079D03*
Y1626339D03*
X1605512Y1580079D03*
Y1626339D03*
X1796847Y1517889D03*
X1809883Y120792D03*
G54D44*
X770472Y1490945D03*
X820079Y388583D03*
X1020866D03*
X1070472Y1490945D03*
G54D31*
X109882Y1453504D03*
Y1468859D03*
Y1484213D03*
Y1499567D03*
Y1514922D03*
Y1555867D03*
Y1571221D03*
Y1586575D03*
Y1601930D03*
Y1617284D03*
X127205Y1453504D03*
X118543Y1457835D03*
X127205Y1468859D03*
X118543Y1473189D03*
X127205Y1484213D03*
X118543Y1488544D03*
X127205Y1499567D03*
Y1514922D03*
X118543Y1503898D03*
Y1519252D03*
X127205Y1555867D03*
X118543Y1560197D03*
X127205Y1571221D03*
X118543Y1575552D03*
X127205Y1586575D03*
X118543Y1590906D03*
X127205Y1601930D03*
X118543Y1606260D03*
X127205Y1617284D03*
X118543Y1621615D03*
X144528Y1453504D03*
X135866Y1457835D03*
X144528Y1468859D03*
X135866Y1473189D03*
X144528Y1484213D03*
X135866Y1488544D03*
X144528Y1499567D03*
Y1514922D03*
X135866Y1503898D03*
Y1519252D03*
X144528Y1555867D03*
X135866Y1560197D03*
X144528Y1571221D03*
X135866Y1575552D03*
X144528Y1586575D03*
X135866Y1590906D03*
X144528Y1601930D03*
X135866Y1606260D03*
X144528Y1617284D03*
X135866Y1621615D03*
X161850Y1453504D03*
X153189Y1457835D03*
X161850Y1468859D03*
X153189Y1473189D03*
X161850Y1484213D03*
X153189Y1488544D03*
X161850Y1499567D03*
Y1514922D03*
X153189Y1503898D03*
Y1519252D03*
X161850Y1555867D03*
X153189Y1560197D03*
X161850Y1571221D03*
X153189Y1575552D03*
X161850Y1586575D03*
X153189Y1590906D03*
X161850Y1601930D03*
X153189Y1606260D03*
X161850Y1617284D03*
X153189Y1621615D03*
X179173Y1453504D03*
X170512Y1457835D03*
X179173Y1468859D03*
X170512Y1473189D03*
X179173Y1484213D03*
X170512Y1488544D03*
X179173Y1499567D03*
Y1514922D03*
X170512Y1503898D03*
Y1519252D03*
X179173Y1555867D03*
X170512Y1560197D03*
X179173Y1571221D03*
X170512Y1575552D03*
X179173Y1586575D03*
X170512Y1590906D03*
X179173Y1601930D03*
X170512Y1606260D03*
X179173Y1617284D03*
X170512Y1621615D03*
X187835Y1457835D03*
Y1473189D03*
Y1488544D03*
Y1503898D03*
Y1519252D03*
Y1560197D03*
Y1575552D03*
Y1590906D03*
Y1606260D03*
Y1621615D03*
X283110Y1453504D03*
X291771Y1457835D03*
X283110Y1468859D03*
X291771Y1473189D03*
X283110Y1484213D03*
X291771Y1488544D03*
X283110Y1499567D03*
X291771Y1503898D03*
X283110Y1514922D03*
X291771Y1519252D03*
X283110Y1555867D03*
X291771Y1560197D03*
X283110Y1571221D03*
X291771Y1575552D03*
X283110Y1586575D03*
X291771Y1590906D03*
X283110Y1601930D03*
X291771Y1606260D03*
X283110Y1617284D03*
X291771Y1621615D03*
X300433Y1453504D03*
X309094Y1457835D03*
X300433Y1468859D03*
X309094Y1473189D03*
X300433Y1484213D03*
X309094Y1488544D03*
X300433Y1499567D03*
X309094Y1503898D03*
X300433Y1514922D03*
X309094Y1519252D03*
X300433Y1555867D03*
X309094Y1560197D03*
X300433Y1571221D03*
X309094Y1575552D03*
X300433Y1586575D03*
X309094Y1590906D03*
X300433Y1601930D03*
X309094Y1606260D03*
X300433Y1617284D03*
X309094Y1621615D03*
X317756Y1453504D03*
X326417Y1457835D03*
X317756Y1468859D03*
X326417Y1473189D03*
X317756Y1484213D03*
X326417Y1488544D03*
X317756Y1499567D03*
X326417Y1503898D03*
X317756Y1514922D03*
X326417Y1519252D03*
X317756Y1555867D03*
X326417Y1560197D03*
X317756Y1571221D03*
X326417Y1575552D03*
X317756Y1586575D03*
X326417Y1590906D03*
X317756Y1601930D03*
X326417Y1606260D03*
X317756Y1617284D03*
X326417Y1621615D03*
X335078Y1453504D03*
X343740Y1457835D03*
X335078Y1468859D03*
X343740Y1473189D03*
X335078Y1484213D03*
X343740Y1488544D03*
X335078Y1499567D03*
X343740Y1503898D03*
X335078Y1514922D03*
X343740Y1519252D03*
X335078Y1555867D03*
X343740Y1560197D03*
X335078Y1571221D03*
X343740Y1575552D03*
X335078Y1586575D03*
X343740Y1590906D03*
X335078Y1601930D03*
X343740Y1606260D03*
X335078Y1617284D03*
X343740Y1621615D03*
X352401Y1453504D03*
X361063Y1457835D03*
X352401Y1468859D03*
X361063Y1473189D03*
X352401Y1484213D03*
X361063Y1488544D03*
X352401Y1499567D03*
X361063Y1503898D03*
X352401Y1514922D03*
X361063Y1519252D03*
X352401Y1555867D03*
X361063Y1560197D03*
X352401Y1571221D03*
X361063Y1575552D03*
X352401Y1586575D03*
X361063Y1590906D03*
X352401Y1601930D03*
X361063Y1606260D03*
X352401Y1617284D03*
X361063Y1621615D03*
X456339Y1453504D03*
Y1468859D03*
Y1484213D03*
Y1499567D03*
Y1514922D03*
Y1555867D03*
Y1571221D03*
Y1586575D03*
Y1601930D03*
Y1617284D03*
X473662Y1453504D03*
X465000Y1457835D03*
X473662Y1468859D03*
X465000Y1473189D03*
X473662Y1484213D03*
X465000Y1488544D03*
X473662Y1499567D03*
Y1514922D03*
X465000Y1503898D03*
Y1519252D03*
X473662Y1555867D03*
X465000Y1560197D03*
X473662Y1571221D03*
X465000Y1575552D03*
X473662Y1586575D03*
X465000Y1590906D03*
X473662Y1601930D03*
X465000Y1606260D03*
X473662Y1617284D03*
X465000Y1621615D03*
X490985Y1453504D03*
X482323Y1457835D03*
X490985Y1468859D03*
X482323Y1473189D03*
X490985Y1484213D03*
X482323Y1488544D03*
X490985Y1499567D03*
Y1514922D03*
X482323Y1503898D03*
Y1519252D03*
X490985Y1555867D03*
X482323Y1560197D03*
X490985Y1571221D03*
X482323Y1575552D03*
X490985Y1586575D03*
X482323Y1590906D03*
X490985Y1601930D03*
X482323Y1606260D03*
X490985Y1617284D03*
X482323Y1621615D03*
X508307Y1453504D03*
X499646Y1457835D03*
X508307Y1468859D03*
X499646Y1473189D03*
X508307Y1484213D03*
X499646Y1488544D03*
X508307Y1499567D03*
Y1514922D03*
X499646Y1503898D03*
Y1519252D03*
X508307Y1555867D03*
X499646Y1560197D03*
X508307Y1571221D03*
X499646Y1575552D03*
X508307Y1586575D03*
X499646Y1590906D03*
X508307Y1601930D03*
X499646Y1606260D03*
X508307Y1617284D03*
X499646Y1621615D03*
X516969Y1457835D03*
Y1473189D03*
Y1488544D03*
Y1503898D03*
Y1519252D03*
Y1560197D03*
Y1575552D03*
Y1590906D03*
Y1606260D03*
Y1621615D03*
X525630Y1453504D03*
X534292Y1457835D03*
X525630Y1468859D03*
X534292Y1473189D03*
X525630Y1484213D03*
X534292Y1488544D03*
X525630Y1499567D03*
X534292Y1503898D03*
X525630Y1514922D03*
X534292Y1519252D03*
X525630Y1555867D03*
X534292Y1560197D03*
X525630Y1571221D03*
X534292Y1575552D03*
X525630Y1586575D03*
X534292Y1590906D03*
X525630Y1601930D03*
X534292Y1606260D03*
X525630Y1617284D03*
X534292Y1621615D03*
X629567Y1453504D03*
X638228Y1457835D03*
X629567Y1468859D03*
X638228Y1473189D03*
X629567Y1484213D03*
X638228Y1488544D03*
X629567Y1499567D03*
X638228Y1503898D03*
X629567Y1514922D03*
X638228Y1519252D03*
X629567Y1555867D03*
X638228Y1560197D03*
X629567Y1571221D03*
X638228Y1575552D03*
X629567Y1586575D03*
X638228Y1590906D03*
X629567Y1601930D03*
X638228Y1606260D03*
X629567Y1617284D03*
X638228Y1621615D03*
X646890Y1453504D03*
Y1468859D03*
Y1484213D03*
Y1499567D03*
Y1514922D03*
Y1555867D03*
Y1571221D03*
Y1586575D03*
Y1601930D03*
Y1617284D03*
X664213Y1453504D03*
X655551Y1457835D03*
X664213Y1468859D03*
X655551Y1473189D03*
X664213Y1484213D03*
X655551Y1488544D03*
X664213Y1499567D03*
Y1514922D03*
X655551Y1503898D03*
Y1519252D03*
X664213Y1555867D03*
X655551Y1560197D03*
X664213Y1571221D03*
X655551Y1575552D03*
X664213Y1586575D03*
X655551Y1590906D03*
X664213Y1601930D03*
X655551Y1606260D03*
X664213Y1617284D03*
X655551Y1621615D03*
X681535Y1453504D03*
X672874Y1457835D03*
X681535Y1468859D03*
X672874Y1473189D03*
X681535Y1484213D03*
X672874Y1488544D03*
X681535Y1499567D03*
Y1514922D03*
X672874Y1503898D03*
Y1519252D03*
X681535Y1555867D03*
X672874Y1560197D03*
X681535Y1571221D03*
X672874Y1575552D03*
X681535Y1586575D03*
X672874Y1590906D03*
X681535Y1601930D03*
X672874Y1606260D03*
X681535Y1617284D03*
X672874Y1621615D03*
X698858Y1453504D03*
X690197Y1457835D03*
X698858Y1468859D03*
X690197Y1473189D03*
X698858Y1484213D03*
X690197Y1488544D03*
X698858Y1499567D03*
Y1514922D03*
X690197Y1503898D03*
Y1519252D03*
X698858Y1555867D03*
X690197Y1560197D03*
X698858Y1571221D03*
X690197Y1575552D03*
X698858Y1586575D03*
X690197Y1590906D03*
X698858Y1601930D03*
X690197Y1606260D03*
X698858Y1617284D03*
X690197Y1621615D03*
X707520Y1457835D03*
Y1473189D03*
Y1488544D03*
Y1503898D03*
Y1519252D03*
Y1560197D03*
Y1575552D03*
Y1590906D03*
Y1606260D03*
Y1621615D03*
X1131850Y1453504D03*
X1140511Y1457835D03*
X1131850Y1468859D03*
X1140511Y1473189D03*
X1131850Y1484213D03*
X1140511Y1488544D03*
X1131850Y1499567D03*
X1140511Y1503898D03*
X1131850Y1514922D03*
X1140511Y1519252D03*
X1131850Y1555867D03*
X1140511Y1560197D03*
X1131850Y1571221D03*
X1140511Y1575552D03*
X1131850Y1586575D03*
X1140511Y1590906D03*
X1131850Y1601930D03*
X1140511Y1606260D03*
X1131850Y1617284D03*
X1140511Y1621615D03*
X1149173Y1453504D03*
X1157834Y1457835D03*
X1149173Y1468859D03*
X1157834Y1473189D03*
X1149173Y1484213D03*
X1157834Y1488544D03*
X1149173Y1499567D03*
X1157834Y1503898D03*
X1149173Y1514922D03*
X1157834Y1519252D03*
X1149173Y1555867D03*
X1157834Y1560197D03*
X1149173Y1571221D03*
X1157834Y1575552D03*
X1149173Y1586575D03*
X1157834Y1590906D03*
X1149173Y1601930D03*
X1157834Y1606260D03*
X1149173Y1617284D03*
X1157834Y1621615D03*
X1166496Y1453504D03*
Y1468859D03*
Y1484213D03*
Y1499567D03*
Y1514922D03*
Y1555867D03*
Y1571221D03*
Y1586575D03*
Y1601930D03*
Y1617284D03*
X1183818Y1453504D03*
X1175157Y1457835D03*
X1183818Y1468859D03*
X1175157Y1473189D03*
X1183818Y1484213D03*
X1175157Y1488544D03*
X1183818Y1499567D03*
Y1514922D03*
X1175157Y1503898D03*
Y1519252D03*
X1183818Y1555867D03*
X1175157Y1560197D03*
X1183818Y1571221D03*
X1175157Y1575552D03*
X1183818Y1586575D03*
X1175157Y1590906D03*
X1183818Y1601930D03*
X1175157Y1606260D03*
X1183818Y1617284D03*
X1175157Y1621615D03*
X1201141Y1453504D03*
X1192480Y1457835D03*
X1201141Y1468859D03*
X1192480Y1473189D03*
X1201141Y1484213D03*
X1192480Y1488544D03*
X1201141Y1499567D03*
Y1514922D03*
X1192480Y1503898D03*
Y1519252D03*
X1201141Y1555867D03*
X1192480Y1560197D03*
X1201141Y1571221D03*
X1192480Y1575552D03*
X1201141Y1586575D03*
X1192480Y1590906D03*
X1201141Y1601930D03*
X1192480Y1606260D03*
X1201141Y1617284D03*
X1192480Y1621615D03*
X1209803Y1457835D03*
Y1473189D03*
Y1488544D03*
Y1503898D03*
Y1519252D03*
Y1560197D03*
Y1575552D03*
Y1590906D03*
Y1606260D03*
Y1621615D03*
X1305079Y1453504D03*
X1313740Y1457835D03*
X1305079Y1468859D03*
X1313740Y1473189D03*
X1305079Y1484213D03*
X1313740Y1488544D03*
X1305079Y1499567D03*
X1313740Y1503898D03*
X1305079Y1514922D03*
X1313740Y1519252D03*
X1305079Y1555867D03*
X1313740Y1560197D03*
X1305079Y1571221D03*
X1313740Y1575552D03*
X1305079Y1586575D03*
X1313740Y1590906D03*
X1305079Y1601930D03*
X1313740Y1606260D03*
X1305079Y1617284D03*
X1313740Y1621615D03*
X1322402Y1453504D03*
X1331063Y1457835D03*
X1322402Y1468859D03*
X1331063Y1473189D03*
X1322402Y1484213D03*
X1331063Y1488544D03*
X1322402Y1499567D03*
X1331063Y1503898D03*
X1322402Y1514922D03*
X1331063Y1519252D03*
X1322402Y1555867D03*
X1331063Y1560197D03*
X1322402Y1571221D03*
X1331063Y1575552D03*
X1322402Y1586575D03*
X1331063Y1590906D03*
X1322402Y1601930D03*
X1331063Y1606260D03*
X1322402Y1617284D03*
X1331063Y1621615D03*
X1339725Y1453504D03*
X1348386Y1457835D03*
X1339725Y1468859D03*
X1348386Y1473189D03*
X1339725Y1484213D03*
X1348386Y1488544D03*
X1339725Y1499567D03*
X1348386Y1503898D03*
X1339725Y1514922D03*
X1348386Y1519252D03*
X1339725Y1555867D03*
X1348386Y1560197D03*
X1339725Y1571221D03*
X1348386Y1575552D03*
X1339725Y1586575D03*
X1348386Y1590906D03*
X1339725Y1601930D03*
X1348386Y1606260D03*
X1339725Y1617284D03*
X1348386Y1621615D03*
X1357047Y1453504D03*
X1365709Y1457835D03*
X1357047Y1468859D03*
X1365709Y1473189D03*
X1357047Y1484213D03*
X1365709Y1488544D03*
X1357047Y1499567D03*
X1365709Y1503898D03*
X1357047Y1514922D03*
X1365709Y1519252D03*
X1357047Y1555867D03*
X1365709Y1560197D03*
X1357047Y1571221D03*
X1365709Y1575552D03*
X1357047Y1586575D03*
X1365709Y1590906D03*
X1357047Y1601930D03*
X1365709Y1606260D03*
X1357047Y1617284D03*
X1365709Y1621615D03*
X1374370Y1453504D03*
X1383032Y1457835D03*
X1374370Y1468859D03*
X1383032Y1473189D03*
X1374370Y1484213D03*
X1383032Y1488544D03*
X1374370Y1499567D03*
X1383032Y1503898D03*
X1374370Y1514922D03*
X1383032Y1519252D03*
X1374370Y1555867D03*
X1383032Y1560197D03*
X1374370Y1571221D03*
X1383032Y1575552D03*
X1374370Y1586575D03*
X1383032Y1590906D03*
X1374370Y1601930D03*
X1383032Y1606260D03*
X1374370Y1617284D03*
X1383032Y1621615D03*
X1478307Y1453504D03*
Y1468859D03*
Y1484213D03*
Y1499567D03*
Y1514922D03*
Y1555867D03*
Y1571221D03*
Y1586575D03*
Y1601930D03*
Y1617284D03*
X1495630Y1453504D03*
X1486968Y1457835D03*
X1495630Y1468859D03*
X1486968Y1473189D03*
X1495630Y1484213D03*
X1486968Y1488544D03*
X1495630Y1499567D03*
Y1514922D03*
X1486968Y1503898D03*
Y1519252D03*
X1495630Y1555867D03*
X1486968Y1560197D03*
X1495630Y1571221D03*
X1486968Y1575552D03*
X1495630Y1586575D03*
X1486968Y1590906D03*
X1495630Y1601930D03*
X1486968Y1606260D03*
X1495630Y1617284D03*
X1486968Y1621615D03*
X1512953Y1453504D03*
X1504291Y1457835D03*
X1512953Y1468859D03*
X1504291Y1473189D03*
X1512953Y1484213D03*
X1504291Y1488544D03*
X1512953Y1499567D03*
Y1514922D03*
X1504291Y1503898D03*
Y1519252D03*
X1512953Y1555867D03*
X1504291Y1560197D03*
X1512953Y1571221D03*
X1504291Y1575552D03*
X1512953Y1586575D03*
X1504291Y1590906D03*
X1512953Y1601930D03*
X1504291Y1606260D03*
X1512953Y1617284D03*
X1504291Y1621615D03*
X1530275Y1453504D03*
X1521614Y1457835D03*
X1530275Y1468859D03*
X1521614Y1473189D03*
X1530275Y1484213D03*
X1521614Y1488544D03*
X1530275Y1499567D03*
Y1514922D03*
X1521614Y1503898D03*
Y1519252D03*
X1530275Y1555867D03*
X1521614Y1560197D03*
X1530275Y1571221D03*
X1521614Y1575552D03*
X1530275Y1586575D03*
X1521614Y1590906D03*
X1530275Y1601930D03*
X1521614Y1606260D03*
X1530275Y1617284D03*
X1521614Y1621615D03*
X1547598Y1453504D03*
X1538937Y1457835D03*
X1547598Y1468859D03*
X1538937Y1473189D03*
X1547598Y1484213D03*
X1538937Y1488544D03*
X1547598Y1499567D03*
Y1514922D03*
X1538937Y1503898D03*
Y1519252D03*
X1547598Y1555867D03*
X1538937Y1560197D03*
X1547598Y1571221D03*
X1538937Y1575552D03*
X1547598Y1586575D03*
X1538937Y1590906D03*
X1547598Y1601930D03*
X1538937Y1606260D03*
X1547598Y1617284D03*
X1538937Y1621615D03*
X1556260Y1457835D03*
Y1473189D03*
Y1488544D03*
Y1503898D03*
Y1519252D03*
Y1560197D03*
Y1575552D03*
Y1590906D03*
Y1606260D03*
Y1621615D03*
X1651535Y1453504D03*
X1660196Y1457835D03*
X1651535Y1468859D03*
X1660196Y1473189D03*
X1651535Y1484213D03*
X1660196Y1488544D03*
X1651535Y1499567D03*
X1660196Y1503898D03*
X1651535Y1514922D03*
X1660196Y1519252D03*
X1651535Y1555867D03*
X1660196Y1560197D03*
X1651535Y1571221D03*
X1660196Y1575552D03*
X1651535Y1586575D03*
X1660196Y1590906D03*
X1651535Y1601930D03*
X1660196Y1606260D03*
X1651535Y1617284D03*
X1660196Y1621615D03*
X1668858Y1453504D03*
X1677519Y1457835D03*
X1668858Y1468859D03*
X1677519Y1473189D03*
X1668858Y1484213D03*
X1677519Y1488544D03*
X1668858Y1499567D03*
X1677519Y1503898D03*
X1668858Y1514922D03*
X1677519Y1519252D03*
X1668858Y1555867D03*
X1677519Y1560197D03*
X1668858Y1571221D03*
X1677519Y1575552D03*
X1668858Y1586575D03*
X1677519Y1590906D03*
X1668858Y1601930D03*
X1677519Y1606260D03*
X1668858Y1617284D03*
X1677519Y1621615D03*
X1686181Y1453504D03*
Y1468859D03*
Y1484213D03*
Y1499567D03*
Y1514922D03*
Y1555867D03*
Y1571221D03*
Y1586575D03*
Y1601930D03*
Y1617284D03*
X1703503Y1453504D03*
X1694842Y1457835D03*
X1703503Y1468859D03*
X1694842Y1473189D03*
X1703503Y1484213D03*
X1694842Y1488544D03*
X1703503Y1499567D03*
Y1514922D03*
X1694842Y1503898D03*
Y1519252D03*
X1703503Y1555867D03*
X1694842Y1560197D03*
X1703503Y1571221D03*
X1694842Y1575552D03*
X1703503Y1586575D03*
X1694842Y1590906D03*
X1703503Y1601930D03*
X1694842Y1606260D03*
X1703503Y1617284D03*
X1694842Y1621615D03*
X1720826Y1453504D03*
X1712165Y1457835D03*
X1720826Y1468859D03*
X1712165Y1473189D03*
X1720826Y1484213D03*
X1712165Y1488544D03*
X1720826Y1499567D03*
Y1514922D03*
X1712165Y1503898D03*
Y1519252D03*
X1720826Y1555867D03*
X1712165Y1560197D03*
X1720826Y1571221D03*
X1712165Y1575552D03*
X1720826Y1586575D03*
X1712165Y1590906D03*
X1720826Y1601930D03*
X1712165Y1606260D03*
X1720826Y1617284D03*
X1712165Y1621615D03*
X1729488Y1457835D03*
Y1473189D03*
Y1488544D03*
Y1503898D03*
Y1519252D03*
Y1560197D03*
Y1575552D03*
Y1590906D03*
Y1606260D03*
Y1621615D03*
G54D37*
X235433Y1606142D03*
X581890D03*
X1259055D03*
X1605512D03*
G54D16*
X15139Y198883D03*
Y201683D03*
X18564Y238589D03*
X6690Y1496782D03*
X34520Y213539D03*
X36201Y238714D03*
X21530Y236121D03*
X27966Y238689D03*
X27625Y663094D03*
X25818Y682139D03*
X28818D03*
X32079Y1517641D03*
X65189Y228961D03*
Y231461D03*
Y223661D03*
Y226461D03*
X54733Y231226D03*
Y228726D03*
Y223726D03*
Y226226D03*
X67622Y572842D03*
X64408Y572975D03*
X73110Y101701D03*
X78501Y110445D03*
Y115401D03*
Y129574D03*
Y124618D03*
X73158Y229286D03*
X76851Y222212D03*
Y224712D03*
X73158Y231786D03*
X75777Y585507D03*
X71184D03*
X71730Y579475D03*
X71228Y590145D03*
X75822Y590190D03*
X75684Y605443D03*
X83684D03*
X78129Y656900D03*
X72314Y680207D03*
Y683407D03*
X82714Y674707D03*
X71928Y873683D03*
X88903Y117557D03*
Y122513D03*
Y131731D03*
Y136687D03*
X94390Y293645D03*
Y290845D03*
Y288345D03*
X91890Y293645D03*
Y290845D03*
Y288345D03*
X93456Y649838D03*
X89432Y668293D03*
X92134D03*
X85614Y674707D03*
X87714Y684607D03*
X117501Y198883D03*
Y201683D03*
X111275Y1008262D03*
Y1011762D03*
X130328Y238689D03*
X123892Y236121D03*
X120926Y238589D03*
X136882Y213539D03*
X138563Y238714D03*
X143186Y402291D03*
Y397335D03*
X140786Y416465D03*
Y411509D03*
Y425682D03*
Y430638D03*
Y439855D03*
Y444811D03*
Y468609D03*
Y473565D03*
Y487738D03*
Y482782D03*
Y512743D03*
Y517699D03*
Y531872D03*
Y526916D03*
X157095Y228726D03*
Y231226D03*
X167551Y223661D03*
X157095Y226226D03*
Y223726D03*
X151188Y390223D03*
Y395179D03*
Y404396D03*
Y409352D03*
Y423525D03*
Y418569D03*
Y432743D03*
Y437699D03*
Y489895D03*
Y480677D03*
Y475721D03*
Y494851D03*
Y519855D03*
Y538984D03*
Y534028D03*
Y524811D03*
X175472Y101701D03*
X175520Y229286D03*
X179213Y224712D03*
Y222212D03*
X167551Y231461D03*
Y228961D03*
Y226461D03*
X175520Y231786D03*
X194189Y103621D03*
X196752Y293645D03*
Y290845D03*
Y288345D03*
X194252Y293645D03*
Y290845D03*
Y288345D03*
X203740Y567914D03*
Y565414D03*
Y570414D03*
Y575414D03*
Y572914D03*
X219863Y198883D03*
Y201683D03*
X226254Y236121D03*
X223288Y238589D03*
X239244Y213539D03*
X232690Y238689D03*
X240925Y238714D03*
X259457Y228726D03*
Y231226D03*
Y226226D03*
Y223726D03*
X251802Y824128D03*
X277834Y101701D03*
X269913Y228961D03*
Y226461D03*
Y223661D03*
X277882Y229286D03*
X269913Y231461D03*
X277882Y231786D03*
X286129Y36971D03*
X296551Y103621D03*
X281575Y224712D03*
Y222212D03*
X296614Y293645D03*
Y290845D03*
Y288345D03*
X309106Y37543D03*
X299114Y290845D03*
Y288345D03*
Y293645D03*
X302966Y324139D03*
X310013Y316731D03*
X301158Y380307D03*
X301308Y395346D03*
X301393Y400039D03*
X322225Y198883D03*
Y201683D03*
X325650Y238589D03*
X328616Y236121D03*
X321549Y445315D03*
Y448115D03*
X323489Y471484D03*
Y466528D03*
Y480701D03*
Y485657D03*
Y515617D03*
Y510661D03*
Y529791D03*
Y524835D03*
Y565657D03*
Y560701D03*
Y574874D03*
Y579830D03*
Y589047D03*
Y594003D03*
Y603221D03*
Y608177D03*
X330905Y11806D03*
Y23806D03*
Y31806D03*
X341606Y213539D03*
X335052Y238689D03*
X343287Y238714D03*
X345050Y458334D03*
X333891Y473640D03*
Y487813D03*
Y478596D03*
Y492769D03*
Y522730D03*
Y517774D03*
Y531947D03*
Y536903D03*
Y572769D03*
Y567813D03*
Y586943D03*
Y581987D03*
Y596160D03*
Y601116D03*
Y610333D03*
Y615289D03*
X347450Y447486D03*
X353670Y488618D03*
Y491118D03*
Y493618D03*
Y496118D03*
X372275Y226461D03*
X361819Y231226D03*
Y228726D03*
Y223726D03*
Y226226D03*
X372275Y228961D03*
Y231461D03*
Y223661D03*
X364954Y450091D03*
X367564Y452740D03*
X365332Y490070D03*
Y487570D03*
X361887Y493758D03*
Y496258D03*
X377020Y782535D03*
X368491Y815092D03*
X368273Y928100D03*
X380196Y101701D03*
X380244Y229286D03*
X383937Y222212D03*
Y224712D03*
X380244Y231786D03*
X393837Y466409D03*
X393823Y487382D03*
X398913Y103621D03*
X398976Y293645D03*
X401476D03*
Y288345D03*
Y290845D03*
X398976Y288345D03*
Y290845D03*
X406843Y399161D03*
Y401661D03*
Y396661D03*
X405603Y668060D03*
X408103D03*
X403103D03*
X400603D03*
Y678060D03*
X405603D03*
X408103D03*
X403103D03*
X406967Y878764D03*
X406415Y874840D03*
X399285Y1081599D03*
X398915Y1097278D03*
X396415D03*
X401711Y1419771D03*
X406667D03*
X400911Y1537902D03*
X407048D03*
X400911Y1544424D03*
X407048Y1549936D03*
X400911D03*
X420050Y33425D03*
X418876Y401661D03*
Y396661D03*
Y399161D03*
X411754Y474513D03*
X424731Y508152D03*
Y513452D03*
Y515952D03*
X414275Y508217D03*
Y510717D03*
Y515717D03*
Y513217D03*
X424731Y510952D03*
X410603Y668060D03*
Y678060D03*
X425759Y869921D03*
Y872721D03*
Y875521D03*
Y867121D03*
Y878321D03*
X411214Y892109D03*
X413012Y1537902D03*
Y1544098D03*
X426196Y1534087D03*
X413012Y1549936D03*
X421616Y1549885D03*
X442704Y506427D03*
X427693Y506520D03*
X438353Y508685D03*
X427693Y509020D03*
X432700Y516277D03*
X429210Y784833D03*
X428759Y869921D03*
Y867121D03*
Y872721D03*
Y875521D03*
Y878321D03*
X432332Y892049D03*
Y897649D03*
Y894849D03*
Y900449D03*
X453544Y461961D03*
X451144Y472809D03*
X447836Y711199D03*
X451889Y1301067D03*
X456832Y1299121D03*
X451889Y1306023D03*
X472226Y198883D03*
Y201683D03*
X473658Y467215D03*
X471048Y464566D03*
X469495Y1011303D03*
Y1023303D03*
Y1017303D03*
X491607Y213539D03*
X478617Y236121D03*
X475651Y238589D03*
X485053Y238689D03*
X481495Y1011303D03*
X475495D03*
X481495Y1023303D03*
Y1017303D03*
X475495Y1023303D03*
X484800Y1302000D03*
X493288Y238714D03*
X522276Y223661D03*
Y226461D03*
Y228961D03*
Y231461D03*
X511820Y231226D03*
Y228726D03*
Y223726D03*
Y226226D03*
X521494Y572975D03*
X524475Y952290D03*
X509471Y981608D03*
X517374Y1287222D03*
X514363Y1287370D03*
X520548Y1287181D03*
X530197Y101701D03*
X530245Y229286D03*
X533938Y222212D03*
Y224712D03*
X530245Y231786D03*
X524708Y572842D03*
X532863Y585507D03*
X528270D03*
X528816Y579475D03*
X532908Y590190D03*
X528314Y590145D03*
X532770Y605443D03*
X528868Y873683D03*
X548914Y103621D03*
X551477Y288345D03*
Y290845D03*
X548977Y288345D03*
Y290845D03*
Y293645D03*
X551477D03*
X540770Y605443D03*
X574588Y201683D03*
X568362Y1008262D03*
Y1011762D03*
X574588Y198883D03*
X587415Y238689D03*
X580979Y236121D03*
X578013Y238589D03*
X577249Y965445D03*
X593969Y213539D03*
X595650Y238714D03*
X600272Y397335D03*
Y402291D03*
X597872Y425682D03*
Y416465D03*
Y411509D03*
Y439855D03*
Y430638D03*
Y444811D03*
Y468609D03*
Y473565D03*
Y487738D03*
Y482782D03*
Y517699D03*
Y531872D03*
Y526916D03*
X606142Y965665D03*
X614182Y223726D03*
Y226226D03*
Y231226D03*
Y228726D03*
X608274Y390223D03*
Y395179D03*
Y404396D03*
Y409352D03*
Y418569D03*
Y423525D03*
Y432743D03*
Y437699D03*
Y489895D03*
Y480677D03*
Y475721D03*
Y494851D03*
Y519855D03*
Y538984D03*
Y534028D03*
Y524811D03*
X632559Y101701D03*
X624638Y231461D03*
X636300Y222212D03*
Y224712D03*
X632607Y229286D03*
X624638Y223661D03*
Y226461D03*
Y228961D03*
X632607Y231786D03*
X651276Y103621D03*
X651339Y290845D03*
Y293645D03*
X653839D03*
Y288345D03*
Y290845D03*
X651339Y288345D03*
X660826Y570414D03*
Y567914D03*
Y565414D03*
Y575414D03*
Y572914D03*
X676950Y201683D03*
X680375Y238589D03*
X683341Y236121D03*
X696331Y213539D03*
X698012Y238714D03*
X689777Y238689D03*
X716544Y228726D03*
Y231226D03*
Y226226D03*
Y223726D03*
X704446Y760611D03*
X713425Y786029D03*
X734921Y101701D03*
X727000Y228961D03*
Y226461D03*
Y223661D03*
X734969Y229286D03*
X727000Y231461D03*
X734969Y231786D03*
X721218Y742131D03*
X720271Y782481D03*
X738662Y224712D03*
Y222212D03*
X744069Y746617D03*
X735576Y861780D03*
X753638Y103621D03*
X760407Y324494D03*
X767099Y316731D03*
X767310Y1599164D03*
X756358Y1616917D03*
X779312Y198883D03*
Y201683D03*
X782737Y238589D03*
X780575Y471484D03*
Y466528D03*
Y480701D03*
Y485657D03*
Y510661D03*
Y515617D03*
Y524835D03*
Y529791D03*
Y560701D03*
Y565657D03*
Y579830D03*
Y574874D03*
Y589047D03*
Y594003D03*
Y603221D03*
Y608177D03*
X798693Y213539D03*
X792139Y238689D03*
X785703Y236121D03*
X790977Y473640D03*
Y487813D03*
Y478596D03*
Y492769D03*
Y517774D03*
Y522730D03*
Y531947D03*
Y536903D03*
Y567813D03*
Y572769D03*
Y581987D03*
Y586943D03*
Y601116D03*
Y596160D03*
Y615289D03*
Y610333D03*
X800374Y238714D03*
X804536Y441486D03*
X802136Y452334D03*
X810756Y491118D03*
Y488618D03*
Y483618D03*
Y486118D03*
X815492Y732917D03*
X829362Y231461D03*
Y228961D03*
Y226461D03*
Y223661D03*
X818906Y228726D03*
Y231226D03*
Y226226D03*
Y223726D03*
X829381Y348036D03*
X824650Y446740D03*
X822040Y444091D03*
X826262Y462326D03*
Y459326D03*
X818973Y491258D03*
Y488758D03*
X822418Y485070D03*
Y482570D03*
X823790Y713375D03*
X823843Y732109D03*
X819890Y736924D03*
X828423Y964731D03*
X837283Y101701D03*
X837331Y229286D03*
X841024Y224712D03*
Y222212D03*
X837331Y231786D03*
X839573Y325327D03*
X856000Y103621D03*
X858563Y293645D03*
Y290845D03*
X856063Y293645D03*
Y290845D03*
X858563Y288345D03*
X856063D03*
X854622Y359004D03*
X873885Y340892D03*
X873733Y357844D03*
X871382Y373971D03*
X875907Y486256D03*
X870137Y669461D03*
X875916Y808965D03*
X886026Y346584D03*
X896592Y362369D03*
Y366369D03*
Y370369D03*
X882907Y480350D03*
X892023Y570176D03*
X890959Y579788D03*
X890956Y588325D03*
X894015Y588253D03*
X895933Y618143D03*
X910076Y304843D03*
X905120D03*
X913206Y336489D03*
X910040Y353532D03*
X902169Y413002D03*
Y418002D03*
Y415502D03*
X913853Y561487D03*
X904393Y570176D03*
X908517D03*
X898815D03*
X898232Y588320D03*
X902635Y588305D03*
X906999Y588274D03*
X905313Y709259D03*
X905050Y720268D03*
X913716Y800815D03*
X899916D03*
X911053Y800510D03*
X901428Y1136426D03*
X904897Y1145169D03*
X902397D03*
X929978Y186854D03*
Y184054D03*
X917906Y321670D03*
X922629Y336609D03*
X922198Y342051D03*
X917858Y331453D03*
X927309Y357267D03*
X921389D03*
X915395D03*
Y363212D03*
X927309Y363239D03*
Y369210D03*
X921468D03*
X915395D03*
X927072Y386992D03*
X919072D03*
X923072D03*
X914202Y418002D03*
Y413002D03*
Y415502D03*
X916590Y800636D03*
X921790Y810965D03*
X926044Y1545370D03*
Y1542370D03*
X938125Y230891D03*
X942805Y223860D03*
X936369Y221292D03*
X940158Y245707D03*
X946064Y252998D03*
X941845Y278968D03*
X939606Y310521D03*
X939653Y317474D03*
X940924Y328959D03*
X936608Y326058D03*
X945120Y326441D03*
X930398Y342050D03*
X936453Y345336D03*
X945599Y345383D03*
X940972Y338238D03*
X943663Y355674D03*
X944900Y363700D03*
X938499Y362202D03*
X940600Y370600D03*
X939314Y707847D03*
X931244Y720471D03*
X936026Y730600D03*
X941916Y808965D03*
X949359Y198710D03*
X951040Y223885D03*
X956348Y356371D03*
X952170Y356131D03*
X958823Y362802D03*
X954888Y369513D03*
X948400Y370045D03*
X956035Y1545333D03*
X959035D03*
X953035D03*
X950035D03*
X959035Y1542333D03*
X956035D03*
X953035D03*
X950035D03*
X968906Y223726D03*
Y228726D03*
Y231226D03*
X979362Y223661D03*
X968906Y226226D03*
X973338Y345018D03*
X978581Y572975D03*
X971144Y908972D03*
X965405Y1136426D03*
X987283Y101701D03*
X987331Y229286D03*
X991024Y224712D03*
Y222212D03*
X979362Y231461D03*
Y228961D03*
Y226461D03*
X987331Y231786D03*
X992045Y366559D03*
X984045D03*
X988045D03*
X981795Y572842D03*
X985903Y579475D03*
X985357Y585507D03*
X989950D03*
X985401Y590145D03*
X989995Y590190D03*
X989857Y605443D03*
X983712Y722064D03*
X1006000Y103621D03*
X1008563Y293645D03*
X1006063D03*
Y290845D03*
Y288345D03*
X1008563Y290845D03*
Y288345D03*
X997857Y605443D03*
X1010606Y1547824D03*
X1010659Y1568771D03*
Y1565771D03*
X1010653Y1571669D03*
X1021451Y322879D03*
X1026032Y322906D03*
X1018238Y678647D03*
X1018155Y684132D03*
X1025116Y698332D03*
X1024932Y717856D03*
X1016320Y828481D03*
X1026340Y917761D03*
X1025448Y1008262D03*
Y1011762D03*
X1013606Y1547824D03*
X1016606D03*
X1019606D03*
X1013659Y1568771D03*
X1016659D03*
X1019659D03*
X1013659Y1565771D03*
X1016659D03*
X1019659D03*
X1013653Y1571669D03*
X1016653D03*
X1019653D03*
X1031674Y198883D03*
Y201683D03*
X1038065Y236121D03*
X1035099Y238589D03*
X1030184Y288709D03*
X1038068Y298789D03*
X1033112D03*
X1030753Y732213D03*
X1051055Y213539D03*
X1044501Y238689D03*
X1052736Y238714D03*
X1048695Y280161D03*
X1057359Y402291D03*
Y397335D03*
X1054959Y411509D03*
Y425682D03*
Y416465D03*
Y430638D03*
Y439855D03*
Y444811D03*
Y468609D03*
Y473565D03*
Y487738D03*
Y482782D03*
Y517699D03*
Y512743D03*
Y531872D03*
Y526916D03*
X1071268Y226226D03*
Y223726D03*
Y228726D03*
Y231226D03*
X1065361Y390223D03*
Y395179D03*
Y404396D03*
Y409352D03*
Y423525D03*
Y418569D03*
Y432743D03*
Y437699D03*
Y489895D03*
Y480677D03*
Y475721D03*
Y494851D03*
Y519855D03*
Y524811D03*
Y538984D03*
Y534028D03*
X1089645Y101701D03*
X1081724Y226461D03*
Y223661D03*
X1089693Y229286D03*
X1081724Y231461D03*
Y228961D03*
X1089693Y231786D03*
X1079863Y345660D03*
X1090747Y1617415D03*
X1108362Y103621D03*
X1093386Y224712D03*
Y222212D03*
X1108425Y293645D03*
Y290845D03*
Y288345D03*
X1096264Y1562285D03*
X1093713Y1585583D03*
X1110925Y293645D03*
Y290845D03*
Y288345D03*
X1117913Y565414D03*
Y567914D03*
Y570414D03*
Y572914D03*
Y575414D03*
X1122718Y598857D03*
X1121191Y612555D03*
X1120512Y617332D03*
X1121022Y607750D03*
X1134036Y198883D03*
Y201683D03*
X1137461Y238589D03*
X1140427Y236121D03*
X1138166Y534759D03*
X1153417Y213539D03*
X1146863Y238689D03*
X1155098Y238714D03*
X1149437Y728541D03*
X1152316Y746625D03*
X1173630Y226226D03*
Y223726D03*
Y228726D03*
Y231226D03*
X1161274Y550462D03*
X1170603Y715281D03*
X1163751Y719498D03*
X1168577Y733812D03*
X1169266Y800799D03*
X1184086Y231461D03*
Y228961D03*
Y226461D03*
Y223661D03*
X1176577Y885974D03*
X1188431Y936568D03*
X1192007Y101701D03*
X1192055Y229286D03*
X1195748Y224712D03*
Y222212D03*
X1192055Y231786D03*
X1192990Y914873D03*
X1195118Y936296D03*
X1210724Y103621D03*
X1213287Y293645D03*
Y290845D03*
Y288345D03*
X1210787Y293645D03*
Y290845D03*
Y288345D03*
X1217139Y324139D03*
X1222909Y-83456D03*
Y-78500D03*
Y-68500D03*
Y-73456D03*
X1228265Y-44406D03*
Y-39450D03*
Y-29450D03*
Y-34406D03*
X1236398Y198883D03*
Y201683D03*
X1224186Y316731D03*
X1237662Y466528D03*
Y471484D03*
Y480701D03*
Y485657D03*
Y515617D03*
Y510661D03*
Y524835D03*
Y529791D03*
Y565657D03*
Y560701D03*
Y589047D03*
Y574874D03*
Y579830D03*
Y603221D03*
Y594003D03*
Y608177D03*
X1239823Y238589D03*
X1242789Y236121D03*
X1248064Y473640D03*
Y487813D03*
Y478596D03*
Y492769D03*
Y517774D03*
Y522730D03*
Y531947D03*
Y536903D03*
X1255779Y213539D03*
X1257460Y238714D03*
X1264481Y300223D03*
X1261623Y447486D03*
X1259223Y458334D03*
X1267843Y488618D03*
Y491118D03*
Y493618D03*
X1275992Y223726D03*
Y226226D03*
Y231226D03*
Y228726D03*
X1286448Y223661D03*
Y226461D03*
Y228961D03*
Y231461D03*
X1279127Y450091D03*
X1281737Y452740D03*
X1279505Y487570D03*
Y490070D03*
X1276060Y496258D03*
Y493758D03*
X1294369Y101701D03*
X1294417Y229286D03*
X1298110Y222212D03*
Y224712D03*
X1294417Y231786D03*
X1313086Y103621D03*
X1313149Y288345D03*
Y290845D03*
Y293645D03*
X1315649Y288345D03*
Y290845D03*
Y293645D03*
X1308010Y466409D03*
X1307996Y487382D03*
X1313459Y1081599D03*
X1310589Y1097278D03*
X1313089D03*
X1334223Y33425D03*
X1333049Y399268D03*
Y401768D03*
Y396768D03*
X1321016Y399161D03*
Y401661D03*
Y396661D03*
X1325927Y474513D03*
X1386399Y201683D03*
X1383669Y1011303D03*
Y1017303D03*
Y1023303D03*
X1386399Y198883D03*
X1399226Y238689D03*
X1392790Y236121D03*
X1389824Y238589D03*
X1395669Y1011303D03*
X1389669D03*
X1395669Y1017303D03*
Y1023303D03*
X1389669D03*
X1405780Y213539D03*
X1407461Y238714D03*
X1425993Y231226D03*
Y228726D03*
Y226226D03*
Y223726D03*
X1444370Y101701D03*
X1436449Y228961D03*
X1444418Y229286D03*
X1436449Y226461D03*
Y223661D03*
X1448111Y222212D03*
Y224712D03*
X1436449Y231461D03*
X1444418Y231786D03*
X1438882Y572842D03*
X1447037Y585507D03*
X1442444D03*
X1442990Y579475D03*
X1435668Y572975D03*
X1442488Y590145D03*
X1447082Y590190D03*
X1446944Y605443D03*
X1443041Y873683D03*
X1463087Y103621D03*
X1465650Y293645D03*
Y288345D03*
Y290845D03*
X1463150Y288345D03*
Y290845D03*
Y293645D03*
X1454944Y605443D03*
X1479409Y-83456D03*
Y-78500D03*
Y-68500D03*
Y-73456D03*
X1476822Y40780D03*
X1498621Y15043D03*
Y35043D03*
Y27043D03*
X1488761Y198883D03*
Y201683D03*
X1492186Y238589D03*
X1495152Y236121D03*
X1483813Y368516D03*
X1482535Y1008262D03*
Y1002453D03*
Y1011762D03*
X1514765Y-44536D03*
Y-39580D03*
Y-29580D03*
Y-34536D03*
X1508142Y213539D03*
X1509823Y238714D03*
X1501588Y238689D03*
X1514446Y402291D03*
Y397335D03*
X1512046Y411509D03*
Y425682D03*
Y416465D03*
Y439855D03*
Y430638D03*
Y444811D03*
Y468609D03*
Y473565D03*
Y487738D03*
Y482782D03*
Y517699D03*
Y512743D03*
Y531872D03*
Y526916D03*
X1528355Y228726D03*
Y223726D03*
Y226226D03*
Y231226D03*
X1515779Y351594D03*
X1522448Y390223D03*
Y395179D03*
Y404396D03*
Y409352D03*
Y423525D03*
Y418569D03*
Y437699D03*
Y432743D03*
Y489895D03*
Y480677D03*
Y475721D03*
Y494851D03*
Y519855D03*
Y538984D03*
Y534028D03*
Y524811D03*
X1546732Y101701D03*
X1538811Y226461D03*
Y228961D03*
Y231461D03*
X1546780Y229286D03*
X1538811Y223661D03*
X1546780Y231786D03*
X1550473Y222212D03*
Y224712D03*
X1565449Y103621D03*
X1565512Y288345D03*
X1568012Y293645D03*
Y290845D03*
Y288345D03*
X1565512Y293645D03*
Y290845D03*
X1575000Y565414D03*
Y567914D03*
Y570414D03*
Y572914D03*
Y575414D03*
X1579753Y599100D03*
X1578679Y613047D03*
X1578114Y607563D03*
X1591123Y198883D03*
Y201683D03*
X1594548Y238589D03*
X1610504Y213539D03*
X1597514Y236121D03*
X1612185Y238714D03*
X1603950Y238689D03*
X1641173Y231461D03*
X1630717Y223726D03*
Y226226D03*
Y231226D03*
Y228726D03*
X1641173Y223661D03*
Y226461D03*
Y228961D03*
X1649094Y101701D03*
X1649142Y229286D03*
X1652835Y222212D03*
Y224712D03*
X1649142Y231786D03*
X1667811Y103621D03*
X1670374Y290845D03*
Y288345D03*
X1667874Y290845D03*
Y288345D03*
X1670374Y293645D03*
X1667874D03*
X1674226Y324139D03*
X1693485Y198883D03*
Y201683D03*
X1681273Y316731D03*
X1699876Y236121D03*
X1696910Y238589D03*
X1706312Y238689D03*
X1694749Y466528D03*
Y471484D03*
X1705151Y473640D03*
Y487813D03*
Y478596D03*
X1694749Y480701D03*
Y485657D03*
X1705151Y492769D03*
Y517774D03*
Y522730D03*
X1694749Y510661D03*
Y515617D03*
X1705151Y536903D03*
Y531947D03*
X1694749Y524835D03*
Y529791D03*
X1705151Y572769D03*
Y567813D03*
X1694749Y565657D03*
Y560701D03*
Y579830D03*
X1705151Y586943D03*
Y581987D03*
X1694749Y589047D03*
Y574874D03*
Y603221D03*
X1705151Y601116D03*
Y596160D03*
X1694749Y594003D03*
X1705151Y615289D03*
X1694749Y608177D03*
X1705151Y610333D03*
X1712866Y213539D03*
X1714547Y238714D03*
X1718710Y447486D03*
X1716310Y458334D03*
X1724930Y491118D03*
Y488618D03*
Y493618D03*
Y496118D03*
X1733909Y-83456D03*
Y-78500D03*
Y-68500D03*
Y-73456D03*
X1733079Y223726D03*
Y226226D03*
Y231226D03*
Y228726D03*
X1743535Y223661D03*
X1738824Y452740D03*
X1736214Y450091D03*
X1736592Y487570D03*
Y490070D03*
X1733147Y493758D03*
Y496258D03*
X1751456Y101701D03*
X1743535Y226461D03*
X1755197Y224712D03*
X1743535Y228961D03*
Y231461D03*
X1751504Y229286D03*
X1755197Y222212D03*
X1751504Y231786D03*
X1770173Y103621D03*
X1772736Y293645D03*
X1770236D03*
Y290845D03*
Y288345D03*
X1772736Y290845D03*
Y288345D03*
X1765097Y466409D03*
X1765083Y487382D03*
X1772768Y818696D03*
X1790136Y399161D03*
Y401661D03*
Y396661D03*
X1778103Y399161D03*
Y401661D03*
Y396661D03*
X1783014Y474513D03*
X1778801Y836469D03*
X1786256Y927626D03*
X1784306Y924601D03*
X1786256Y930626D03*
X1799265Y-44666D03*
Y-39710D03*
Y-29710D03*
Y-34666D03*
X1791302Y829031D03*
X1816385Y1136912D03*
X1813885D03*
Y1144912D03*
X1816385D03*
G54D20*
X51043Y60709D03*
Y150197D03*
X153405Y60709D03*
Y150197D03*
X255767Y60709D03*
Y150197D03*
X279360Y368760D03*
Y421555D03*
Y501752D03*
Y550020D03*
Y636752D03*
X358129Y60709D03*
Y150197D03*
X508130Y60709D03*
Y150197D03*
X610492Y60709D03*
Y150197D03*
X712854Y60709D03*
Y150197D03*
X736446Y368760D03*
Y421555D03*
Y501752D03*
Y550020D03*
Y636752D03*
X815216Y60709D03*
Y150197D03*
X965216Y60709D03*
Y150197D03*
X1067578Y60709D03*
Y150197D03*
X1169940Y60709D03*
Y150197D03*
X1193533Y368760D03*
Y421555D03*
Y501752D03*
Y550020D03*
Y636752D03*
X1272302Y60709D03*
Y150197D03*
X1422303Y60709D03*
Y150197D03*
X1524665Y60709D03*
Y150197D03*
X1627027Y60709D03*
Y150197D03*
X1650620Y368760D03*
Y421555D03*
Y501752D03*
Y550020D03*
Y636752D03*
X1729389Y60709D03*
Y150197D03*
G54D46*
X843012Y1592787D03*
Y1602787D03*
Y1612787D03*
Y1622787D03*
X853012Y1592787D03*
Y1602787D03*
Y1612787D03*
Y1622787D03*
X878012Y1592787D03*
Y1602787D03*
Y1612787D03*
Y1622787D03*
X888012Y1592787D03*
Y1602787D03*
Y1612787D03*
Y1622787D03*
X913012Y1592787D03*
Y1602787D03*
Y1612787D03*
Y1622787D03*
X923012Y1592787D03*
Y1602787D03*
Y1612787D03*
Y1622787D03*
X948012Y1592787D03*
Y1602787D03*
Y1612787D03*
Y1622787D03*
X958012Y1592787D03*
Y1602787D03*
Y1612787D03*
Y1622787D03*
X983012Y1592787D03*
X993012D03*
X983012Y1602787D03*
Y1612787D03*
X993012Y1602787D03*
Y1612787D03*
X983012Y1622787D03*
X993012D03*
X1018012Y1592787D03*
X1028012D03*
X1018012Y1602787D03*
Y1612787D03*
X1028012Y1602787D03*
Y1612787D03*
X1018012Y1622787D03*
X1028012D03*
G54D12*
X3035Y1578036D03*
X3017Y1639466D03*
X14751Y62381D03*
X12601Y92110D03*
X9364Y107501D03*
X16728Y107910D03*
X12652Y116894D03*
X13615Y153263D03*
X10966Y155873D03*
Y152873D03*
X12709Y175777D03*
X9745Y245784D03*
X19075Y278429D03*
X7036Y268371D03*
X14252Y1121333D03*
X11552D03*
X16752D03*
X8952D03*
X14152Y1111633D03*
X11452D03*
X8852D03*
X16652D03*
X14252Y1130333D03*
X16752D03*
X14306Y1138705D03*
X16806D03*
X20079Y1429347D03*
X12327Y1519202D03*
X11995Y1535134D03*
X6567Y1554215D03*
X14375Y1553121D03*
X18409Y1554202D03*
X12000Y1644980D03*
X33288Y109410D03*
Y116497D03*
X30788D03*
X25988D03*
X22439Y106495D03*
X30788Y123584D03*
X33288Y123583D03*
X25988Y123584D03*
X33288Y130670D03*
X30788D03*
X25988D03*
X30788Y137757D03*
X25988D03*
X29201Y151651D03*
X26201D03*
X20709Y175777D03*
X28740Y247292D03*
X21449Y253198D03*
X28740Y267292D03*
X21386Y273198D03*
X23479Y295619D03*
X32452Y581222D03*
X29652D03*
X35252D03*
Y591215D03*
X29652D03*
X32452D03*
X34254Y611091D03*
X29451Y633560D03*
X30369Y663048D03*
X27854Y671553D03*
X30414Y671508D03*
X26596Y874520D03*
X26844Y920354D03*
X24132Y958151D03*
X25371Y980696D03*
X34314Y1215403D03*
X22284Y1464612D03*
X32079Y1525641D03*
X35237Y1532096D03*
X35850Y1556096D03*
X32000Y1644980D03*
X46450Y82984D03*
Y77784D03*
Y75184D03*
Y80384D03*
X48364Y92473D03*
X46450Y85584D03*
X37988Y109410D03*
Y102323D03*
Y116496D03*
Y130670D03*
Y123583D03*
X52437Y137756D03*
X37988D03*
X45984Y163264D03*
X37284Y285272D03*
X42690Y451466D03*
X48596Y458466D03*
X39643Y555194D03*
X36843D03*
X39643Y563194D03*
X36843D03*
X39643Y571194D03*
X36843D03*
X49265Y886660D03*
X52922Y900295D03*
X47916Y947622D03*
X50366Y1086981D03*
Y1082388D03*
X38200Y1089721D03*
X44365Y1086404D03*
X38216Y1093757D03*
X49500Y1199066D03*
X51197Y1218206D03*
X39452Y1250932D03*
X48195Y1511279D03*
X48079Y1525641D03*
Y1529641D03*
Y1521641D03*
X52048Y1556062D03*
X52000Y1644980D03*
X56098Y109410D03*
Y116496D03*
X55964Y103037D03*
X56098Y123583D03*
Y130670D03*
X68896Y226141D03*
X58279Y293796D03*
X66293Y285690D03*
X68793D03*
X66293Y288190D03*
X68793D03*
X60779Y293796D03*
X65759Y437508D03*
X61759D03*
X57759D03*
X54936Y449352D03*
X59522Y448874D03*
X68619Y447269D03*
X68497Y450201D03*
X64550Y504699D03*
X62050D03*
X59550D03*
X68236Y519458D03*
X61752Y516979D03*
X64252D03*
X59252D03*
X55318Y629362D03*
X53129Y627948D03*
X55307Y688473D03*
X66342Y880067D03*
X67316Y865869D03*
X64175Y897500D03*
X67461Y912983D03*
X63303Y912835D03*
X57178Y981386D03*
X69263Y1053152D03*
X55049Y1082343D03*
X55004Y1086937D03*
X58981Y1105100D03*
X56381D03*
X61581D03*
X64281D03*
X61681Y1114800D03*
X56481D03*
X59081D03*
X64381D03*
X57218Y1123867D03*
X55397Y1133688D03*
X57897D03*
X58250Y1220896D03*
X65940Y1209382D03*
X58250Y1227796D03*
Y1230296D03*
Y1237196D03*
Y1234696D03*
Y1223396D03*
X57185Y1480808D03*
X57144Y1491047D03*
X56114Y1556061D03*
X68743Y1583498D03*
X73381Y94017D03*
X69381D03*
X71422Y151540D03*
X75072Y191941D03*
X81572Y184619D03*
X74939Y188727D03*
X83552Y206760D03*
X71696Y226141D03*
X76766Y256535D03*
X84766D03*
X71593Y285690D03*
Y288190D03*
X75819Y290755D03*
X79819D03*
X83819D03*
X71826Y480705D03*
X75736Y519458D03*
X73236D03*
X70736D03*
X81740Y636250D03*
X69670Y633205D03*
Y636005D03*
X81740Y633450D03*
X69670Y638805D03*
X81740Y639050D03*
X74414Y681907D03*
X76991Y946134D03*
X84679Y1018368D03*
X70059Y1071656D03*
X69373Y1063389D03*
X70059Y1079656D03*
X80290Y1345691D03*
Y1350683D03*
X75334Y1345691D03*
Y1350683D03*
X80290Y1357603D03*
Y1362595D03*
X75334Y1357603D03*
Y1362595D03*
X80290Y1381801D03*
Y1369889D03*
Y1374881D03*
X75334Y1381801D03*
Y1374881D03*
Y1369889D03*
X80290Y1386793D03*
X75334D03*
X87000Y1597855D03*
X76005Y1580680D03*
X82433Y1580590D03*
X72000Y1644980D03*
X88080Y103603D03*
X87002Y146461D03*
X85904Y152367D03*
X87604Y180572D03*
X92287Y180527D03*
X96010Y192421D03*
X92242Y185121D03*
X87604Y185165D03*
X85796Y279208D03*
X89900Y281307D03*
X90257Y445506D03*
X88875Y840940D03*
X91581Y877859D03*
Y874859D03*
X87853Y899220D03*
X91128Y1006487D03*
X99836Y997860D03*
X95836D03*
X100594Y1035088D03*
X97247Y1030568D03*
X103124Y1165091D03*
X87574Y1345691D03*
Y1350683D03*
X99814D03*
Y1345691D03*
X92530D03*
Y1350683D03*
X87574Y1362595D03*
Y1357603D03*
X99814Y1362595D03*
Y1357603D03*
X92530Y1362595D03*
Y1357603D03*
X87574Y1374881D03*
Y1369795D03*
Y1381801D03*
X99814D03*
Y1374881D03*
Y1369889D03*
X92530Y1374881D03*
Y1369795D03*
Y1381801D03*
X87574Y1399079D03*
Y1393993D03*
Y1386793D03*
X99814Y1399079D03*
Y1394087D03*
Y1386793D03*
X92530Y1393993D03*
Y1399079D03*
Y1386793D03*
X87574Y1410991D03*
Y1405999D03*
X99814Y1410991D03*
Y1405999D03*
X92530Y1410991D03*
Y1405999D03*
X92000Y1644980D03*
X107364Y113394D03*
Y110394D03*
X110013Y110784D03*
X110152Y130898D03*
X117607Y133298D03*
X111754Y134579D03*
X107540Y172665D03*
Y180665D03*
X107572Y200864D03*
Y212864D03*
Y216864D03*
Y221864D03*
X109329Y252371D03*
X112474Y716315D03*
X114397Y727974D03*
X113601Y881266D03*
X107641Y865224D03*
X103836Y997860D03*
X111836D03*
X114770Y1009354D03*
X107836Y997860D03*
X115836D03*
X108933Y1102091D03*
X112433D03*
X103124D03*
X112433Y1114691D03*
X103124D03*
X108933D03*
Y1127291D03*
X112433D03*
X103124D03*
X112433Y1139891D03*
X103124Y1152491D03*
X108933D03*
X112433D03*
X108933Y1165091D03*
X112433D03*
X103184Y1177691D03*
X108933D03*
X112433D03*
X109415Y1202103D03*
X112795Y1223749D03*
X104770Y1350683D03*
Y1345691D03*
X112054D03*
Y1350683D03*
X117010Y1345691D03*
Y1350683D03*
X104770Y1362595D03*
Y1357603D03*
X112054Y1362595D03*
Y1357603D03*
X117010Y1362595D03*
Y1357603D03*
Y1369889D03*
Y1374881D03*
Y1381801D03*
X104770D03*
Y1374881D03*
Y1369889D03*
X112054D03*
Y1374881D03*
Y1381801D03*
X104770Y1399079D03*
Y1394087D03*
Y1386793D03*
X112054Y1399079D03*
Y1394087D03*
Y1386793D03*
X117010Y1394087D03*
Y1399079D03*
Y1386793D03*
X104770Y1410991D03*
Y1405999D03*
X112054Y1410991D03*
Y1405999D03*
X117010Y1410991D03*
Y1405999D03*
X107669Y1456451D03*
Y1465913D03*
X116330Y1465513D03*
X107669Y1461182D03*
X116330Y1460782D03*
X107669Y1481267D03*
X116330Y1480867D03*
X107669Y1476536D03*
X116330Y1476136D03*
Y1470244D03*
X107669Y1471805D03*
X116330Y1491490D03*
Y1485598D03*
X107669Y1487159D03*
Y1496621D03*
X116330Y1496221D03*
X107669Y1491890D03*
X116330Y1506845D03*
Y1500952D03*
X107669Y1502514D03*
X116330Y1511576D03*
X107669Y1511976D03*
Y1507245D03*
X116330Y1516307D03*
X107669Y1563544D03*
X116330Y1563144D03*
X107669Y1558813D03*
Y1568275D03*
X116330Y1567875D03*
X107669Y1578898D03*
X116330Y1578498D03*
Y1572606D03*
X107669Y1574167D03*
Y1583629D03*
X116330Y1583229D03*
X107669Y1594253D03*
X116330Y1593853D03*
Y1587960D03*
X107669Y1589522D03*
Y1609607D03*
X116330Y1609207D03*
X107669Y1598984D03*
X116330Y1598584D03*
Y1603315D03*
X107669Y1604876D03*
X116330Y1613938D03*
Y1618669D03*
X107669Y1614338D03*
X112000Y1644980D03*
X128350Y116497D03*
X133150D03*
X124606Y106495D03*
X125599Y109172D03*
X122599D03*
X133150Y123584D03*
X128350D03*
X133150Y130670D03*
X128350D03*
Y137757D03*
X133150D03*
X126246Y141228D03*
X124340Y146012D03*
X129134Y150847D03*
X131102Y247292D03*
X123811Y253198D03*
X125125Y362403D03*
X118122Y747565D03*
X122887Y884000D03*
X127067Y891495D03*
X124079Y1009354D03*
X119836Y997860D03*
X131836D03*
X127836D03*
X123836D03*
X120579Y1009354D03*
Y1021954D03*
X124079D03*
X133870Y1105091D03*
Y1117691D03*
Y1130291D03*
Y1142891D03*
Y1155491D03*
Y1168091D03*
X121211Y1215195D03*
X126937Y1209607D03*
X124294Y1350683D03*
Y1345691D03*
X129250Y1350683D03*
Y1345691D03*
X124294Y1362595D03*
Y1357603D03*
X129250D03*
Y1362595D03*
X124294Y1374881D03*
Y1369889D03*
Y1381801D03*
X129250Y1374881D03*
Y1369889D03*
Y1381801D03*
X124294Y1394087D03*
Y1399079D03*
Y1386793D03*
X129250Y1394087D03*
Y1399079D03*
Y1386793D03*
X124294Y1405999D03*
Y1410991D03*
X129250Y1405999D03*
Y1410991D03*
X124992Y1465913D03*
Y1456451D03*
Y1461182D03*
X133653Y1465513D03*
Y1460782D03*
X124992Y1471805D03*
Y1476536D03*
Y1481267D03*
X133653Y1476136D03*
Y1470244D03*
Y1480867D03*
Y1496221D03*
X124992Y1487159D03*
Y1491890D03*
Y1496621D03*
X133653Y1491490D03*
Y1485598D03*
Y1506845D03*
Y1500952D03*
Y1511576D03*
X124992Y1511976D03*
Y1507245D03*
Y1502514D03*
X133653Y1516307D03*
X124992Y1558813D03*
Y1563544D03*
X133653Y1563144D03*
Y1567875D03*
X124992Y1574167D03*
Y1578898D03*
X133653Y1578498D03*
Y1572606D03*
X124992Y1568275D03*
Y1589522D03*
Y1594253D03*
X133653Y1593853D03*
Y1587960D03*
X124992Y1583629D03*
X133653Y1583229D03*
X124992Y1609607D03*
Y1604876D03*
Y1598984D03*
X133653Y1609207D03*
Y1598584D03*
Y1603315D03*
X124992Y1614338D03*
X133653Y1613938D03*
Y1618669D03*
X132000Y1644980D03*
X148812Y80384D03*
Y82984D03*
Y75184D03*
Y77784D03*
Y85584D03*
X135650Y109410D03*
X140350Y116496D03*
Y109410D03*
Y102323D03*
X135650Y116497D03*
Y123583D03*
Y130670D03*
X140350D03*
Y123583D03*
Y137756D03*
X136604Y450750D03*
X140703Y536382D03*
X145670Y597580D03*
X147893Y599588D03*
X147155Y589556D03*
X147094Y592354D03*
X145609Y594668D03*
X147896Y596095D03*
X147925Y615600D03*
X147893Y607588D03*
X139836Y997860D03*
X147836D03*
X143836D03*
X135836D03*
X145516Y1024954D03*
Y1012354D03*
X148534Y1046476D03*
X134457Y1180654D03*
X141490Y1345691D03*
Y1350683D03*
X136534D03*
Y1345691D03*
X148774Y1350683D03*
Y1345691D03*
X141490Y1357603D03*
Y1362595D03*
X136534D03*
Y1357603D03*
X148774D03*
Y1362595D03*
X141490Y1369889D03*
Y1374881D03*
Y1381801D03*
X136534Y1369889D03*
Y1381801D03*
Y1374881D03*
X148774Y1369889D03*
Y1381801D03*
Y1374881D03*
X141490Y1386793D03*
Y1394087D03*
Y1399079D03*
X136534D03*
Y1394087D03*
Y1386793D03*
X148774Y1394087D03*
Y1399079D03*
Y1386793D03*
X141490Y1405999D03*
Y1410991D03*
X136534D03*
Y1405999D03*
X148774D03*
Y1410991D03*
X142315Y1456451D03*
Y1461182D03*
Y1465913D03*
Y1471805D03*
Y1476536D03*
Y1481267D03*
Y1487159D03*
Y1491890D03*
Y1496621D03*
Y1507245D03*
Y1502514D03*
Y1511976D03*
Y1558813D03*
Y1563544D03*
Y1574167D03*
Y1578898D03*
Y1568275D03*
Y1589522D03*
Y1594253D03*
Y1583629D03*
Y1609607D03*
Y1604876D03*
Y1598984D03*
Y1614338D03*
X151366Y92849D03*
X158460Y116496D03*
X158326Y103037D03*
X158460Y109410D03*
Y130670D03*
Y123583D03*
X155051Y137756D03*
X163141Y293796D03*
X160641D03*
X166528Y312392D03*
X157375Y555234D03*
X157090Y562003D03*
X152386Y634946D03*
X151836Y997860D03*
X159836D03*
X164028Y1041468D03*
X155513Y1065148D03*
X161014Y1345691D03*
Y1350683D03*
X153730Y1345691D03*
Y1350683D03*
X165970Y1345691D03*
Y1350683D03*
X161014Y1362595D03*
Y1357603D03*
X153730Y1362595D03*
Y1357603D03*
X165970Y1362595D03*
Y1357603D03*
X161014Y1381801D03*
Y1369889D03*
Y1374881D03*
X153730Y1369889D03*
Y1381801D03*
Y1374881D03*
X165970D03*
Y1381801D03*
Y1369889D03*
X161014Y1394087D03*
Y1386793D03*
X153730Y1394087D03*
Y1386793D03*
X165970Y1394087D03*
Y1386793D03*
X161014Y1399079D03*
X153730D03*
X165970D03*
X161014Y1410991D03*
Y1405999D03*
X153730D03*
Y1410991D03*
X165970D03*
Y1405999D03*
X159637Y1461182D03*
X150976Y1465513D03*
Y1460782D03*
X159637Y1465913D03*
Y1456451D03*
X150976Y1476136D03*
Y1470244D03*
Y1480867D03*
X159637Y1471805D03*
Y1476536D03*
Y1481267D03*
Y1496621D03*
X150976Y1491490D03*
Y1485598D03*
Y1496221D03*
X159637Y1487159D03*
Y1491890D03*
X150976Y1500952D03*
Y1511576D03*
X159637Y1507245D03*
Y1502514D03*
Y1511976D03*
X150976Y1506845D03*
Y1516307D03*
X159637Y1558813D03*
Y1563544D03*
X150976Y1563144D03*
X159637Y1578898D03*
X150976Y1567875D03*
Y1578498D03*
Y1572606D03*
X159637Y1568275D03*
Y1574167D03*
X150976Y1583229D03*
Y1593853D03*
Y1587960D03*
X159637Y1583629D03*
Y1589522D03*
Y1594253D03*
X150976Y1609207D03*
Y1598584D03*
Y1603315D03*
X159637Y1609607D03*
Y1604876D03*
Y1598984D03*
X150976Y1613938D03*
Y1618669D03*
X159637Y1614338D03*
X152000Y1644980D03*
X179743Y94017D03*
X175743D03*
X171743D03*
X175871Y110445D03*
X180863Y115401D03*
Y110445D03*
X175871Y115401D03*
X180863Y129574D03*
Y124618D03*
X175871Y129574D03*
Y124618D03*
X173784Y151540D03*
X177434Y191941D03*
X177301Y188727D03*
X171258Y226141D03*
X174058D03*
X179128Y256535D03*
X173955Y285690D03*
Y288190D03*
X171155Y285690D03*
X168655Y288190D03*
X171155D03*
X168655Y285690D03*
X182181Y290755D03*
X178181D03*
X177369Y389154D03*
Y396240D03*
Y403327D03*
Y410413D03*
Y417500D03*
Y424587D03*
Y431673D03*
Y438760D03*
Y445847D03*
Y467539D03*
Y474626D03*
Y488799D03*
Y481713D03*
Y495886D03*
Y511673D03*
Y518760D03*
Y525847D03*
Y532933D03*
Y540020D03*
Y547106D03*
X176650Y602197D03*
X177114Y595108D03*
X173254Y1345691D03*
Y1350683D03*
X178210Y1345691D03*
Y1350683D03*
X173254Y1362595D03*
Y1357603D03*
X178210D03*
Y1362595D03*
X173254Y1374881D03*
Y1369889D03*
Y1381801D03*
X178210Y1374881D03*
Y1369889D03*
Y1381801D03*
X173254Y1394087D03*
Y1386793D03*
X178210Y1394087D03*
Y1386793D03*
X173254Y1399079D03*
X178210D03*
X173254Y1405999D03*
Y1410991D03*
X178210Y1405999D03*
Y1410991D03*
X168299Y1465513D03*
Y1460782D03*
X176960Y1465914D03*
Y1456452D03*
Y1461183D03*
X168299Y1476136D03*
Y1470244D03*
Y1480867D03*
X176960Y1476537D03*
Y1471806D03*
Y1481268D03*
X168299Y1491490D03*
Y1485598D03*
Y1496221D03*
X176960Y1491891D03*
Y1487160D03*
Y1496622D03*
Y1507246D03*
Y1502515D03*
X168299Y1506845D03*
Y1500952D03*
Y1511576D03*
X176960Y1511977D03*
X168299Y1516307D03*
Y1563144D03*
X176960Y1563544D03*
Y1558813D03*
Y1568275D03*
X168299Y1578498D03*
Y1572606D03*
Y1567875D03*
Y1583229D03*
X176960Y1583629D03*
X168299Y1593853D03*
Y1587960D03*
X176960Y1594253D03*
Y1589522D03*
X168299Y1609207D03*
Y1598584D03*
Y1603315D03*
X176960Y1609607D03*
Y1598984D03*
Y1604876D03*
X168299Y1613938D03*
Y1618669D03*
X176960Y1614338D03*
X172000Y1644980D03*
X188820Y80140D03*
Y84140D03*
Y76140D03*
X183752Y94017D03*
X186273Y117557D03*
X191265D03*
X186273Y131731D03*
Y122513D03*
X191265D03*
Y131731D03*
X189364Y146461D03*
X186273Y136687D03*
X191265D03*
X188266Y152367D03*
X194649Y180527D03*
X189966Y180572D03*
X198372Y192421D03*
X189966Y185165D03*
X194604Y185121D03*
X183934Y184619D03*
X185914Y206760D03*
X187128Y256535D03*
X188158Y279208D03*
X192262Y281307D03*
X186181Y290755D03*
X191988Y389154D03*
X190518Y396240D03*
X194603Y422864D03*
X195295Y414823D03*
X194673Y429832D03*
X194278Y436447D03*
X196313Y447953D03*
X195480Y467539D03*
X194222Y472772D03*
X194956Y487711D03*
X195069Y479104D03*
X195480Y495886D03*
X190829Y516841D03*
X194080Y510565D03*
X185654Y552872D03*
X185776Y550123D03*
X185099Y562443D03*
X186867Y560675D03*
X187408Y572334D03*
X185640Y574102D03*
X193723Y656942D03*
X185494Y1345597D03*
Y1350683D03*
X190450Y1345597D03*
Y1350683D03*
X197734Y1345691D03*
Y1350683D03*
X185494Y1362595D03*
Y1357603D03*
X197734Y1362595D03*
Y1357603D03*
X190450Y1362595D03*
Y1357603D03*
X185494Y1374881D03*
Y1381801D03*
Y1369889D03*
X197734D03*
Y1381801D03*
Y1374881D03*
X190450Y1369889D03*
Y1374881D03*
Y1381801D03*
X185494Y1393993D03*
Y1386793D03*
X190450Y1393993D03*
Y1386793D03*
X197734Y1394087D03*
Y1386793D03*
X185494Y1399079D03*
X190450D03*
X197734D03*
X185494Y1410991D03*
Y1405999D03*
X190450Y1410991D03*
Y1405999D03*
X197734D03*
Y1410991D03*
X185622Y1465513D03*
Y1460782D03*
Y1480868D03*
Y1476137D03*
Y1470244D03*
Y1485599D03*
X192000Y1644980D03*
X211262Y60922D03*
X206398Y55513D03*
X208463Y96472D03*
X202195Y117261D03*
X209726Y113394D03*
Y110394D03*
X212375Y110784D03*
X211969Y133298D03*
X214116Y134579D03*
X209902Y172665D03*
Y180665D03*
X209934Y200864D03*
Y212864D03*
Y216864D03*
Y221864D03*
X211691Y252371D03*
X215380Y389153D03*
X210580D03*
X215380Y396240D03*
X208080Y403327D03*
X215380Y403326D03*
X210580D03*
X208080Y410413D03*
X210580D03*
X215380D03*
X208080Y396240D03*
X210580D03*
X208080Y417500D03*
X215380Y417499D03*
X210580D03*
X208080Y424586D03*
X210580D03*
X215380D03*
X208080Y431673D03*
Y438760D03*
X210580D03*
X215380D03*
Y431673D03*
X210580D03*
X208080Y445847D03*
X215380Y467539D03*
X210580D03*
X208080Y474626D03*
X210580D03*
X215380D03*
Y488799D03*
X208080D03*
X210580D03*
Y481712D03*
X208080D03*
X215380D03*
X208080Y495886D03*
X215380Y518760D03*
X210580D03*
X208080D03*
X210580Y511673D03*
X215380D03*
X210580Y532933D03*
X208080D03*
Y540020D03*
Y525846D03*
X210580D03*
X215380D03*
Y532933D03*
X212460Y560500D03*
X209429Y625300D03*
X202690Y1345597D03*
Y1350683D03*
Y1362595D03*
Y1357603D03*
Y1369889D03*
Y1381801D03*
Y1374881D03*
Y1394087D03*
Y1386793D03*
Y1399079D03*
Y1405999D03*
Y1410991D03*
X211473Y1446675D03*
X213296Y1438215D03*
X211473Y1451631D03*
Y1462631D03*
Y1457675D03*
X224961Y109172D03*
X226968Y106495D03*
X230712Y116497D03*
X227961Y109172D03*
X230712Y123584D03*
Y130670D03*
X219969Y133298D03*
X228608Y141228D03*
X230712Y137757D03*
X226702Y146012D03*
X231496Y150847D03*
X226173Y253198D03*
X228760Y316122D03*
X223925Y543925D03*
X224500Y555000D03*
X222646Y607542D03*
X217945Y1423924D03*
X217799Y1433684D03*
X216465Y1446675D03*
X222253Y1438483D03*
X216465Y1451631D03*
Y1462631D03*
Y1457675D03*
X229260Y1469587D03*
X218171Y1474460D03*
X224176Y1492816D03*
X223235Y1506770D03*
X222908Y1502028D03*
X226957Y1510442D03*
X216342Y1515642D03*
X217519Y1537172D03*
X242712Y116496D03*
Y109410D03*
Y102323D03*
X238012Y116497D03*
X235512D03*
X238012Y109410D03*
Y123583D03*
Y130670D03*
X235512D03*
X242712D03*
Y123583D03*
X235512Y123584D03*
Y137757D03*
X242712Y137756D03*
X233464Y247292D03*
X236349Y339428D03*
X247333Y599506D03*
X241967Y616063D03*
X243078Y636486D03*
X240249Y628328D03*
X241084Y638243D03*
X246583Y665140D03*
X241850Y678462D03*
X247600Y848500D03*
X240845Y1345691D03*
Y1350683D03*
X245801Y1345691D03*
Y1350683D03*
X240845Y1357603D03*
Y1362595D03*
X245801Y1357603D03*
Y1362595D03*
X240845Y1381801D03*
Y1374881D03*
Y1369889D03*
X245801Y1381801D03*
Y1374881D03*
Y1369889D03*
X240845Y1386793D03*
X245801D03*
X232675Y1466801D03*
X240466Y1503857D03*
X243268Y1501903D03*
X237700Y1531600D03*
X251174Y77784D03*
Y80384D03*
Y82984D03*
Y75184D03*
Y85584D03*
X253728Y92849D03*
X260688Y103037D03*
X260822Y116496D03*
Y109410D03*
Y130670D03*
Y123583D03*
X257413Y137756D03*
X263003Y293796D03*
X257226Y312081D03*
X265011Y403307D03*
X255000Y427017D03*
X254692Y431029D03*
X253758Y435029D03*
X254678Y449873D03*
X261605Y465492D03*
Y472579D03*
X259105D03*
X254305D03*
X261605Y486752D03*
X254305D03*
X259105Y479666D03*
X261605D03*
X254305D03*
X259105Y486752D03*
X254305Y493839D03*
X259105D03*
X261605Y516713D03*
X259105D03*
Y523800D03*
X261605D03*
X254305D03*
Y516713D03*
X261605Y509626D03*
Y530886D03*
X259105D03*
Y537973D03*
X254305Y530886D03*
Y537973D03*
Y566752D03*
X261605Y559665D03*
Y566752D03*
X259105D03*
X261605Y588012D03*
X259105Y588013D03*
X254305Y573839D03*
X261605D03*
X259105D03*
X261605Y580926D03*
X259105D03*
X254305D03*
Y588013D03*
X259105Y602186D03*
X254305D03*
Y595099D03*
X259105D03*
X261605D03*
Y602185D03*
X254305Y609272D03*
X259105D03*
X261605D03*
X259105Y616359D03*
X254305D03*
X248984Y638125D03*
X258867Y680499D03*
X258041Y1350683D03*
Y1345691D03*
X253085Y1350683D03*
Y1345691D03*
X258041Y1362595D03*
X253085D03*
X258041Y1357603D03*
X253085D03*
X258041Y1381801D03*
Y1369795D03*
Y1374881D03*
X253085Y1381801D03*
Y1369795D03*
Y1374881D03*
Y1393993D03*
Y1399079D03*
X258041Y1386793D03*
Y1399079D03*
Y1393993D03*
X253085Y1386793D03*
X258041Y1405999D03*
Y1410991D03*
X253085Y1405999D03*
Y1410991D03*
X248042Y1532900D03*
X274105Y94017D03*
X278105D03*
X278233Y115401D03*
Y110445D03*
Y129574D03*
Y124618D03*
X276146Y151540D03*
X279796Y191941D03*
X279663Y188727D03*
X276420Y226141D03*
X273620D03*
X276317Y288190D03*
X273517Y285690D03*
X271017Y288190D03*
X273517D03*
X271017Y285690D03*
X265503Y293796D03*
X276317Y285690D03*
X274425Y390500D03*
X265011Y410394D03*
X266405Y451319D03*
Y458406D03*
Y465492D03*
X266229Y462264D03*
X266405Y472579D03*
Y479665D03*
Y486752D03*
Y493839D03*
Y523799D03*
Y516713D03*
Y509626D03*
Y530886D03*
Y537973D03*
Y566752D03*
Y559665D03*
Y580926D03*
Y588012D03*
Y573839D03*
Y602185D03*
Y595099D03*
Y609272D03*
Y616358D03*
X269700Y884600D03*
X269900Y914200D03*
X270100Y946500D03*
X277565Y1350683D03*
Y1345691D03*
X265325D03*
Y1350683D03*
X270281Y1345691D03*
Y1350683D03*
X277565Y1362595D03*
X265325D03*
X270281D03*
X277565Y1357603D03*
X265325D03*
X270281D03*
X277565Y1381801D03*
Y1374881D03*
Y1369889D03*
X265325D03*
Y1374881D03*
Y1381801D03*
X270281Y1369889D03*
Y1374881D03*
Y1381801D03*
X277565Y1386793D03*
Y1394087D03*
Y1399079D03*
X265325Y1394087D03*
Y1399079D03*
Y1386793D03*
X270281Y1399079D03*
Y1394087D03*
Y1386793D03*
X265325Y1405999D03*
Y1410991D03*
X270281Y1405999D03*
Y1410991D03*
X277565Y1405999D03*
Y1410991D03*
X272000Y1644980D03*
X291182Y84140D03*
Y80140D03*
Y76140D03*
X282105Y94017D03*
X286114D03*
X288635Y117557D03*
X283225Y115401D03*
Y110445D03*
X293627Y117557D03*
X288635Y131731D03*
Y122513D03*
X283225Y129574D03*
Y124618D03*
X293627Y122513D03*
Y131731D03*
X291726Y146461D03*
X293627Y136687D03*
X288635D03*
X290628Y152367D03*
X292328Y180572D03*
Y185165D03*
X286296Y184619D03*
X288276Y206760D03*
X281490Y256535D03*
X289490D03*
X290520Y279208D03*
X294624Y281307D03*
X284543Y290755D03*
X280543D03*
X288543D03*
X284075Y381500D03*
X284482Y460250D03*
X284516Y465492D03*
X282247Y470136D03*
X284516Y472579D03*
Y479665D03*
Y486752D03*
Y493839D03*
Y516713D03*
Y509626D03*
X283377Y532756D03*
X283456Y525483D03*
X280976Y537973D03*
X284516Y559665D03*
Y566752D03*
X284366Y579978D03*
X284516Y573839D03*
X284580Y608117D03*
X282521Y1345691D03*
X289805Y1350683D03*
Y1345691D03*
X294761Y1350683D03*
Y1345691D03*
X282521Y1350683D03*
X289805Y1362595D03*
X294761D03*
X282521D03*
X289805Y1357603D03*
X294761D03*
X282521D03*
X289805Y1374881D03*
Y1369889D03*
Y1381801D03*
X294761Y1374881D03*
Y1369889D03*
Y1381801D03*
X282521D03*
Y1374881D03*
Y1369889D03*
X289805Y1394087D03*
Y1399079D03*
Y1386793D03*
X294761Y1394087D03*
Y1399079D03*
Y1386793D03*
X282521D03*
Y1399079D03*
Y1394087D03*
X289805Y1405999D03*
Y1410991D03*
X294761Y1405999D03*
Y1410991D03*
X282521Y1405999D03*
Y1410991D03*
X280897Y1465913D03*
X289558Y1465513D03*
X280897Y1461182D03*
X289558Y1460782D03*
X280897Y1456451D03*
X289558Y1480867D03*
X280897Y1476536D03*
X289558Y1476136D03*
Y1470244D03*
X280897Y1471805D03*
Y1481267D03*
Y1491890D03*
X289558Y1491490D03*
Y1485598D03*
X280897Y1487159D03*
Y1496621D03*
X289558Y1496221D03*
X280897Y1507245D03*
X289558Y1506845D03*
Y1500952D03*
X280897Y1502514D03*
X289558Y1511576D03*
X280897Y1511976D03*
X289558Y1516307D03*
X280897Y1563544D03*
X289558Y1563144D03*
X280897Y1558813D03*
Y1574167D03*
Y1568275D03*
X289558Y1567875D03*
X280897Y1578898D03*
X289558Y1578498D03*
Y1572606D03*
Y1593853D03*
Y1587960D03*
X280897Y1589522D03*
Y1583629D03*
X289558Y1583229D03*
X280897Y1594253D03*
Y1609607D03*
X289558Y1609207D03*
X280897Y1598984D03*
X289558Y1598584D03*
Y1603315D03*
X280897Y1604876D03*
Y1614338D03*
X289558Y1613938D03*
Y1618669D03*
X292000Y1644980D03*
X308760Y55513D03*
X310882Y96613D03*
X305953Y91951D03*
X312088Y113394D03*
X304557Y117261D03*
X297011Y180527D03*
X312264Y172665D03*
Y180665D03*
X299759Y190285D03*
X296966Y185121D03*
X312296Y212864D03*
Y200864D03*
Y221864D03*
Y216864D03*
X306812Y342319D03*
X309258Y389912D03*
Y393924D03*
Y385912D03*
Y409924D03*
Y405924D03*
Y401924D03*
X306673Y418838D03*
X298507Y445908D03*
X302457Y445787D03*
X302045Y1345691D03*
Y1350683D03*
X307001D03*
Y1345691D03*
X302045Y1362595D03*
X307001D03*
X302045Y1357603D03*
X307001D03*
X302045Y1374881D03*
Y1381801D03*
Y1369889D03*
X307001Y1374881D03*
Y1369889D03*
Y1381801D03*
X302045Y1386793D03*
Y1394087D03*
Y1399079D03*
X307001Y1386793D03*
Y1399079D03*
Y1394087D03*
X302045Y1405999D03*
Y1410991D03*
X307001Y1405999D03*
Y1410991D03*
X298220Y1465913D03*
Y1456451D03*
Y1461182D03*
X306881Y1465513D03*
Y1460782D03*
Y1470244D03*
Y1480867D03*
X298220Y1471805D03*
Y1476536D03*
Y1481267D03*
X306881Y1476136D03*
X298220Y1487159D03*
Y1491890D03*
Y1496621D03*
X306881Y1491490D03*
Y1485598D03*
Y1496221D03*
X298220Y1507245D03*
Y1502514D03*
X306881Y1506845D03*
Y1500952D03*
Y1511576D03*
X298220Y1511976D03*
X306881Y1516307D03*
X298220Y1558813D03*
Y1563544D03*
X306881Y1563144D03*
X298220Y1568275D03*
X306881Y1567875D03*
X298220Y1574167D03*
Y1578898D03*
X306881Y1578498D03*
Y1572606D03*
X298220Y1583629D03*
X306881Y1583229D03*
X298220Y1589522D03*
Y1594253D03*
X306881Y1593853D03*
Y1587960D03*
Y1598584D03*
Y1603315D03*
X298220Y1609607D03*
Y1604876D03*
Y1598984D03*
X306881Y1609207D03*
X298220Y1614338D03*
X306881Y1613938D03*
Y1618669D03*
X312000Y1644980D03*
X313624Y60922D03*
X327323Y109172D03*
X314737Y110784D03*
X314854Y130898D03*
X322331Y133298D03*
X329064Y146012D03*
X316478Y134579D03*
X328535Y253198D03*
X314053Y252371D03*
X323882Y303839D03*
X315904Y336324D03*
X320483Y353506D03*
X319241Y1350683D03*
Y1345691D03*
X314285D03*
Y1350683D03*
X326525Y1345691D03*
Y1350683D03*
X319241Y1362595D03*
X314285D03*
X326525D03*
X319241Y1357603D03*
X314285D03*
X326525D03*
X319241Y1374881D03*
Y1381801D03*
Y1369889D03*
X314285Y1374881D03*
Y1381801D03*
Y1369889D03*
X326525Y1381801D03*
Y1369889D03*
Y1374881D03*
X319241Y1386793D03*
Y1399079D03*
Y1394087D03*
X314285Y1386793D03*
Y1399079D03*
Y1394087D03*
X326525Y1399079D03*
Y1394087D03*
Y1386793D03*
X319241Y1410991D03*
Y1405999D03*
X314285Y1410991D03*
Y1405999D03*
X326525Y1410991D03*
Y1405999D03*
X315543Y1465913D03*
Y1456451D03*
Y1461182D03*
X324204Y1465513D03*
Y1460782D03*
Y1480867D03*
X315543Y1471805D03*
Y1476536D03*
Y1481267D03*
X324204Y1476136D03*
Y1470244D03*
X315543Y1487159D03*
Y1491890D03*
Y1496621D03*
X324204Y1491490D03*
Y1485598D03*
Y1496221D03*
Y1500952D03*
Y1511576D03*
X315543Y1507245D03*
Y1502514D03*
Y1511976D03*
X324204Y1506845D03*
Y1516307D03*
X315543Y1558813D03*
Y1563544D03*
X324204Y1563144D03*
X315543Y1574167D03*
Y1578898D03*
X324204Y1567875D03*
Y1578498D03*
Y1572606D03*
X315543Y1568275D03*
Y1583629D03*
Y1589522D03*
Y1594253D03*
X324204Y1583229D03*
Y1593853D03*
Y1587960D03*
X315543Y1609607D03*
Y1604876D03*
Y1598984D03*
X324204Y1609207D03*
Y1598584D03*
Y1603315D03*
X315543Y1614338D03*
X324204Y1613938D03*
Y1618669D03*
X329330Y106495D03*
X345074Y116496D03*
X337874Y116497D03*
X340374D03*
X345074Y109410D03*
Y102323D03*
X340374Y109410D03*
X333074Y116497D03*
X330323Y109172D03*
X337874Y130670D03*
X345074D03*
Y123583D03*
X340374D03*
X337874Y123584D03*
X333074D03*
Y130670D03*
X340374D03*
X333074Y137757D03*
X337874D03*
X330970Y141228D03*
X345074Y137756D03*
X333858Y150847D03*
X335826Y247292D03*
X338358Y554861D03*
X337564Y1018294D03*
X337629Y1186071D03*
X336901Y1196407D03*
X338765Y1350683D03*
Y1345691D03*
X331481D03*
Y1350683D03*
X343721Y1345691D03*
Y1350683D03*
X331481Y1362595D03*
X343721D03*
X338765D03*
X331481Y1357603D03*
X343721D03*
X338765D03*
X331481Y1374881D03*
Y1381801D03*
Y1369889D03*
X343721Y1381801D03*
Y1369889D03*
Y1374881D03*
X338765Y1381801D03*
Y1369889D03*
Y1374881D03*
X331481Y1399079D03*
Y1394087D03*
Y1386793D03*
X343721D03*
Y1394087D03*
Y1399079D03*
X338765Y1386793D03*
Y1394087D03*
Y1399079D03*
X331481Y1410991D03*
Y1405999D03*
X343721Y1410991D03*
Y1405999D03*
X338765Y1410991D03*
Y1405999D03*
X341527Y1460782D03*
X332865Y1465913D03*
Y1456451D03*
Y1461182D03*
X341527Y1465513D03*
Y1476136D03*
Y1470244D03*
Y1480867D03*
X332865Y1471805D03*
Y1476536D03*
Y1481267D03*
X341527Y1491490D03*
Y1485598D03*
Y1496221D03*
X332865Y1487159D03*
Y1491890D03*
Y1496621D03*
Y1511976D03*
X341527Y1506845D03*
Y1500952D03*
Y1511576D03*
X332865Y1507245D03*
Y1502514D03*
X341527Y1516307D03*
X332865Y1558813D03*
Y1563544D03*
X341527Y1563144D03*
X332865Y1578898D03*
X341527Y1567875D03*
Y1578498D03*
Y1572606D03*
X332865Y1568275D03*
Y1574167D03*
Y1583629D03*
Y1589522D03*
Y1594253D03*
X341527Y1583229D03*
Y1593853D03*
Y1587960D03*
X332865Y1598984D03*
X341527Y1609207D03*
Y1598584D03*
Y1603315D03*
X332865Y1609607D03*
Y1604876D03*
X341527Y1613938D03*
Y1618669D03*
X332865Y1614338D03*
X332000Y1644980D03*
X353536Y82984D03*
Y80384D03*
Y77784D03*
Y75184D03*
X356090Y92849D03*
X353536Y85584D03*
X359525Y137756D03*
X356423Y301288D03*
X348375Y322284D03*
X348968Y333138D03*
X359278Y491870D03*
X356778D03*
X358096Y867459D03*
X358086Y884616D03*
X357962Y898800D03*
X358024Y912085D03*
X358085Y923327D03*
X355929Y1132042D03*
X351563Y1132410D03*
X349700Y1148000D03*
X357947Y1159455D03*
X352536Y1160168D03*
X357297Y1192709D03*
X360659Y1209789D03*
X355961Y1350683D03*
X351005Y1345597D03*
Y1350683D03*
X355961Y1345597D03*
X351005Y1362595D03*
X355961D03*
X351005Y1357603D03*
X355961D03*
X351005Y1374881D03*
Y1381801D03*
Y1369889D03*
X355961Y1381801D03*
Y1374881D03*
Y1369889D03*
X351005Y1399079D03*
Y1393993D03*
Y1386793D03*
X355961D03*
Y1399079D03*
Y1393993D03*
X351005Y1410991D03*
Y1405999D03*
X355961D03*
Y1410991D03*
X350188Y1491891D03*
Y1487160D03*
Y1496622D03*
Y1507246D03*
Y1502515D03*
Y1511977D03*
X358850Y1511576D03*
Y1506845D03*
Y1516307D03*
X350188Y1563544D03*
Y1558813D03*
Y1568275D03*
Y1578898D03*
Y1574167D03*
Y1583629D03*
Y1594253D03*
Y1589522D03*
Y1604876D03*
Y1609607D03*
Y1598984D03*
Y1614338D03*
X352000Y1644980D03*
X376467Y94017D03*
X363050Y103037D03*
X363184Y116496D03*
Y109410D03*
Y130670D03*
Y123583D03*
X375982Y226141D03*
X378782D03*
X365365Y293796D03*
X367865D03*
X373379Y288190D03*
X375879Y285690D03*
X373379D03*
X375879Y288190D03*
X368057Y354184D03*
X364933Y374232D03*
X373264Y370010D03*
X366443Y472189D03*
X373504Y517954D03*
X375040Y932959D03*
X371424Y937185D03*
X367944Y946082D03*
X368657Y1146937D03*
X366133Y1162817D03*
X368661Y1182649D03*
X368917Y1195419D03*
X365029Y1214158D03*
X362735Y1211864D03*
X369839Y1218940D03*
X363245Y1345691D03*
Y1350683D03*
X368201Y1345691D03*
Y1350683D03*
X363245Y1362595D03*
X368201D03*
X363245Y1357603D03*
X368201D03*
X363245Y1369889D03*
Y1381801D03*
Y1374881D03*
X368201D03*
Y1381801D03*
Y1369889D03*
X363245Y1399079D03*
Y1394087D03*
Y1386793D03*
X368201D03*
Y1394087D03*
Y1399079D03*
X363245Y1405999D03*
Y1410991D03*
X368201D03*
Y1405999D03*
X372000Y1644980D03*
X393544Y76140D03*
Y84140D03*
Y80140D03*
X384467Y94017D03*
X388476D03*
X380467D03*
X390997Y117557D03*
X385587Y115401D03*
X380595D03*
X385587Y110445D03*
X380595D03*
X390997Y131731D03*
Y122513D03*
X385587Y129574D03*
X380595D03*
X385587Y124618D03*
X380595D03*
X390997Y136687D03*
X382158Y191941D03*
X388658Y184619D03*
X382025Y188727D03*
X390638Y206760D03*
X391852Y256535D03*
X383852D03*
X392882Y279208D03*
X378679Y285690D03*
Y288190D03*
X386905Y290755D03*
X382905D03*
X390905D03*
X392387Y337599D03*
Y342555D03*
X392444Y401949D03*
X393893Y413611D03*
X393833Y423944D03*
X393652Y482382D03*
X393746Y478382D03*
X388593Y664232D03*
X386350Y693559D03*
X391478Y690675D03*
X391614Y938651D03*
X381377Y1003008D03*
X381045Y1009444D03*
X391284Y1307238D03*
X394000Y1508100D03*
X382017Y1555700D03*
Y1547700D03*
Y1551700D03*
X392000Y1644980D03*
X408493Y117577D03*
X395989Y117557D03*
Y131731D03*
Y122513D03*
Y136687D03*
X399373Y180527D03*
X394690Y180572D03*
X403096Y192421D03*
X394690Y185165D03*
X399328Y185121D03*
X396986Y281307D03*
X409484Y314921D03*
X398951Y333711D03*
X397374Y344439D03*
X407493Y354142D03*
X394237Y370899D03*
X394944Y398949D03*
X399518Y402642D03*
X402018D03*
X396633Y423944D03*
X396693Y413611D03*
X399193D03*
X401693D03*
X401633Y423944D03*
X399133D03*
X409284Y741316D03*
X401121Y936686D03*
X409121Y939186D03*
X401121D03*
X409121Y936686D03*
X409231Y1123101D03*
X406105Y1139435D03*
X410131Y1129301D03*
X407631D03*
X409231Y1125801D03*
X406105Y1131935D03*
Y1134435D03*
Y1136935D03*
Y1141935D03*
Y1146935D03*
Y1144435D03*
X403263Y1152684D03*
X406319Y1204405D03*
Y1206905D03*
Y1211905D03*
Y1209405D03*
X397695Y1287071D03*
X399716Y1295198D03*
X408523Y1332967D03*
X404657D03*
X408937Y1351568D03*
X403981D03*
X401990Y1446807D03*
X399731Y1442755D03*
X397245Y1511640D03*
X404053Y1513673D03*
X397220Y1521207D03*
X409461Y1569560D03*
X405461D03*
X426147Y151540D03*
X414626Y180665D03*
Y172665D03*
X414658Y212864D03*
Y200864D03*
Y216864D03*
Y221864D03*
X422873Y309966D03*
X419955Y306966D03*
X414999D03*
X411984Y314921D03*
X421231Y338523D03*
Y331255D03*
Y345776D03*
X413432Y346797D03*
X416318Y367903D03*
X424479Y367859D03*
X418754Y468607D03*
X418226Y653288D03*
Y646480D03*
Y648980D03*
Y655788D03*
X425121Y936686D03*
Y939186D03*
X417121Y936686D03*
Y939186D03*
X417677Y1052215D03*
X425175Y1098767D03*
X417171Y1098887D03*
X419987Y1098518D03*
X419731Y1123101D03*
X417231D03*
X422631Y1125801D03*
X425131Y1129301D03*
X422631D03*
X420131D03*
X417631D03*
X415131D03*
X412631D03*
X420131Y1125801D03*
X417631D03*
X425131D03*
X422495Y1152713D03*
Y1155213D03*
X412095Y1152713D03*
Y1155213D03*
X422934Y1200821D03*
Y1198321D03*
X420619Y1204617D03*
Y1207117D03*
Y1209617D03*
Y1212117D03*
X411174Y1282776D03*
X418537Y1300197D03*
X423741Y1300115D03*
X413354Y1300197D03*
X425582Y1291743D03*
X423762Y1305298D03*
X413374D03*
X418558Y1310523D03*
X413395Y1310481D03*
X423721Y1310523D03*
X425283Y1373958D03*
X411147Y1474993D03*
X419818Y1474945D03*
X415241Y1492990D03*
X415095Y1502750D03*
X411353Y1519440D03*
X419467Y1519706D03*
X420279Y1525978D03*
X410626Y1525991D03*
X413461Y1569560D03*
X412000Y1644980D03*
X441727Y146461D03*
X440629Y152367D03*
X435703Y306966D03*
X430747D03*
X427829Y309966D03*
X428459Y331255D03*
X435793D03*
X428500Y345776D03*
X435793Y345738D03*
X430439Y358115D03*
X435702Y367813D03*
X430746D03*
X427782Y464026D03*
X438396Y511493D03*
X435834Y509580D03*
X431804Y536682D03*
Y539182D03*
X441832Y626193D03*
X433206Y1055498D03*
X430706D03*
Y1057998D03*
X433206D03*
Y1060498D03*
Y1062998D03*
X430706D03*
Y1060498D03*
X441359Y1123101D03*
X438233Y1139435D03*
X441359Y1125801D03*
X439759Y1129301D03*
X442259D03*
X429331Y1136935D03*
Y1134435D03*
Y1139435D03*
Y1131935D03*
X435733D03*
Y1134435D03*
Y1136935D03*
Y1139435D03*
X438233Y1131935D03*
Y1134435D03*
Y1136935D03*
X429331Y1141935D03*
X435733D03*
Y1146935D03*
Y1144435D03*
X438233Y1141935D03*
Y1146935D03*
Y1144435D03*
X437231Y1154902D03*
Y1152402D03*
X429331Y1146935D03*
Y1144435D03*
X433249Y1204405D03*
Y1209405D03*
Y1211905D03*
Y1206905D03*
X437991Y1286544D03*
X440896Y1311366D03*
X432485Y1325784D03*
X439624Y1345691D03*
Y1350683D03*
Y1357603D03*
Y1362595D03*
Y1381801D03*
Y1369889D03*
Y1374881D03*
X436002Y1382252D03*
X439624Y1386793D03*
X437675Y1550158D03*
X429784Y1548222D03*
X432000Y1644980D03*
X458454Y328963D03*
Y324007D03*
Y339755D03*
Y344711D03*
X453463Y370694D03*
X448092Y375770D03*
X443094Y491251D03*
X455104Y536582D03*
Y539082D03*
X447279Y633881D03*
X454815Y974622D03*
X448999Y994483D03*
X456210Y1004680D03*
X452319Y1000828D03*
X449731Y1000855D03*
X453710Y1018825D03*
X443091Y1022766D03*
Y1030266D03*
X450063Y1043140D03*
X449767Y1047047D03*
X457303Y1098767D03*
X452115Y1098518D03*
X446863Y1098428D03*
X449359Y1123101D03*
X451859D03*
X457259Y1129301D03*
X449759Y1125801D03*
X452259D03*
X444759Y1129301D03*
X447259D03*
X449759D03*
X452259D03*
X454759Y1125801D03*
X457259D03*
X454759Y1129301D03*
X443223Y1155213D03*
Y1152713D03*
X452623D03*
Y1155213D03*
X447549Y1204617D03*
X449864Y1198321D03*
Y1200821D03*
X447549Y1209617D03*
Y1207117D03*
Y1212117D03*
X454120Y1269498D03*
X456213Y1286776D03*
X451304Y1293045D03*
X456820Y1345691D03*
X451864D03*
Y1350683D03*
X456820D03*
X444580Y1345691D03*
Y1350683D03*
X456820Y1362595D03*
Y1357603D03*
X451864Y1362595D03*
Y1357603D03*
X444580D03*
Y1362595D03*
X456820Y1374881D03*
X451864D03*
X444580Y1369889D03*
X456820Y1369795D03*
X451864D03*
X444580Y1374881D03*
Y1381801D03*
X456820D03*
X451864D03*
X456820Y1399079D03*
X451864Y1393993D03*
Y1399079D03*
X456820Y1393993D03*
Y1386793D03*
X451864D03*
X444580D03*
X456820Y1405999D03*
X451864D03*
Y1410991D03*
X456820D03*
X454125Y1461182D03*
Y1465913D03*
Y1471805D03*
Y1481267D03*
Y1476536D03*
Y1491890D03*
Y1487159D03*
Y1496621D03*
Y1511976D03*
Y1507245D03*
Y1502514D03*
Y1558813D03*
Y1578898D03*
Y1568275D03*
Y1563544D03*
Y1574167D03*
Y1583629D03*
Y1589522D03*
Y1594253D03*
Y1609607D03*
Y1598984D03*
Y1604876D03*
Y1614338D03*
X452000Y1644980D03*
X464738Y110784D03*
X462089Y113394D03*
X472332Y133298D03*
X464332D03*
X466479Y134579D03*
X464054Y252371D03*
X461454Y336837D03*
Y331881D03*
Y347629D03*
Y352585D03*
X466375Y366365D03*
X470389Y389553D03*
X468558Y491669D03*
Y503669D03*
Y507669D03*
Y512669D03*
X462242Y809792D03*
X475032Y843252D03*
X474678Y857919D03*
X463134Y859203D03*
X460455Y867050D03*
X475046Y885952D03*
X467494Y924532D03*
X462427Y1030218D03*
X460277Y1090268D03*
Y1093068D03*
X474818Y1123101D03*
X469192Y1131935D03*
X474818Y1125801D03*
X473218Y1129301D03*
X461459Y1136935D03*
Y1134435D03*
Y1139435D03*
Y1131935D03*
X471692Y1139435D03*
Y1136935D03*
Y1134435D03*
Y1131935D03*
X469192Y1139435D03*
Y1136935D03*
Y1134435D03*
X471692Y1146935D03*
Y1141935D03*
X469192Y1144435D03*
Y1146935D03*
Y1141935D03*
X471692Y1144435D03*
X461459D03*
X462687Y1152684D03*
X468850D03*
X461459Y1141935D03*
Y1146935D03*
X463216Y1254164D03*
Y1250760D03*
Y1244055D03*
X461613Y1286776D03*
X469060Y1345691D03*
Y1350683D03*
X464104Y1345691D03*
Y1350683D03*
X469060Y1357603D03*
Y1362595D03*
X464104D03*
Y1357603D03*
Y1381801D03*
X469060D03*
X464104Y1369889D03*
X469060D03*
X464104Y1374881D03*
X469060D03*
Y1386793D03*
X464104D03*
X469060Y1399079D03*
X464104Y1394087D03*
X469060D03*
X464104Y1399079D03*
Y1405999D03*
X469060D03*
X464104Y1410991D03*
X469060D03*
X471448Y1461182D03*
X462786Y1460782D03*
X471448Y1465913D03*
X462786Y1465513D03*
X471448Y1481267D03*
X462786Y1480867D03*
X471448Y1471805D03*
Y1476536D03*
X462786Y1476136D03*
Y1470244D03*
X471448Y1496621D03*
X462786Y1496221D03*
X471448Y1491890D03*
X462786Y1491490D03*
Y1485598D03*
X471448Y1487159D03*
Y1511976D03*
Y1502514D03*
Y1507245D03*
X462786Y1511576D03*
Y1506845D03*
Y1500952D03*
Y1516307D03*
Y1563144D03*
X471448Y1558813D03*
X462786Y1578498D03*
X471448Y1574167D03*
Y1568275D03*
Y1563544D03*
X462786Y1567875D03*
Y1572606D03*
X471448Y1578898D03*
Y1594253D03*
X462786Y1593853D03*
X471448Y1589522D03*
Y1583629D03*
X462786Y1583229D03*
Y1587960D03*
X471448Y1598984D03*
X462786Y1609207D03*
Y1598584D03*
Y1603315D03*
X471448Y1609607D03*
Y1604876D03*
Y1614338D03*
X462786Y1613938D03*
Y1618669D03*
X472000Y1644980D03*
X480324Y109172D03*
X477324D03*
X479331Y106495D03*
X483075Y116497D03*
X487875D03*
X490375Y109410D03*
Y116497D03*
X483075Y130670D03*
X487875Y123584D03*
Y130670D03*
X490375Y123583D03*
Y130670D03*
X483075Y123584D03*
X479065Y146012D03*
X480971Y141228D03*
X483075Y137757D03*
X487875D03*
X483859Y150847D03*
X485827Y247292D03*
X478536Y253198D03*
X483242Y366481D03*
X483584Y375840D03*
X483736Y371266D03*
X483541Y380306D03*
X481724Y391589D03*
Y387089D03*
X488438Y425464D03*
X482532Y418464D03*
X482484Y444517D03*
X486738Y581222D03*
X489538D03*
Y591215D03*
X486738D03*
X491340Y611091D03*
X485005Y659771D03*
X491324Y667293D03*
X485303Y681841D03*
X486246Y804497D03*
X485824Y819787D03*
X481593Y826387D03*
X491453Y834546D03*
X491527Y843206D03*
X488469Y857013D03*
X481943Y924633D03*
X488388Y938903D03*
X483636Y952152D03*
X490143Y989521D03*
X476148Y1057998D03*
Y1055498D03*
X478648D03*
Y1057998D03*
X476148Y1060498D03*
Y1062998D03*
X478648D03*
Y1060498D03*
X490762Y1098767D03*
X485574Y1098518D03*
X480322Y1098428D03*
X485318Y1123101D03*
X482818D03*
X490718Y1129301D03*
X483218Y1125801D03*
X485718D03*
X475718Y1129301D03*
X478218D03*
X480718D03*
X483218D03*
X485718D03*
X488218Y1125801D03*
X490718D03*
X488218Y1129301D03*
X477682Y1152713D03*
Y1155213D03*
X488082D03*
Y1152713D03*
X479521Y1204405D03*
Y1206905D03*
Y1211905D03*
Y1209405D03*
X488584Y1345691D03*
Y1350683D03*
X481300Y1345691D03*
X476344D03*
X481300Y1350683D03*
X476344D03*
X488584Y1357603D03*
Y1362595D03*
X481300D03*
Y1357603D03*
X476344Y1362595D03*
Y1357603D03*
X488584Y1381801D03*
X481300D03*
X488584Y1374881D03*
Y1369889D03*
X481300D03*
Y1374881D03*
X476344Y1381801D03*
Y1369889D03*
Y1374881D03*
X488584Y1386793D03*
X481300D03*
Y1399079D03*
X476344Y1394087D03*
Y1399079D03*
X488584Y1394087D03*
X481300D03*
X488584Y1399079D03*
X476344Y1386793D03*
Y1410991D03*
X481300Y1405999D03*
X476344D03*
X488584D03*
Y1410991D03*
X481300D03*
X480109Y1460782D03*
Y1465513D03*
X488771Y1465913D03*
Y1461182D03*
X480109Y1476136D03*
Y1470244D03*
X488771Y1471805D03*
Y1476536D03*
Y1481267D03*
X480109Y1480867D03*
Y1496221D03*
X488771Y1487159D03*
Y1491890D03*
X480109Y1491490D03*
Y1485598D03*
X488771Y1496621D03*
Y1511976D03*
X480109Y1511576D03*
Y1506845D03*
Y1500952D03*
X488771Y1502514D03*
Y1507245D03*
X480109Y1516307D03*
X488771Y1558813D03*
X480109Y1563144D03*
X488771Y1578898D03*
X480109Y1578498D03*
X488771Y1574167D03*
Y1568275D03*
Y1563544D03*
X480109Y1567875D03*
Y1572606D03*
X488771Y1589522D03*
Y1583629D03*
X480109Y1583229D03*
Y1587960D03*
X488771Y1594253D03*
X480109Y1593853D03*
X488771Y1609607D03*
Y1604876D03*
Y1598984D03*
X480109Y1609207D03*
Y1598584D03*
Y1603315D03*
X488771Y1614338D03*
X480109Y1613938D03*
Y1618669D03*
X503537Y77784D03*
Y75184D03*
Y80384D03*
Y82984D03*
X506091Y92849D03*
X503537Y85584D03*
X495075Y116496D03*
Y102323D03*
Y109410D03*
Y130670D03*
Y123583D03*
Y137756D03*
X497424Y354559D03*
X492317Y376252D03*
X503682Y455466D03*
X497776Y448466D03*
X493929Y555194D03*
X496729D03*
X493929Y563194D03*
X496729D03*
X493929Y571194D03*
X496729D03*
X492338Y581222D03*
Y591215D03*
X494632Y654622D03*
X501618Y698355D03*
X499012Y699819D03*
X503311Y715652D03*
X500705Y705524D03*
X507546Y738539D03*
X505673Y767961D03*
X500717D03*
X504341Y812040D03*
X491655Y829173D03*
X506246Y824689D03*
X492799Y846488D03*
X503741Y846830D03*
X497467Y833027D03*
X499640Y861538D03*
X499595Y963963D03*
X493050Y976078D03*
X506566Y1000766D03*
Y1004766D03*
Y1016266D03*
Y1030766D03*
X505981Y1052487D03*
X506946Y1123101D03*
Y1125801D03*
X505346Y1129301D03*
X507846D03*
X503820Y1139435D03*
Y1136935D03*
Y1134435D03*
Y1131935D03*
X501320Y1139435D03*
Y1136935D03*
Y1134435D03*
Y1131935D03*
X494918Y1136935D03*
Y1134435D03*
Y1139435D03*
Y1131935D03*
X503820Y1144435D03*
Y1146935D03*
Y1141935D03*
X501320Y1144435D03*
Y1146935D03*
Y1141935D03*
X494918Y1146935D03*
Y1144435D03*
Y1141935D03*
X502562Y1152713D03*
Y1155213D03*
X506451Y1204405D03*
X493821Y1204617D03*
X496136Y1200821D03*
Y1198321D03*
X506451Y1206905D03*
Y1211905D03*
Y1209405D03*
X493821Y1207117D03*
Y1209617D03*
Y1212117D03*
X500824Y1350683D03*
Y1345691D03*
X505780Y1350683D03*
Y1345691D03*
X493540D03*
Y1350683D03*
X505780Y1362595D03*
Y1357603D03*
X500824Y1362595D03*
Y1357603D03*
X493540Y1362595D03*
Y1357603D03*
Y1381801D03*
Y1374881D03*
Y1369889D03*
X505780Y1381801D03*
Y1374881D03*
Y1369889D03*
X500824D03*
Y1381801D03*
Y1374881D03*
Y1394087D03*
X505780Y1399079D03*
X500824D03*
X505780Y1394087D03*
X493540Y1386793D03*
Y1394087D03*
Y1399079D03*
X505780Y1386793D03*
X500824D03*
X505780Y1410991D03*
X500824D03*
X505780Y1405999D03*
X500824D03*
X493540D03*
Y1410991D03*
X497432Y1465513D03*
X506093Y1465913D03*
X497432Y1460782D03*
X506093Y1461182D03*
X497432Y1480867D03*
X506093Y1481267D03*
X497432Y1476136D03*
Y1470244D03*
X506093Y1471805D03*
Y1476536D03*
X497432Y1496221D03*
Y1491490D03*
Y1485598D03*
X506093Y1487159D03*
Y1491890D03*
Y1496621D03*
Y1511976D03*
X497432Y1506845D03*
Y1500952D03*
X506093Y1502514D03*
Y1507245D03*
X497432Y1511576D03*
Y1516307D03*
Y1563144D03*
X506093Y1558813D03*
X497432Y1578498D03*
X506093Y1578898D03*
X497432Y1567875D03*
Y1572606D03*
X506093Y1574167D03*
Y1568275D03*
Y1563544D03*
X497432Y1587960D03*
X506093Y1589522D03*
Y1583629D03*
X497432Y1593853D03*
X506093Y1594253D03*
X497432Y1583229D03*
X506093Y1604876D03*
Y1598984D03*
X497432Y1609207D03*
X506093Y1609607D03*
X497432Y1598584D03*
Y1603315D03*
Y1613938D03*
Y1618669D03*
X506093Y1614338D03*
X492000Y1644980D03*
X513051Y103037D03*
X513185Y116496D03*
Y109410D03*
Y130670D03*
Y123583D03*
X509251Y137756D03*
X517866Y293796D03*
X515366D03*
X523380Y285690D03*
Y288190D03*
X511342Y311124D03*
X520845Y434508D03*
X516845D03*
X512845D03*
X514608Y445874D03*
X510022Y446352D03*
X523705Y444269D03*
X523583Y447201D03*
X521636Y504699D03*
X516636D03*
X519136D03*
X516338Y516979D03*
X521338D03*
X518838D03*
X512404Y629362D03*
X510215Y627948D03*
X511990Y686365D03*
X518001Y694940D03*
X522410Y694881D03*
X518067Y699378D03*
X518530Y703584D03*
X522628Y703884D03*
X508237Y723585D03*
X512502Y738539D03*
X516953Y738575D03*
X521909D03*
X520159Y758832D03*
X509063Y782867D03*
X517194Y773232D03*
X522316Y793574D03*
X509316Y793224D03*
X508130Y787488D03*
X521178Y814001D03*
X521565Y820931D03*
X520720Y846133D03*
X517832Y834558D03*
X508049Y877789D03*
X523272Y880067D03*
X509428Y888390D03*
X521115Y897500D03*
X511025Y911443D03*
X509673Y900295D03*
X516256Y939157D03*
X514886Y952189D03*
X519792Y1031271D03*
X517702Y1098518D03*
X512450Y1098428D03*
X522890Y1098767D03*
X514946Y1123101D03*
X517446D03*
X522846Y1129301D03*
X515346Y1125801D03*
X517846D03*
X510346Y1129301D03*
X512846D03*
X515346D03*
X517846D03*
X520346Y1125801D03*
X522846D03*
X520346Y1129301D03*
X518210Y1155213D03*
Y1152713D03*
X508810D03*
Y1155213D03*
X520751Y1204617D03*
X523066Y1200821D03*
Y1198321D03*
X520751Y1207117D03*
Y1209617D03*
Y1212117D03*
X513064Y1345691D03*
X518020Y1350683D03*
X513064D03*
X518020Y1345691D03*
Y1357603D03*
X513064Y1362595D03*
Y1357603D03*
X518020Y1362595D03*
X513064Y1369889D03*
Y1381801D03*
Y1374881D03*
X518020Y1369889D03*
Y1381801D03*
Y1374881D03*
Y1394087D03*
Y1399079D03*
X513064Y1394087D03*
Y1399079D03*
Y1386793D03*
X518020D03*
Y1405999D03*
Y1410991D03*
X513064D03*
Y1405999D03*
X514755Y1460782D03*
Y1465513D03*
Y1480867D03*
Y1476136D03*
Y1470244D03*
Y1491490D03*
Y1485598D03*
Y1496221D03*
Y1511576D03*
Y1506845D03*
Y1500952D03*
Y1516307D03*
Y1563144D03*
Y1567875D03*
Y1572606D03*
Y1578498D03*
Y1593853D03*
Y1583229D03*
Y1587960D03*
Y1603315D03*
Y1609207D03*
Y1598584D03*
Y1613938D03*
Y1618669D03*
X512000Y1644980D03*
X526468Y94017D03*
X534468D03*
X538477D03*
X530468D03*
X530596Y115401D03*
X535588Y110445D03*
Y115401D03*
X530596Y110445D03*
Y124618D03*
Y129574D03*
X535588Y124618D03*
Y129574D03*
X528509Y151540D03*
X538659Y184619D03*
X532159Y191941D03*
X532026Y188727D03*
X528783Y226141D03*
X525983D03*
X533853Y256535D03*
X525880Y285690D03*
X528680D03*
X525880Y288190D03*
X528680D03*
X532906Y290755D03*
X536906D03*
X540906D03*
X524206Y354119D03*
X533027Y351836D03*
X530215Y364422D03*
X535142Y397552D03*
X532936Y519544D03*
X527936D03*
X525436D03*
X530436D03*
X538826Y633450D03*
X526756Y636005D03*
Y633205D03*
X538826Y636250D03*
Y639050D03*
X526756Y638805D03*
X524653Y643595D03*
X534940Y684489D03*
X539111Y681459D03*
X526956Y694959D03*
X526951Y699443D03*
X535387Y712617D03*
X526933Y703820D03*
X532628Y720776D03*
X526276Y721339D03*
X539763Y734097D03*
X534807D03*
X531763Y739097D03*
X526807D03*
X532450Y767474D03*
X532278Y762736D03*
X531501Y792331D03*
X531260Y794934D03*
X531666Y815724D03*
X531313Y822693D03*
X527733Y847026D03*
X527346Y911458D03*
X528674Y964851D03*
X527046Y1131935D03*
Y1139435D03*
Y1134435D03*
Y1136935D03*
X528274Y1152684D03*
X527046Y1146935D03*
Y1144435D03*
Y1141935D03*
X525304Y1345691D03*
X530260D03*
X537544Y1350683D03*
X525304D03*
X530260D03*
X537544Y1345691D03*
Y1357603D03*
X525304Y1362595D03*
X530260D03*
X525304Y1357603D03*
X530260D03*
X537544Y1362595D03*
Y1374881D03*
X525304Y1369889D03*
Y1381801D03*
Y1374881D03*
X530260Y1369889D03*
Y1381801D03*
Y1374881D03*
X537544Y1369889D03*
Y1381801D03*
Y1399079D03*
Y1394087D03*
X530260D03*
Y1399079D03*
X525304Y1394087D03*
Y1399079D03*
X537544Y1386793D03*
X525304D03*
X530260D03*
X537544Y1410991D03*
Y1405999D03*
X530260D03*
X525304D03*
X530260Y1410991D03*
X525304D03*
X532000Y1644980D03*
X543545Y84140D03*
Y80140D03*
Y76140D03*
X540998Y117557D03*
X545990D03*
Y122513D03*
Y131731D03*
X540998Y122513D03*
Y131731D03*
X544089Y146461D03*
X545990Y136687D03*
X540998D03*
X542991Y152367D03*
X549374Y180527D03*
X544691Y180572D03*
X553097Y192421D03*
X549329Y185121D03*
X544691Y185165D03*
X540639Y206760D03*
X541853Y256535D03*
X542883Y279208D03*
X546987Y281307D03*
X541644Y389047D03*
X553731Y388487D03*
X541706Y381723D03*
X552905Y430829D03*
X550274Y658676D03*
X556574Y684031D03*
Y700031D03*
Y688987D03*
Y716031D03*
Y704987D03*
Y720987D03*
X552384Y762892D03*
X552188Y766577D03*
X553871Y811298D03*
X545741Y804149D03*
X548464Y823156D03*
X540807Y816556D03*
X541129Y828335D03*
Y838865D03*
X545981Y846389D03*
X549241Y841388D03*
X545237Y850319D03*
X548521Y877859D03*
Y874859D03*
X545144Y909025D03*
X544793Y899220D03*
X548215Y1006560D03*
X552923Y997860D03*
X541766Y1018368D03*
X557681Y1035088D03*
X554740Y1345597D03*
X542500Y1345691D03*
X549784Y1345597D03*
X542500Y1350683D03*
X549784D03*
X554740D03*
Y1362595D03*
Y1357603D03*
X542500Y1362595D03*
X549784D03*
X542500Y1357603D03*
X549784D03*
X554740Y1381801D03*
Y1374881D03*
X542500D03*
X549784Y1369889D03*
Y1381801D03*
Y1374881D03*
X542500Y1369889D03*
Y1381801D03*
X554740Y1369889D03*
Y1399079D03*
Y1393993D03*
X542500Y1399079D03*
X549784Y1393993D03*
Y1399079D03*
X542500Y1394087D03*
X554740Y1386793D03*
X549784D03*
X542500D03*
X554740Y1410991D03*
Y1405999D03*
X542500Y1410991D03*
X549784D03*
X542500Y1405999D03*
X549784D03*
X552000Y1644980D03*
X566287Y60922D03*
X561123Y55513D03*
X563224Y96813D03*
X558316Y91951D03*
X556920Y117261D03*
X567100Y110784D03*
X564451Y113394D03*
X567290Y130898D03*
X568841Y134579D03*
X564627Y180665D03*
Y172665D03*
X569969Y195176D03*
X564659Y212864D03*
Y200864D03*
X569829Y203393D03*
X564659Y221864D03*
Y216864D03*
X566416Y252371D03*
X570634Y375453D03*
X559074Y696987D03*
Y692031D03*
Y712987D03*
Y708031D03*
X561886Y728138D03*
X559625Y739609D03*
X557813Y747814D03*
X570578Y749800D03*
X570695Y767052D03*
X564276Y776701D03*
X558241Y796389D03*
X569186Y787332D03*
X561401Y811242D03*
X567316Y806224D03*
X561061Y803606D03*
X563099Y829943D03*
X567316Y827724D03*
X559741Y822149D03*
X572171Y842346D03*
X559196Y846296D03*
X569577Y886913D03*
X560814Y901022D03*
X564923Y997860D03*
X560923D03*
X568923D03*
X556923D03*
X571857Y1009354D03*
X565451Y1035102D03*
X569520Y1102091D03*
X560211D03*
X566020D03*
X569520Y1114691D03*
X566020D03*
X560211D03*
X569520Y1139891D03*
X566020D03*
X560211D03*
X566020Y1127291D03*
X560211D03*
X569520D03*
X566020Y1152491D03*
X560211D03*
X569520D03*
X566020Y1165091D03*
X560211D03*
X569520D03*
X560211Y1177691D03*
X566020D03*
X569520D03*
X566502Y1202103D03*
X569882Y1223749D03*
X562024Y1350683D03*
Y1345691D03*
X566980D03*
Y1350683D03*
X562024Y1357603D03*
X566980D03*
Y1362595D03*
X562024D03*
Y1369889D03*
Y1381801D03*
Y1374881D03*
X566980Y1369889D03*
Y1381801D03*
Y1374881D03*
Y1399079D03*
Y1394087D03*
X562024Y1399079D03*
Y1394087D03*
X566980Y1386793D03*
X562024D03*
X566980Y1410991D03*
X562024D03*
X566980Y1405999D03*
X562024D03*
X565600Y1530800D03*
X569349Y1541947D03*
X560635Y1543531D03*
X566800Y1541800D03*
X582686Y109172D03*
X579686D03*
X581693Y106495D03*
X585437Y116497D03*
X574694Y133298D03*
X585437Y123584D03*
Y130670D03*
X581427Y146012D03*
X583333Y141228D03*
X585437Y137757D03*
X586221Y150847D03*
X588189Y247292D03*
X580898Y253198D03*
X581487Y336676D03*
X573805Y728301D03*
X574620Y772724D03*
X584624Y781850D03*
X581001Y814123D03*
X579758Y817753D03*
X579827Y884000D03*
X579251Y903364D03*
X582706Y908959D03*
X580923Y997860D03*
X576923D03*
X588923D03*
X577666Y1009354D03*
X581166D03*
X572923Y997860D03*
X584923D03*
X581166Y1021954D03*
X577666D03*
X578298Y1215195D03*
X584024Y1209607D03*
X587689Y1505724D03*
X583661Y1529142D03*
X573784Y1530646D03*
X575332Y1523740D03*
X583800Y1518000D03*
X583740Y1520640D03*
X587858Y1517942D03*
X577645Y1540982D03*
X580700Y1544100D03*
X592737Y109410D03*
X590237Y116497D03*
X592737D03*
X597437Y102323D03*
Y109410D03*
Y116496D03*
Y123583D03*
Y130670D03*
X592737Y123583D03*
X590237Y123584D03*
Y130670D03*
X592737D03*
X597437Y137756D03*
X590237Y137757D03*
X590178Y309760D03*
X593690Y450750D03*
X597872Y512743D03*
X592880D03*
X597789Y536382D03*
X602756Y597580D03*
X604979Y599588D03*
X604241Y589556D03*
X604180Y592354D03*
X602695Y594668D03*
X604982Y596095D03*
X605011Y615600D03*
X604979Y607588D03*
X592238Y880612D03*
X597129Y913386D03*
X602385Y940920D03*
X596923Y997860D03*
X592923D03*
X604923D03*
X600923D03*
X602603Y1012354D03*
Y1024954D03*
X604405Y1034870D03*
X591898Y1035011D03*
X590957Y1105091D03*
Y1117691D03*
Y1130291D03*
Y1155491D03*
Y1142891D03*
Y1168091D03*
Y1180691D03*
X592978Y1514812D03*
X591858Y1523542D03*
X598800Y1546400D03*
X605899Y80384D03*
Y82984D03*
Y77784D03*
Y75184D03*
X608453Y92849D03*
X605899Y85584D03*
X615413Y103037D03*
X615547Y116496D03*
Y109410D03*
Y130670D03*
Y123583D03*
X612138Y137756D03*
X617728Y293796D03*
X620228D03*
X614461Y555234D03*
X614176Y562003D03*
X609472Y634946D03*
X612489Y941024D03*
X616923Y997860D03*
X608923D03*
X620151Y1040363D03*
X619086Y1056453D03*
X620715Y1046785D03*
X612000Y1644980D03*
X636830Y94017D03*
X628830D03*
X632830D03*
X632958Y110445D03*
Y115401D03*
Y124618D03*
Y129574D03*
X630871Y151540D03*
X634521Y191941D03*
X634388Y188727D03*
X631145Y226141D03*
X628345D03*
X636215Y256535D03*
X631042Y288190D03*
Y285690D03*
X625742Y288190D03*
X628242Y285690D03*
X625742D03*
X628242Y288190D03*
X635268Y290755D03*
X634455Y389154D03*
Y396240D03*
Y403327D03*
Y410413D03*
Y417500D03*
Y424587D03*
Y431673D03*
Y438760D03*
Y445847D03*
Y467539D03*
Y474626D03*
Y488799D03*
Y481713D03*
Y495886D03*
Y511673D03*
Y518760D03*
Y525847D03*
Y532933D03*
Y540020D03*
Y547106D03*
X633736Y602197D03*
X634200Y595108D03*
X622270Y864781D03*
X630466Y1394087D03*
X625510Y1399079D03*
Y1394087D03*
X630466Y1399079D03*
X625510Y1405999D03*
X630466D03*
X625510Y1410991D03*
X630466D03*
X636015Y1460782D03*
X627354Y1461182D03*
X636015Y1465513D03*
X627354Y1465913D03*
Y1456451D03*
X636015Y1476136D03*
X627354Y1476536D03*
X636015Y1480867D03*
X627354Y1481267D03*
Y1471805D03*
X636015Y1470244D03*
X627354Y1487159D03*
X636015Y1485598D03*
Y1491490D03*
X627354Y1491890D03*
X636015Y1496221D03*
X627354Y1496621D03*
Y1507245D03*
Y1511976D03*
X636015Y1511576D03*
X627354Y1502514D03*
X636015Y1500952D03*
Y1506845D03*
Y1516307D03*
X627354Y1558813D03*
X636015Y1563144D03*
X627354Y1563544D03*
X636015Y1567875D03*
X627354Y1568275D03*
Y1574167D03*
X636015Y1572606D03*
Y1578498D03*
X627354Y1578898D03*
X636015Y1593853D03*
X627354Y1594253D03*
X636015Y1583229D03*
X627354Y1583629D03*
Y1589522D03*
X636015Y1587960D03*
X627354Y1604876D03*
X636015Y1603315D03*
Y1598584D03*
X627354Y1598984D03*
X636015Y1609207D03*
X627354Y1609607D03*
X636015Y1618669D03*
Y1613938D03*
X627354Y1614338D03*
X632000Y1644980D03*
X645907Y76140D03*
Y84140D03*
Y80140D03*
X640839Y94017D03*
X643360Y117557D03*
X637950Y110445D03*
Y115401D03*
X648352Y117557D03*
X643360Y122513D03*
Y131731D03*
X637950Y124618D03*
Y129574D03*
X648352Y122513D03*
Y131731D03*
X646451Y146461D03*
X643360Y136687D03*
X648352D03*
X645353Y152367D03*
X647053Y180572D03*
X651736Y180527D03*
X651691Y185121D03*
X647053Y185165D03*
X641021Y184619D03*
X643001Y206760D03*
X644215Y256535D03*
X645245Y279208D03*
X649349Y281307D03*
X639268Y290755D03*
X643268D03*
X649074Y389154D03*
X647604Y396240D03*
X652381Y414823D03*
X651689Y422864D03*
X651759Y429832D03*
X651364Y436447D03*
X653399Y447953D03*
X652566Y467539D03*
X651308Y472772D03*
X652042Y487711D03*
X652155Y479104D03*
X652566Y495886D03*
X647915Y516841D03*
X651166Y510565D03*
X642862Y550123D03*
X642740Y552872D03*
X644494Y572334D03*
X642185Y562443D03*
X643953Y560675D03*
X642726Y574102D03*
X647361Y653161D03*
X648352Y645467D03*
X650958Y677843D03*
X649990Y1350683D03*
Y1345691D03*
Y1357603D03*
Y1362595D03*
Y1381801D03*
X642706Y1374881D03*
Y1381801D03*
Y1369889D03*
X649990Y1374881D03*
Y1369889D03*
X637750Y1374881D03*
Y1381801D03*
Y1369889D03*
X649990Y1399079D03*
Y1394087D03*
X642706Y1386793D03*
X649990D03*
X637750Y1399079D03*
X642706Y1394087D03*
X637750D03*
X642706Y1399079D03*
X637750Y1386793D03*
X649990Y1405999D03*
Y1410991D03*
X637750D03*
X642706D03*
Y1405999D03*
X637750D03*
X653338Y1465513D03*
X644677Y1461182D03*
Y1456451D03*
Y1465913D03*
X653338Y1460782D03*
X644677Y1476536D03*
Y1471805D03*
X653338Y1480867D03*
Y1470244D03*
Y1476136D03*
X644677Y1481267D03*
X653338Y1491490D03*
X644677Y1496621D03*
Y1491890D03*
Y1487159D03*
X653338Y1496221D03*
Y1485598D03*
X644677Y1511976D03*
X653338Y1511576D03*
Y1500952D03*
Y1506845D03*
X644677Y1502514D03*
Y1507245D03*
X653338Y1516307D03*
X644677Y1558813D03*
X653338Y1563144D03*
X644677Y1563544D03*
X653338Y1572606D03*
Y1578498D03*
X644677Y1578898D03*
Y1574167D03*
X653338Y1567875D03*
X644677Y1568275D03*
X653338Y1587960D03*
Y1593853D03*
X644677Y1594253D03*
Y1589522D03*
X653338Y1583229D03*
X644677Y1583629D03*
X653338Y1609207D03*
X644677Y1598984D03*
Y1604876D03*
Y1609607D03*
X653338Y1603315D03*
Y1598584D03*
Y1613938D03*
X644677Y1614338D03*
X653338Y1618669D03*
X652000Y1644980D03*
X668649Y60922D03*
X666209Y57297D03*
X665423Y96853D03*
X660678Y91951D03*
X659282Y117261D03*
X666813Y113394D03*
X669462Y110784D03*
X669056Y133298D03*
X666989Y172665D03*
Y180665D03*
X655459Y192421D03*
X667021Y200864D03*
Y212864D03*
Y221864D03*
Y216864D03*
X668778Y252371D03*
X667666Y389153D03*
X665166Y396240D03*
X667666D03*
X665166Y403327D03*
X667666Y403326D03*
X665166Y410413D03*
X667666D03*
Y417499D03*
X665166Y424586D03*
X667666D03*
X665166Y417500D03*
Y431673D03*
Y438760D03*
X667666D03*
Y431673D03*
X665166Y445847D03*
X667666Y467539D03*
X665166Y474626D03*
X667666D03*
X665166Y488799D03*
X667666D03*
Y481712D03*
X665166D03*
Y495886D03*
X667666Y518760D03*
X665166D03*
X667666Y511673D03*
Y532933D03*
X665166D03*
Y540020D03*
Y525846D03*
X667666D03*
X669546Y560500D03*
X655752Y668885D03*
X661776Y662981D03*
X656157Y691851D03*
X661768Y705043D03*
X654946Y1350683D03*
X662230D03*
X667186D03*
Y1345691D03*
X654946D03*
X662230D03*
X654946Y1357603D03*
Y1362595D03*
X662230Y1357603D03*
Y1362595D03*
X667186Y1357603D03*
Y1362595D03*
X662230Y1369889D03*
X667186Y1374881D03*
Y1381801D03*
Y1369889D03*
X662230Y1374881D03*
Y1381801D03*
X654946D03*
Y1369889D03*
Y1374881D03*
X667186Y1399079D03*
Y1393993D03*
X662230D03*
Y1399079D03*
X655046D03*
Y1394087D03*
X667186Y1386793D03*
X662230D03*
X654946D03*
X667186Y1410991D03*
Y1405999D03*
X662230D03*
Y1410991D03*
X655046Y1405999D03*
Y1410991D03*
X662000Y1456451D03*
Y1465913D03*
Y1461182D03*
Y1481267D03*
Y1476536D03*
Y1471805D03*
Y1496621D03*
Y1491890D03*
Y1487159D03*
Y1511976D03*
Y1502514D03*
Y1507245D03*
Y1563544D03*
Y1558813D03*
Y1568275D03*
Y1578898D03*
Y1574167D03*
Y1594253D03*
Y1589522D03*
Y1583629D03*
Y1598984D03*
Y1604876D03*
Y1609607D03*
Y1614338D03*
X682048Y109172D03*
X685048D03*
X684055Y106495D03*
X677056Y133298D03*
X671203Y134579D03*
X683789Y146012D03*
X685695Y141228D03*
X677331Y195176D03*
X676950Y198883D03*
X683260Y253198D03*
X686012Y339795D03*
X672466Y389153D03*
Y410413D03*
Y396240D03*
Y403326D03*
Y424586D03*
Y417499D03*
Y438760D03*
Y431673D03*
Y467539D03*
Y474626D03*
Y488799D03*
Y481712D03*
Y518760D03*
Y511673D03*
Y525846D03*
Y532933D03*
X681586Y555000D03*
X681011Y543925D03*
X679426Y1350683D03*
X674470Y1345691D03*
X679426D03*
X674470Y1350683D03*
Y1357603D03*
Y1362595D03*
X679426Y1357603D03*
Y1362595D03*
Y1374881D03*
X674470D03*
Y1381801D03*
X679426D03*
Y1369889D03*
X674470D03*
X679426Y1399079D03*
X674470Y1394087D03*
X679426D03*
X674470Y1399079D03*
Y1386793D03*
X679426D03*
X674470Y1405999D03*
X679426D03*
X674470Y1410991D03*
X679426D03*
X679322Y1461182D03*
Y1456451D03*
Y1465913D03*
X670661Y1460782D03*
Y1465513D03*
Y1470244D03*
Y1476136D03*
X679322Y1481267D03*
Y1476536D03*
Y1471805D03*
X670661Y1480867D03*
X679322Y1487159D03*
X670661Y1496221D03*
Y1485598D03*
Y1491490D03*
X679322Y1496621D03*
Y1491890D03*
X670661Y1500952D03*
Y1506845D03*
X679322Y1511976D03*
Y1502514D03*
Y1507245D03*
X670661Y1511576D03*
Y1516307D03*
X679322Y1558813D03*
X670661Y1563144D03*
X679322Y1563544D03*
Y1578898D03*
Y1574167D03*
Y1568275D03*
X670661Y1572606D03*
Y1578498D03*
Y1567875D03*
X679322Y1583629D03*
X670661Y1587960D03*
Y1593853D03*
Y1583229D03*
X679322Y1594253D03*
Y1589522D03*
Y1604876D03*
Y1609607D03*
X670661Y1603315D03*
Y1598584D03*
Y1609207D03*
X679322Y1598984D03*
Y1614338D03*
X670661Y1618669D03*
Y1613938D03*
X672000Y1644980D03*
X695099Y109410D03*
X687799Y116497D03*
X692599D03*
X695099D03*
X699799Y116496D03*
Y109410D03*
Y102323D03*
X687799Y123584D03*
X695099Y123583D03*
X692599Y123584D03*
X687799Y130670D03*
X692599D03*
X695099D03*
X699799Y123583D03*
Y130670D03*
X687799Y137757D03*
X692599D03*
X699799Y137756D03*
X688583Y150847D03*
X690551Y247292D03*
X700164Y636842D03*
X698936Y678462D03*
X702691Y766471D03*
Y753471D03*
X702677Y771159D03*
Y784659D03*
X698950Y1350683D03*
Y1345597D03*
X686710Y1350683D03*
X691666D03*
X686710Y1345691D03*
X691666D03*
X698950Y1362595D03*
Y1357603D03*
X686710D03*
Y1362595D03*
X691666Y1357603D03*
Y1362595D03*
X698950Y1374881D03*
Y1381801D03*
Y1369889D03*
X691666D03*
Y1374881D03*
Y1381801D03*
X686710Y1374881D03*
Y1369889D03*
Y1381801D03*
X698950Y1399079D03*
Y1394087D03*
X686710D03*
Y1399079D03*
X691666Y1394087D03*
Y1399079D03*
X698950Y1386793D03*
X691666D03*
X686710D03*
X698950Y1405999D03*
Y1410991D03*
X686710D03*
X691666D03*
X686710Y1405999D03*
X691666D03*
X696645Y1461183D03*
Y1456452D03*
Y1465914D03*
X687984Y1460782D03*
Y1465513D03*
Y1470244D03*
Y1476136D03*
X696645Y1481268D03*
Y1471806D03*
Y1476537D03*
X687984Y1480867D03*
X696645Y1491891D03*
X687984Y1496221D03*
Y1485598D03*
Y1491490D03*
X696645Y1496622D03*
Y1487160D03*
Y1511977D03*
Y1502515D03*
Y1507246D03*
X687984Y1511576D03*
Y1500952D03*
Y1506845D03*
Y1516307D03*
X696645Y1558813D03*
Y1563544D03*
X687984Y1563144D03*
X696645Y1574167D03*
Y1578898D03*
X687984Y1572606D03*
Y1578498D03*
X696645Y1568275D03*
X687984Y1567875D03*
Y1583229D03*
X696645Y1589522D03*
Y1594253D03*
X687984Y1587960D03*
Y1593853D03*
X696645Y1583629D03*
Y1598984D03*
Y1609607D03*
X687984Y1603315D03*
Y1598584D03*
Y1609207D03*
X696645Y1604876D03*
X687984Y1613938D03*
X696645Y1614338D03*
X687984Y1618669D03*
X692000Y1644980D03*
X718488Y-27642D03*
X718503Y-25127D03*
X708261Y82984D03*
Y80384D03*
Y77784D03*
Y75184D03*
X710815Y92849D03*
X708261Y85584D03*
X717775Y103037D03*
X717909Y116496D03*
Y109410D03*
Y130670D03*
Y123583D03*
X714500Y137756D03*
X713162Y434493D03*
X711764Y449873D03*
X718691Y465492D03*
Y472579D03*
X716191D03*
X711391D03*
X716191Y479666D03*
X718691D03*
X711391D03*
Y486752D03*
X716191D03*
X718691D03*
X711391Y493839D03*
X716191D03*
Y516713D03*
Y523800D03*
X718691D03*
X711391D03*
Y516713D03*
X718691D03*
Y509626D03*
Y530886D03*
X716191D03*
Y537973D03*
X711391Y530886D03*
Y537973D03*
Y566752D03*
X718691Y559665D03*
Y566752D03*
X716191D03*
X711391Y573839D03*
X718691D03*
X716191D03*
X711391Y588013D03*
X718691Y588012D03*
X716191Y588013D03*
X718691Y580926D03*
X716191D03*
X711391D03*
X716191Y602186D03*
X711391D03*
X718691Y602185D03*
Y595099D03*
X711391D03*
X716191D03*
X711391Y609272D03*
X716191D03*
X718691D03*
X716191Y616359D03*
X711391D03*
X706070Y638125D03*
X716656Y646429D03*
X703669Y665140D03*
X716350Y699477D03*
X703604Y699653D03*
X716146Y1350683D03*
X711190D03*
X716146Y1345691D03*
X711190D03*
X703906Y1350683D03*
Y1345597D03*
X716146Y1357603D03*
X711190D03*
Y1362595D03*
X716146D03*
X703906Y1357603D03*
Y1362595D03*
X716146Y1374881D03*
Y1381801D03*
Y1369889D03*
X711190D03*
Y1374881D03*
Y1381801D03*
X703906D03*
Y1369889D03*
Y1374881D03*
X716146Y1399079D03*
X711190D03*
X716146Y1393993D03*
X711190D03*
X703906Y1394087D03*
Y1399079D03*
X716146Y1386793D03*
X711190D03*
X703906D03*
X716146Y1405999D03*
X711190D03*
X716146Y1410991D03*
X711190D03*
X703906Y1405999D03*
Y1410991D03*
X712000Y1644980D03*
X721741Y-27628D03*
X721756Y-25113D03*
X724781Y-26433D03*
X735192Y94017D03*
X731192D03*
X733233Y151540D03*
X736750Y188727D03*
X730707Y226141D03*
X733507D03*
X733404Y285690D03*
X720090Y293796D03*
X722590D03*
X728104Y288190D03*
X730604Y285690D03*
X728104D03*
X730604Y288190D03*
X733404D03*
X731511Y390500D03*
X734606Y379562D03*
X722097Y410394D03*
Y403307D03*
X723491Y458406D03*
Y451319D03*
Y465492D03*
X723315Y462264D03*
X723491Y472579D03*
Y479665D03*
Y486752D03*
Y493839D03*
Y523799D03*
Y516713D03*
Y509626D03*
Y530886D03*
Y537973D03*
Y566752D03*
Y559665D03*
Y573839D03*
Y588012D03*
Y580926D03*
Y595099D03*
Y602185D03*
Y609272D03*
Y616358D03*
X734819Y646429D03*
X725318Y890354D03*
X720373Y940310D03*
X724547Y958287D03*
X723430Y1350683D03*
X728386Y1345691D03*
X723430D03*
X728386Y1350683D03*
Y1357603D03*
Y1362595D03*
X723430Y1357603D03*
Y1362595D03*
X728386Y1381801D03*
Y1374881D03*
Y1369889D03*
X723430D03*
Y1381801D03*
Y1374881D03*
X728386Y1386793D03*
X723430D03*
X728386Y1398985D03*
Y1393993D03*
X723430Y1398985D03*
Y1393993D03*
X728386Y1410897D03*
Y1405905D03*
X723430Y1410897D03*
Y1405905D03*
X732000Y1644980D03*
X748269Y84140D03*
Y76140D03*
Y80140D03*
X743201Y94017D03*
X739192D03*
X750714Y117557D03*
X745722D03*
X740312Y115401D03*
Y110445D03*
X735320D03*
Y115401D03*
X745722Y131731D03*
Y122513D03*
X740312Y129574D03*
Y124618D03*
X735320D03*
Y129574D03*
X750714Y131731D03*
Y122513D03*
Y136687D03*
X745722D03*
X748813Y146461D03*
X747715Y152367D03*
X749415Y180572D03*
Y185165D03*
X743383Y184619D03*
X736883Y191941D03*
X745363Y206760D03*
X738577Y256535D03*
X746577D03*
X747607Y279208D03*
X751711Y281307D03*
X741630Y290755D03*
X737630D03*
X745630D03*
X741161Y381500D03*
X741602Y465492D03*
X741568Y460250D03*
X739333Y470136D03*
X741602Y472579D03*
X741072Y478958D03*
X741602Y486752D03*
Y493839D03*
Y509626D03*
Y516713D03*
X738062Y537973D03*
X740542Y525483D03*
X740463Y532756D03*
X741602Y559665D03*
Y566752D03*
X741452Y579978D03*
X741602Y573839D03*
X741666Y608117D03*
X741000Y771100D03*
X738707Y987952D03*
X745673Y1007009D03*
X747910Y1345691D03*
Y1350683D03*
X735670D03*
X740626D03*
X735670Y1345691D03*
X740626D03*
X747910Y1357603D03*
Y1362595D03*
X735670Y1357603D03*
Y1362595D03*
X740626Y1357603D03*
Y1362595D03*
X747910Y1374881D03*
Y1381801D03*
Y1369889D03*
X740626Y1381801D03*
Y1369889D03*
Y1374881D03*
X735670Y1381801D03*
Y1369889D03*
Y1374881D03*
X747910Y1386793D03*
X735670Y1393993D03*
X740626D03*
Y1398985D03*
X735670D03*
X740626Y1386793D03*
X735670D03*
Y1405905D03*
Y1410897D03*
X740626Y1405905D03*
Y1410897D03*
X742655Y1445733D03*
X747590Y1627871D03*
X765847Y55513D03*
X762065Y117040D03*
X754098Y180527D03*
X757821Y192421D03*
X754053Y185121D03*
X756201Y288345D03*
Y290845D03*
X753701Y288345D03*
Y290845D03*
Y293645D03*
X756201D03*
X763898Y342319D03*
X766344Y393924D03*
Y389912D03*
Y385912D03*
X758038Y381143D03*
X766344Y409924D03*
Y405924D03*
Y401924D03*
X752341Y407148D03*
X756800Y403824D03*
X758381Y395391D03*
X759543Y445787D03*
X755593Y445908D03*
X765106Y1350683D03*
Y1345597D03*
X760150D03*
Y1350683D03*
X752866Y1345691D03*
Y1350683D03*
X765106Y1362595D03*
Y1357603D03*
X760150D03*
Y1362595D03*
X752866Y1357603D03*
Y1362595D03*
X765106Y1374881D03*
Y1381801D03*
Y1369889D03*
X760150Y1374881D03*
Y1381801D03*
Y1369889D03*
X752866Y1374881D03*
Y1381801D03*
Y1369889D03*
X765106Y1386793D03*
X760150D03*
X752866D03*
X766433Y1583713D03*
X752150Y1627871D03*
X762776Y1629415D03*
X752000Y1644980D03*
X771011Y60922D03*
X767929Y96890D03*
X771824Y110784D03*
X769175Y113394D03*
X779418Y133298D03*
X771960Y130898D03*
X773565Y134579D03*
X769351Y172665D03*
Y180665D03*
X769383Y200864D03*
Y212864D03*
Y221864D03*
Y216864D03*
X771140Y252371D03*
X780968Y303839D03*
X772990Y336324D03*
X777569Y353506D03*
X772390Y1350683D03*
X777346D03*
Y1345691D03*
X772390D03*
Y1357603D03*
Y1362595D03*
X777346Y1357603D03*
Y1362595D03*
X777114Y1442270D03*
X778045Y1622545D03*
X782289Y1620109D03*
X773822Y1627418D03*
X772000Y1644980D03*
X784410Y109172D03*
X787410D03*
X794961Y116497D03*
X797461D03*
X790161D03*
X786417Y106495D03*
X797461Y109410D03*
Y123583D03*
X794961Y123584D03*
X790161D03*
X794961Y130670D03*
X797461D03*
X790161D03*
X794961Y137757D03*
X790161D03*
X788057Y141228D03*
X786151Y146012D03*
X793221Y140296D03*
X790945Y150847D03*
X792913Y247292D03*
X785622Y253198D03*
X788522Y290304D03*
X799937Y347340D03*
X791686Y1025440D03*
X794716Y1186071D03*
X792183Y1334030D03*
Y1331230D03*
X789383Y1334030D03*
Y1331230D03*
X794506Y1411307D03*
X793723Y1468071D03*
X793564Y1642682D03*
X810623Y77784D03*
Y82984D03*
Y80384D03*
Y75184D03*
X813177Y92849D03*
X810623Y85584D03*
X802161Y116496D03*
Y109410D03*
Y102323D03*
Y130670D03*
Y123583D03*
Y137756D03*
X816364Y486870D03*
X813864D03*
X813566Y744187D03*
X812661Y810032D03*
X812980Y824166D03*
X816016Y838036D03*
X813182Y852800D03*
X814731Y889365D03*
X812811Y908162D03*
X809682Y1133284D03*
X806787Y1148000D03*
X815034Y1159455D03*
X809623Y1160168D03*
X809393Y1187252D03*
X807487Y1193019D03*
X815487D03*
X811487D03*
X817446Y1210089D03*
X800627Y1392748D03*
X800703Y1426779D03*
X811457Y1639797D03*
X820137Y103037D03*
X820271Y116496D03*
Y109410D03*
Y130670D03*
Y123583D03*
X816637Y137756D03*
X824952Y293796D03*
X822452D03*
X830466Y285690D03*
Y288190D03*
X825792Y305225D03*
X823529Y467189D03*
X830318Y674164D03*
X829784Y713939D03*
X832284Y731216D03*
X830484Y746701D03*
X819993Y754109D03*
X817500Y760000D03*
X820547Y780314D03*
X826925Y769000D03*
X820500Y777500D03*
X826925Y787000D03*
X820500Y792000D03*
X818500Y814000D03*
X820432Y800529D03*
X826925Y805000D03*
Y823000D03*
X826165Y863000D03*
X819134Y863607D03*
X829000Y852000D03*
X825686Y869496D03*
X826797Y883756D03*
X825508Y913869D03*
X822462Y915095D03*
X818347Y939610D03*
X828193Y949324D03*
X832432Y977982D03*
X832711Y993268D03*
X828385Y1120599D03*
X817006Y1133027D03*
X822006Y1130208D03*
X825744Y1146937D03*
X823220Y1162817D03*
X823487Y1193019D03*
X819487D03*
X826612Y1219254D03*
X819522Y1212164D03*
X821816Y1214458D03*
X832084Y1461072D03*
X831457Y1639797D03*
X844781Y-65613D03*
X841756Y-64293D03*
X838503Y-64307D03*
X841741Y-66808D03*
X838488Y-66822D03*
X841554Y94017D03*
X837554D03*
X845563D03*
X833554D03*
X837682Y110445D03*
Y115401D03*
X848084Y117557D03*
X842674Y115401D03*
Y110445D03*
Y129574D03*
Y124618D03*
X837682D03*
Y129574D03*
X848084Y131731D03*
Y122513D03*
Y136687D03*
X839112Y188727D03*
X839245Y191941D03*
X845745Y184619D03*
X847725Y206760D03*
X833069Y226141D03*
X835869D03*
X848939Y256535D03*
X840939D03*
X832966Y288190D03*
Y285690D03*
X835766Y288190D03*
Y285690D03*
X843992Y290755D03*
X839992D03*
X847992D03*
X835236Y533174D03*
X845729Y661263D03*
X836503Y667845D03*
X845784Y713939D03*
X848284Y731181D03*
X846484Y746701D03*
X841500Y758161D03*
Y776161D03*
Y794161D03*
Y812161D03*
X838685Y832987D03*
X845654Y895437D03*
X833870Y881860D03*
X839381Y915839D03*
X839122Y939655D03*
X843734Y1008778D03*
X848520Y1016855D03*
X850631Y84140D03*
Y80140D03*
Y76140D03*
X864006Y117261D03*
X853076Y117557D03*
Y131731D03*
Y122513D03*
Y136687D03*
X851777Y180572D03*
X856460Y180527D03*
X860183Y192421D03*
X851777Y185165D03*
X856415Y185121D03*
X849969Y279208D03*
X854073Y281307D03*
X864920Y343168D03*
X854086Y385000D03*
X858586D03*
X850733Y461382D03*
X850832Y473382D03*
X850738Y477382D03*
X850909Y482382D03*
X853900Y627700D03*
X858202Y646330D03*
X851111Y656635D03*
X856145Y677887D03*
X855646Y685230D03*
X858186Y713170D03*
X867227Y722060D03*
X849500Y761000D03*
X864575Y770500D03*
X849500Y779000D03*
X864575Y788500D03*
X849500Y797000D03*
Y815000D03*
X864575Y806500D03*
X865004Y831273D03*
X864464Y828503D03*
X864575Y824500D03*
X851782Y823720D03*
X851161Y855205D03*
X856628Y915242D03*
X864253D03*
X849600Y915266D03*
X855867Y935540D03*
X849088Y951081D03*
X852247Y1009529D03*
X849996Y1091073D03*
X850023Y1095179D03*
X863342Y1120636D03*
X855542D03*
X858142D03*
X860842D03*
X863442Y1130336D03*
X858242D03*
X855642D03*
X860942D03*
Y1139336D03*
X863442D03*
X861119Y1148080D03*
X863619D03*
X851457Y1639797D03*
X873373Y60922D03*
X868209Y55513D03*
X870395Y96738D03*
X865402Y91951D03*
X871713Y172665D03*
Y180665D03*
X871745Y200864D03*
Y212864D03*
Y216864D03*
Y221864D03*
X876246Y302754D03*
X869313Y688486D03*
X872069Y700894D03*
X876286Y686970D03*
X880501Y710611D03*
X873021Y715729D03*
X877616Y749484D03*
X873318Y744597D03*
X873250Y798750D03*
X872700Y816615D03*
X872628Y915242D03*
X880628D03*
X876481Y941126D03*
X868908Y933640D03*
X867199Y949372D03*
X869390Y978003D03*
X878004Y1224406D03*
X883142Y1259935D03*
X875700Y1299700D03*
X871457Y1639797D03*
X886011Y154100D03*
X895780Y237517D03*
Y232634D03*
X886261Y252090D03*
X885741Y261150D03*
X894844Y418983D03*
X889219Y426952D03*
X887770Y415290D03*
X890270D03*
X897344Y418983D03*
X894519Y426952D03*
X889596Y437264D03*
X896388Y437614D03*
X887096Y437264D03*
X892019Y426952D03*
X897019D03*
X882891Y536122D03*
X896449Y550863D03*
X893949Y550363D03*
X882949Y557363D03*
X887949Y608863D03*
X894449Y606363D03*
X884903Y694119D03*
X886836Y729778D03*
X889083Y780371D03*
X888545Y785528D03*
X888514Y797602D03*
X891916Y808965D03*
X882609Y994245D03*
X897056Y1091391D03*
X891055Y1095407D03*
X897056Y1095984D03*
X884906Y1102760D03*
X884890Y1098724D03*
X893190Y1208069D03*
X894887Y1227209D03*
X891003Y1292765D03*
X890738Y1311132D03*
X891457Y1639797D03*
X898813Y146461D03*
X897715Y152367D03*
X898851Y231496D03*
Y238583D03*
Y245669D03*
X910977Y238583D03*
X898851Y259843D03*
X898576Y253056D03*
X910977Y252756D03*
Y257480D03*
X898851Y274016D03*
X910977Y266929D03*
X898851D03*
X912786Y306697D03*
X901848Y307782D03*
Y312738D03*
X909417Y323302D03*
X912085Y332335D03*
X898888Y437614D03*
X906996Y530707D03*
X902459Y530755D03*
X911630Y543998D03*
X910578Y550186D03*
X909362Y555614D03*
X898156Y554812D03*
X909024Y586768D03*
X908730Y619120D03*
X913686D03*
X899898Y619040D03*
X904854D03*
X910036Y702285D03*
X910753Y715864D03*
X912864Y864189D03*
Y870488D03*
Y867338D03*
X899693Y895207D03*
X904833Y915340D03*
X912628Y928101D03*
X911355Y944909D03*
X906710Y962433D03*
X906909Y951494D03*
X909296Y1020224D03*
X909300Y1014639D03*
X901739Y1091346D03*
X897815Y1078042D03*
X901366Y1078069D03*
X901694Y1095940D03*
X911071Y1123803D03*
X905771D03*
X903171D03*
X908371D03*
X910971Y1114103D03*
X908271D03*
X903071D03*
X905671D03*
X911699Y1129488D03*
X909041Y1126328D03*
X911641D03*
X903908Y1132870D03*
X904063Y1135946D03*
X901940Y1236799D03*
Y1229899D03*
Y1232399D03*
Y1246199D03*
Y1243699D03*
Y1239299D03*
X904703Y1297398D03*
X911457Y1639797D03*
X919175Y113394D03*
X921824Y110784D03*
X921418Y133298D03*
X929418D03*
X923565Y134579D03*
X920142Y308501D03*
X926801Y323302D03*
X923902Y332411D03*
X924600Y533706D03*
X920961Y550075D03*
X915949Y563363D03*
X915712Y613792D03*
X915194Y666671D03*
X928043Y677795D03*
X917286Y679625D03*
X924932Y701051D03*
X920628Y928101D03*
X928628D03*
X916628D03*
X924628D03*
X924487Y951244D03*
X918648Y964717D03*
X915490Y969886D03*
X916749Y1080659D03*
Y1088659D03*
X917110Y1101902D03*
X927598Y1120636D03*
X924898D03*
X914661Y1132612D03*
X914299Y1129488D03*
X914241Y1126328D03*
X924919Y1130336D03*
X927619D03*
X924919Y1139336D03*
X927419D03*
X925097Y1147708D03*
X927597D03*
X927146Y1328597D03*
Y1323641D03*
X929094Y1542353D03*
Y1545353D03*
X926041Y1554503D03*
Y1551503D03*
Y1548503D03*
Y1557503D03*
Y1560503D03*
X944961Y116497D03*
X934410Y109172D03*
X936417Y106495D03*
X937410Y109172D03*
X940161Y116497D03*
Y123584D03*
X944961D03*
X940161Y130670D03*
X944961D03*
X940161Y137757D03*
X944961D03*
X936151Y146012D03*
X938057Y141228D03*
X940945Y150847D03*
X932388Y330517D03*
X932622Y336817D03*
X944694Y352192D03*
X931627Y561578D03*
Y565578D03*
X943825Y581222D03*
Y591215D03*
X935281Y677795D03*
X945626Y789761D03*
X932000Y831000D03*
X942634Y886520D03*
X933700Y887508D03*
X944839Y902400D03*
X938188Y900853D03*
X944628Y928101D03*
X932628D03*
X936628D03*
X940497D03*
X941981Y1224406D03*
X947119Y1259935D03*
X933254Y1308273D03*
X940848Y1310181D03*
X930441Y1455039D03*
Y1458039D03*
Y1464039D03*
Y1461039D03*
Y1467039D03*
X938670Y1510528D03*
X941270D03*
Y1505328D03*
X938670D03*
X940170Y1507928D03*
X943870Y1510528D03*
Y1505328D03*
X945370Y1507928D03*
X942770D03*
X935094Y1542353D03*
X932094D03*
X935094Y1545353D03*
X932094D03*
X938094Y1542353D03*
Y1545353D03*
X941094Y1542353D03*
X944094D03*
X941094Y1545353D03*
X944094D03*
X931457Y1639797D03*
X960623Y82984D03*
Y77784D03*
Y80384D03*
Y75184D03*
Y85584D03*
X947461Y116497D03*
X952161Y116496D03*
Y109410D03*
Y102323D03*
X947461Y109410D03*
Y130670D03*
X952161D03*
Y123583D03*
X947461D03*
X952161Y137756D03*
X949443Y208206D03*
X949579Y330517D03*
X949813Y336817D03*
X956863Y451466D03*
X953816Y555194D03*
X951016D03*
X953816Y571194D03*
X951016D03*
X953816Y563194D03*
X951016D03*
X946625Y581222D03*
X949425D03*
Y591215D03*
X946625D03*
X948427Y611091D03*
X957551Y698251D03*
X954023Y725336D03*
X951195Y727165D03*
X952681Y735256D03*
X956323Y748412D03*
X957474Y764426D03*
X955086Y779798D03*
X956051Y793937D03*
X947735Y824921D03*
X948935Y835800D03*
X954700Y842700D03*
X947735Y854935D03*
X953091Y857440D03*
X953217Y861440D03*
X955967Y860376D03*
X946700Y849200D03*
X950251Y874268D03*
X950291Y870240D03*
Y866240D03*
X953145Y874240D03*
X952738Y886624D03*
X953587Y902814D03*
X961479Y927643D03*
X957671Y991564D03*
X946642Y991361D03*
X961033Y1091391D03*
X948883Y1102760D03*
X948867Y1098724D03*
X955032Y1095407D03*
X961033Y1095984D03*
X957167Y1208069D03*
X958864Y1227209D03*
X949970Y1321749D03*
X952070Y1367717D03*
X949070D03*
X956238Y1455139D03*
Y1458139D03*
Y1461139D03*
Y1464139D03*
X952676Y1461039D03*
Y1464039D03*
Y1458039D03*
Y1455039D03*
X956238Y1467139D03*
Y1469902D03*
X952676Y1467039D03*
X946470Y1510528D03*
Y1505328D03*
X947094Y1545353D03*
Y1542353D03*
X951457Y1639797D03*
X963177Y92849D03*
X970137Y103037D03*
X970271Y116496D03*
Y109410D03*
Y130670D03*
Y123583D03*
X966347Y137756D03*
X974952Y293796D03*
X972452D03*
X972147Y323681D03*
X975932Y437508D03*
X971932D03*
X962769Y458466D03*
X973695Y448874D03*
X969109Y449352D03*
X978723Y504699D03*
X976223D03*
X973723D03*
X978425Y516979D03*
X973425D03*
X975925D03*
X967302Y627948D03*
X969491Y629362D03*
X963187Y667620D03*
X973138Y667621D03*
X978059Y747438D03*
X976764Y786563D03*
X964070Y807686D03*
Y813006D03*
X977218Y802178D03*
X964036Y818961D03*
X968319Y826191D03*
X976635Y835018D03*
X976800Y838011D03*
X974282D03*
X976902Y847135D03*
X971808Y851242D03*
X975925Y854783D03*
X978201Y897500D03*
X969806Y993033D03*
X965716Y1091346D03*
X965671Y1095940D03*
X967148Y1123803D03*
X969748D03*
X969648Y1114103D03*
X967048D03*
X972348Y1123803D03*
X975048D03*
X972248Y1114103D03*
X974948D03*
X970485Y1132870D03*
X967885D03*
X968874Y1145169D03*
X966374D03*
X965917Y1236799D03*
Y1229899D03*
Y1232399D03*
Y1246199D03*
Y1243699D03*
Y1239299D03*
X978727Y1284908D03*
X971467Y1509515D03*
X974067D03*
X972567Y1512115D03*
X969967D03*
X976667Y1509515D03*
X977767Y1506915D03*
X975167D03*
X969967D03*
X972567D03*
X975167Y1512115D03*
X977767D03*
X971140Y1514693D03*
X968540D03*
X973740D03*
X976340D03*
X971457Y1639797D03*
X983554Y94017D03*
X987554D03*
X991554D03*
X987682Y115401D03*
X992674D03*
Y110445D03*
X987682D03*
X992674Y124618D03*
X987682D03*
Y129574D03*
X992674D03*
X985595Y151540D03*
X989245Y191941D03*
X989112Y188727D03*
X983069Y226141D03*
X985869D03*
X990939Y256535D03*
X985766Y288190D03*
X982966D03*
X985766Y285690D03*
X982966D03*
X980466Y288190D03*
Y285690D03*
X993992Y290755D03*
X989992D03*
X979932Y437508D03*
X982792Y447269D03*
X982670Y450201D03*
X989936Y519531D03*
X987436D03*
X982436D03*
X984936D03*
X983843Y633205D03*
Y636005D03*
Y638805D03*
X984307Y748432D03*
X985030Y781204D03*
X988329Y781445D03*
X991990Y773974D03*
X984963Y785387D03*
X979313Y814316D03*
X987903Y818645D03*
X993061Y833135D03*
X979203Y837159D03*
X988820Y858903D03*
X980529Y879097D03*
X988231Y878203D03*
X984892Y868720D03*
X987790Y896596D03*
X995133Y888503D03*
X982787Y899757D03*
X988461Y1013841D03*
X980726Y1080659D03*
Y1088659D03*
X981087Y1101902D03*
X988389Y1302558D03*
X980501Y1369685D03*
X983501D03*
X979538Y1464039D03*
Y1461039D03*
Y1458039D03*
Y1455039D03*
Y1467039D03*
Y1469802D03*
X979267Y1509515D03*
X984467D03*
X981867D03*
X985567Y1512115D03*
Y1506915D03*
X980367D03*
X982967D03*
Y1512115D03*
X980367D03*
X989667Y1509515D03*
X992267D03*
X987067D03*
X988167Y1512115D03*
X990767D03*
Y1506915D03*
X988167D03*
X984140Y1514693D03*
X981540D03*
X978940D03*
X986740D03*
X989340D03*
X991457Y1639797D03*
X1005256Y-25113D03*
X1002003Y-25027D03*
X1005241Y-27628D03*
X1001988Y-27542D03*
X1008281Y-26433D03*
X1000631Y84140D03*
Y76140D03*
Y80140D03*
X995563Y94017D03*
X1003076Y117557D03*
X998084D03*
X1003076Y122513D03*
Y131731D03*
X998084Y122513D03*
Y131731D03*
X1001175Y146461D03*
X1003076Y136687D03*
X998084D03*
X1000077Y152367D03*
X1001777Y180572D03*
X1006460Y180527D03*
X1010183Y192421D03*
X1001777Y185165D03*
X1006415Y185121D03*
X995745Y184619D03*
X997725Y206760D03*
X998939Y256535D03*
X999826Y278734D03*
X1004061Y280808D03*
X997992Y290755D03*
X1004544Y318050D03*
X1004933Y314535D03*
X997921Y333654D03*
X995913Y633450D03*
Y636250D03*
Y639050D03*
X1008342Y761735D03*
X1003539Y762632D03*
X1002834Y777394D03*
X1006053Y787745D03*
X999825Y819488D03*
X1002887Y834342D03*
X1000369D03*
X1005607Y874859D03*
Y877859D03*
X1002930Y906785D03*
X1010009Y998100D03*
X1005301Y1006560D03*
X999700Y1018400D03*
X1008312Y1363533D03*
X1008452Y1376752D03*
X1008483Y1372734D03*
X1006211Y1397662D03*
X1009338Y1391597D03*
Y1388597D03*
X1002538Y1463939D03*
Y1460939D03*
Y1457939D03*
Y1454939D03*
Y1466939D03*
Y1469702D03*
X1008549Y1509815D03*
X1007049Y1507215D03*
X1011149Y1509815D03*
X1009649Y1507215D03*
Y1512415D03*
X1007049D03*
X1008222Y1514993D03*
X1005622D03*
X1010822D03*
X1023373Y60922D03*
X1018209Y55513D03*
X1020254Y97068D03*
X1014006Y117261D03*
X1021537Y113394D03*
X1024186Y110784D03*
X1024289Y130898D03*
X1025927Y134579D03*
X1021713Y180665D03*
Y172665D03*
X1026915Y203393D03*
X1021745Y212864D03*
Y200864D03*
Y221864D03*
Y216864D03*
X1023502Y252371D03*
X1013354Y323362D03*
X1013327Y327453D03*
X1013318Y333190D03*
X1022845Y340944D03*
X1013313Y339909D03*
X1015195Y428305D03*
X1015804Y760454D03*
X1026090Y770943D03*
X1019375Y783056D03*
X1018044Y793592D03*
X1015800Y807535D03*
X1014587Y802788D03*
X1025859Y802275D03*
X1020703Y833659D03*
X1021221Y848712D03*
X1025219Y842155D03*
X1025239Y845070D03*
X1022009Y997860D03*
X1018009D03*
X1026009D03*
X1014009D03*
X1014767Y1035088D03*
X1022594Y1035114D03*
X1017297Y1102091D03*
X1026606Y1102591D03*
X1023106Y1102091D03*
X1017297Y1114691D03*
X1023106D03*
X1026606D03*
X1023106Y1127291D03*
X1026606D03*
X1017297Y1139891D03*
X1023106D03*
X1026606D03*
X1017297Y1127291D03*
X1026606Y1152491D03*
X1017297D03*
X1023106D03*
X1017297Y1165091D03*
X1023106D03*
X1026606D03*
X1017297Y1177691D03*
X1023106D03*
X1026606D03*
X1022420Y1203204D03*
X1026968Y1223749D03*
X1025434Y1320606D03*
X1011829Y1347471D03*
Y1342515D03*
X1015286Y1344924D03*
X1021623Y1373216D03*
X1012338Y1388597D03*
Y1391597D03*
X1015338D03*
Y1388597D03*
X1021338D03*
Y1391597D03*
X1018338D03*
Y1388597D03*
X1027338D03*
Y1391597D03*
X1024338D03*
Y1388597D03*
X1025138Y1463839D03*
Y1460839D03*
Y1457839D03*
Y1454839D03*
Y1466839D03*
Y1469602D03*
X1013749Y1509815D03*
X1016349D03*
X1021549D03*
X1018949D03*
X1024149D03*
X1022649Y1507215D03*
X1025249D03*
X1017449D03*
X1020049D03*
X1014849D03*
X1012249D03*
X1026749Y1509815D03*
X1012249Y1512415D03*
X1014849D03*
X1025249D03*
X1022649D03*
X1020049D03*
X1017449D03*
X1013422Y1514993D03*
X1023822D03*
X1021222D03*
X1018622D03*
X1016022D03*
X1026422D03*
X1011457Y1639797D03*
X1036772Y109172D03*
X1039772D03*
X1038779Y106495D03*
X1042523Y116497D03*
X1031780Y133298D03*
X1042523Y130670D03*
Y123584D03*
X1038513Y146012D03*
X1040419Y141228D03*
X1042523Y137757D03*
X1043307Y150847D03*
X1037984Y253198D03*
X1031354Y325901D03*
X1031382Y340947D03*
X1031310Y337888D03*
X1031377Y333671D03*
X1031362Y329268D03*
X1038796Y763272D03*
X1042880Y794924D03*
X1028155Y879413D03*
X1030300Y881400D03*
X1043252Y902501D03*
X1030009Y997860D03*
X1034009D03*
X1038252Y1009354D03*
X1034752D03*
X1028943D03*
X1042009Y997860D03*
X1038009D03*
X1034752Y1021954D03*
X1038252D03*
X1043553Y1035384D03*
X1040600Y1210600D03*
X1035384Y1215195D03*
X1034513Y1333665D03*
X1042586Y1345824D03*
X1030338Y1391597D03*
Y1388597D03*
X1029349Y1509815D03*
X1027849Y1507215D03*
Y1512415D03*
X1031457Y1639797D03*
X1049823Y109410D03*
X1054523Y116496D03*
Y109410D03*
Y102323D03*
X1049823Y116497D03*
X1047323D03*
X1049823Y130670D03*
X1047323D03*
Y123584D03*
X1049823Y123583D03*
X1054523Y130670D03*
Y123583D03*
Y137756D03*
X1047323Y137757D03*
X1045275Y247292D03*
X1050777Y450750D03*
X1054876Y536382D03*
X1059843Y597580D03*
X1059782Y594668D03*
X1062098Y615600D03*
X1044112Y778835D03*
X1045744Y800835D03*
X1048328Y808166D03*
X1057961Y931919D03*
X1046009Y997860D03*
X1054009D03*
X1050009D03*
X1058009D03*
X1059689Y1012354D03*
Y1024954D03*
X1048043Y1105091D03*
Y1117691D03*
Y1130291D03*
Y1155491D03*
Y1142891D03*
Y1168091D03*
Y1180691D03*
X1051249Y1290288D03*
X1052221Y1336984D03*
X1058891Y1345691D03*
Y1350683D03*
X1053935Y1345691D03*
Y1350683D03*
X1058891Y1362595D03*
X1053935D03*
X1058891Y1357603D03*
X1053935D03*
X1058891Y1381801D03*
Y1374881D03*
Y1369889D03*
X1053935Y1381801D03*
Y1374881D03*
Y1369889D03*
X1058891Y1386793D03*
X1053935D03*
X1051457Y1639797D03*
X1071988Y-66722D03*
X1075241Y-66808D03*
X1072003Y-64207D03*
X1075256Y-64293D03*
X1062985Y82984D03*
Y75184D03*
Y77784D03*
Y80384D03*
X1065539Y92849D03*
X1062985Y85584D03*
X1072499Y103037D03*
X1072633Y116496D03*
Y109410D03*
Y130670D03*
Y123583D03*
X1069224Y137756D03*
X1074814Y293796D03*
X1061325Y339509D03*
X1060679Y360151D03*
Y364276D03*
X1071548Y555234D03*
X1071263Y562003D03*
X1062066Y599588D03*
X1061328Y589556D03*
X1061267Y592354D03*
X1062069Y596095D03*
X1062066Y607588D03*
X1066559Y634946D03*
X1066009Y997860D03*
X1062009D03*
X1074009D03*
X1070778Y1012252D03*
X1066933Y1040567D03*
X1071641Y1058029D03*
X1060172Y1050481D03*
X1071348Y1050503D03*
X1066175Y1350683D03*
Y1345691D03*
X1071131Y1350683D03*
Y1345691D03*
X1066175Y1357603D03*
Y1362595D03*
X1071131Y1357603D03*
Y1362595D03*
X1066175Y1381801D03*
Y1369795D03*
Y1374881D03*
X1071131Y1381801D03*
Y1369795D03*
Y1374881D03*
X1066175Y1393993D03*
Y1399079D03*
Y1386793D03*
X1071131Y1399079D03*
Y1393993D03*
Y1386793D03*
X1066175Y1405999D03*
Y1410991D03*
X1071131Y1405999D03*
Y1410991D03*
X1071457Y1639797D03*
X1078281Y-65613D03*
X1089916Y94017D03*
X1085916D03*
X1090044Y110445D03*
Y115401D03*
Y124618D03*
Y129574D03*
X1087957Y151540D03*
X1091607Y191941D03*
X1091474Y188727D03*
X1085431Y226141D03*
X1088231D03*
X1088128Y285690D03*
Y288190D03*
X1085328D03*
X1082828Y285690D03*
X1085328D03*
X1082828Y288190D03*
X1077314Y293796D03*
X1092354Y290755D03*
X1077602Y314060D03*
X1091542Y389154D03*
Y410413D03*
Y396240D03*
Y403327D03*
Y417500D03*
Y424587D03*
Y431673D03*
Y438760D03*
Y445847D03*
Y467539D03*
Y474626D03*
Y488799D03*
Y481713D03*
Y495886D03*
Y511673D03*
Y518760D03*
Y525847D03*
Y532933D03*
Y540020D03*
Y547106D03*
X1090823Y602197D03*
X1091287Y595108D03*
X1079809Y1034386D03*
X1090655Y1350683D03*
Y1345691D03*
X1083371D03*
Y1350683D03*
X1078415Y1345691D03*
Y1350683D03*
X1090655Y1357603D03*
Y1362595D03*
X1083371Y1357603D03*
Y1362595D03*
X1078415D03*
Y1357603D03*
X1090655Y1381801D03*
Y1374881D03*
Y1369889D03*
X1083371D03*
Y1374881D03*
Y1381801D03*
X1078415Y1369889D03*
Y1374881D03*
Y1381801D03*
X1090655Y1394087D03*
Y1399079D03*
Y1386793D03*
X1083371D03*
Y1399079D03*
Y1394087D03*
X1078415Y1386793D03*
Y1394087D03*
Y1399079D03*
X1090655Y1405999D03*
Y1410991D03*
X1083371Y1405999D03*
Y1410991D03*
X1078415Y1405999D03*
Y1410991D03*
X1092000Y1644980D03*
X1102993Y84140D03*
Y76140D03*
Y80140D03*
X1097925Y94017D03*
X1093916D03*
X1100446Y117557D03*
X1095036Y115401D03*
Y110445D03*
X1105438Y117557D03*
X1095036Y129574D03*
Y124618D03*
X1105438Y131731D03*
Y122513D03*
X1100446Y131731D03*
Y122513D03*
X1103537Y146461D03*
X1100446Y136687D03*
X1105438D03*
X1102439Y152367D03*
X1104139Y180572D03*
X1108822Y180527D03*
X1104139Y185165D03*
X1108777Y185121D03*
X1098107Y184619D03*
X1100087Y206760D03*
X1101301Y256535D03*
X1093301D03*
X1102331Y279208D03*
X1106435Y281307D03*
X1096354Y290755D03*
X1100354D03*
X1100703Y340560D03*
X1101999Y353495D03*
X1093994Y374003D03*
X1106161Y389154D03*
X1104691Y396240D03*
X1108776Y422864D03*
X1108846Y429832D03*
X1108451Y436447D03*
X1108395Y472772D03*
X1105002Y516841D03*
X1108253Y510565D03*
X1099949Y550123D03*
X1099827Y552872D03*
X1101581Y572334D03*
X1099272Y562443D03*
X1101040Y560675D03*
X1099813Y574102D03*
X1104448Y653161D03*
X1108045Y677843D03*
X1107851Y1345691D03*
X1102895Y1350683D03*
Y1345691D03*
X1107851Y1350683D03*
X1095611D03*
Y1345691D03*
X1107851Y1357603D03*
X1102895Y1362595D03*
Y1357603D03*
X1107851Y1362595D03*
X1095611Y1357603D03*
Y1362595D03*
X1107851Y1369889D03*
Y1374881D03*
Y1381801D03*
X1102895Y1374881D03*
Y1369889D03*
Y1381801D03*
X1095611D03*
Y1374881D03*
Y1369889D03*
X1107851Y1386793D03*
Y1394087D03*
Y1399079D03*
X1102895Y1386793D03*
Y1394087D03*
Y1399079D03*
X1095611D03*
Y1394087D03*
Y1386793D03*
X1107851Y1405999D03*
Y1410991D03*
X1102895Y1405999D03*
Y1410991D03*
X1095611Y1405999D03*
Y1410991D03*
X1099900Y1535700D03*
X1107620Y1606752D03*
X1123052Y57511D03*
X1122613Y97042D03*
X1116368Y117261D03*
X1123899Y113394D03*
X1124075Y180665D03*
Y172665D03*
X1112545Y192421D03*
X1124107Y200864D03*
Y212864D03*
Y216864D03*
Y221864D03*
X1123500Y329000D03*
Y339000D03*
Y334000D03*
X1124753Y389153D03*
X1122253Y396240D03*
X1124753D03*
X1122253Y403327D03*
X1124753Y403326D03*
X1122253Y410413D03*
X1124753D03*
X1109468Y414823D03*
X1122253Y424586D03*
X1124753D03*
X1122253Y417500D03*
X1124753Y417499D03*
X1122253Y438760D03*
X1124753D03*
Y431673D03*
X1122253D03*
X1110486Y447953D03*
X1122253Y445847D03*
X1109653Y467539D03*
X1124753D03*
X1122253Y474626D03*
X1124753D03*
X1122253Y488799D03*
X1124753D03*
X1109129Y487711D03*
X1109242Y479104D03*
X1124753Y481712D03*
X1122253D03*
Y495886D03*
X1109653D03*
X1124753Y518760D03*
X1122253D03*
X1124753Y511673D03*
Y532933D03*
X1122253D03*
Y540020D03*
Y525846D03*
X1124753D03*
X1118863Y662981D03*
X1112839Y668885D03*
X1113244Y691851D03*
X1118855Y705043D03*
X1115135Y1345691D03*
Y1350683D03*
X1120091Y1345691D03*
Y1350683D03*
X1115135Y1357603D03*
Y1362595D03*
X1120091Y1357603D03*
Y1362595D03*
X1115135Y1374881D03*
Y1381801D03*
Y1369889D03*
X1120091D03*
Y1374881D03*
Y1381801D03*
X1115135Y1394087D03*
Y1399079D03*
Y1386793D03*
X1120091Y1399079D03*
Y1394087D03*
Y1386793D03*
X1115135Y1405999D03*
Y1410991D03*
X1120091Y1405999D03*
Y1410991D03*
X1112000Y1644980D03*
X1125735Y60922D03*
X1139134Y109172D03*
X1141141Y106495D03*
X1126548Y110784D03*
X1134142Y133298D03*
X1126142D03*
X1140875Y146012D03*
X1128289Y134579D03*
X1129277Y203393D03*
X1140346Y253198D03*
X1125864Y252371D03*
X1129553Y389153D03*
Y396240D03*
Y403326D03*
Y410413D03*
Y424586D03*
Y417499D03*
Y431673D03*
Y438760D03*
X1126931Y453564D03*
X1130355Y453483D03*
X1129553Y467539D03*
X1125178Y459792D03*
X1129553Y474626D03*
Y488799D03*
Y481712D03*
Y518760D03*
Y511673D03*
Y532933D03*
Y525846D03*
X1138098Y543925D03*
X1138673Y555000D03*
X1126633Y560500D03*
X1139615Y1350683D03*
Y1345691D03*
X1132331D03*
Y1350683D03*
X1127375D03*
Y1345691D03*
X1139615Y1357603D03*
Y1362595D03*
X1132331D03*
Y1357603D03*
X1127375D03*
Y1362595D03*
X1139615Y1374881D03*
Y1369889D03*
Y1381801D03*
X1132331Y1369889D03*
Y1381801D03*
Y1374881D03*
X1127375Y1369889D03*
Y1381801D03*
Y1374881D03*
X1139615Y1394087D03*
Y1399079D03*
Y1386793D03*
X1132331D03*
Y1394087D03*
Y1399079D03*
X1127375Y1386793D03*
Y1394087D03*
Y1399079D03*
X1139615Y1405999D03*
Y1410991D03*
X1132331Y1405999D03*
Y1410991D03*
X1127375Y1405999D03*
Y1410991D03*
X1129637Y1465913D03*
Y1461182D03*
Y1456451D03*
X1138298Y1465513D03*
Y1460782D03*
X1129637Y1476536D03*
Y1481267D03*
X1138298Y1476136D03*
Y1470244D03*
Y1480867D03*
X1129637Y1471805D03*
Y1496621D03*
X1138298Y1491490D03*
Y1485598D03*
Y1496221D03*
X1129637Y1491890D03*
Y1487159D03*
X1138298Y1500952D03*
Y1511576D03*
X1129637Y1507245D03*
Y1502514D03*
Y1511976D03*
X1138298Y1506845D03*
Y1516307D03*
X1129637Y1563544D03*
Y1558813D03*
X1138298Y1563144D03*
Y1572606D03*
X1129637Y1568275D03*
Y1578898D03*
Y1574167D03*
X1138298Y1567875D03*
Y1578498D03*
X1129637Y1583629D03*
Y1594253D03*
Y1589522D03*
X1138298Y1583229D03*
Y1593853D03*
Y1587960D03*
Y1598584D03*
Y1603315D03*
X1129637Y1609607D03*
Y1598984D03*
Y1604876D03*
X1138298Y1609207D03*
X1129637Y1614338D03*
X1138298Y1613938D03*
Y1618669D03*
X1132000Y1644980D03*
X1142134Y109172D03*
X1156885Y116496D03*
Y102323D03*
Y109410D03*
X1152185D03*
Y116497D03*
X1149685D03*
X1144885D03*
X1152185Y130670D03*
X1149685D03*
Y123584D03*
X1152185Y123583D03*
X1144885Y130670D03*
Y123584D03*
X1156885Y130670D03*
Y123583D03*
X1142781Y141228D03*
X1156885Y137756D03*
X1149685Y137757D03*
X1144885D03*
X1145669Y150847D03*
X1147637Y247292D03*
X1145761Y324148D03*
X1157251Y636842D03*
X1156023Y678462D03*
X1149345Y771517D03*
X1145910Y794217D03*
X1151277Y790996D03*
X1149627Y813323D03*
X1146985Y812642D03*
X1152510Y844642D03*
X1156811Y1350683D03*
Y1345691D03*
X1151855D03*
Y1350683D03*
X1144571D03*
Y1345691D03*
X1156811Y1357603D03*
Y1362595D03*
X1151855D03*
Y1357603D03*
X1144571D03*
Y1362595D03*
X1156811Y1374881D03*
Y1369889D03*
Y1381801D03*
X1151855Y1374881D03*
Y1369889D03*
Y1381801D03*
X1144571Y1369889D03*
Y1381801D03*
Y1374881D03*
X1156811Y1386793D03*
Y1399079D03*
Y1394087D03*
X1151855Y1386793D03*
Y1399079D03*
Y1394087D03*
X1144571D03*
Y1399079D03*
Y1386793D03*
X1156811Y1405999D03*
Y1410991D03*
X1151855Y1405999D03*
Y1410991D03*
X1144571Y1405999D03*
Y1410991D03*
X1146960Y1465913D03*
Y1461182D03*
X1155621Y1465513D03*
Y1460782D03*
X1146960Y1456451D03*
X1155621Y1480867D03*
X1146960Y1471805D03*
Y1476536D03*
Y1481267D03*
X1155621Y1476136D03*
Y1470244D03*
Y1491490D03*
Y1485598D03*
Y1496221D03*
X1146960Y1487159D03*
Y1491890D03*
Y1496621D03*
Y1507245D03*
Y1502514D03*
X1155621Y1506845D03*
Y1500952D03*
Y1511576D03*
X1146960Y1511976D03*
X1155621Y1516307D03*
X1146960Y1563544D03*
X1155621Y1563144D03*
X1146960Y1558813D03*
X1155621Y1572606D03*
X1146960Y1568275D03*
X1155621Y1567875D03*
X1146960Y1574167D03*
Y1578898D03*
X1155621Y1578498D03*
X1146960Y1594253D03*
X1155621Y1593853D03*
Y1587960D03*
X1146960Y1583629D03*
X1155621Y1583229D03*
X1146960Y1589522D03*
Y1609607D03*
Y1604876D03*
Y1598984D03*
X1155621Y1609207D03*
Y1598584D03*
Y1603315D03*
X1146960Y1614338D03*
X1155621Y1613938D03*
Y1618669D03*
X1152000Y1644980D03*
X1165347Y82984D03*
Y75184D03*
Y77784D03*
Y80384D03*
X1167756Y92734D03*
X1165347Y85584D03*
X1171586Y137756D03*
X1168902Y431029D03*
X1167931Y435029D03*
X1169173Y427017D03*
X1168851Y449873D03*
X1171255Y456287D03*
X1173278Y472579D03*
X1168478D03*
X1173278Y479666D03*
X1168478D03*
Y486752D03*
X1173278D03*
X1168478Y493839D03*
X1173278D03*
X1168478Y523800D03*
Y516713D03*
X1173278D03*
Y523800D03*
Y537973D03*
X1168478D03*
X1173278Y530886D03*
X1168478D03*
X1173278Y566752D03*
X1168478D03*
Y580926D03*
X1173278D03*
Y588013D03*
X1168478D03*
X1173278Y573839D03*
X1168478D03*
Y602186D03*
X1173278D03*
Y595099D03*
X1168478D03*
X1173278Y609272D03*
X1168478D03*
Y616359D03*
X1173278D03*
X1163157Y638125D03*
X1160756Y665140D03*
X1157985Y791142D03*
X1161291Y791662D03*
X1173697Y791911D03*
X1160516Y800900D03*
X1169051Y1345597D03*
Y1350683D03*
X1164095D03*
Y1345597D03*
X1169051Y1357603D03*
Y1362595D03*
X1164095Y1357603D03*
Y1362595D03*
X1169051Y1381801D03*
Y1374881D03*
Y1369889D03*
X1164095D03*
Y1381801D03*
Y1374881D03*
X1169051Y1393993D03*
Y1399079D03*
Y1386793D03*
X1164095Y1393993D03*
Y1399079D03*
Y1386793D03*
X1169051Y1410991D03*
Y1405999D03*
X1164095D03*
Y1410991D03*
X1164283Y1465913D03*
Y1456451D03*
Y1461182D03*
X1172944Y1465513D03*
Y1460782D03*
Y1470244D03*
Y1480867D03*
X1164283Y1471805D03*
Y1476536D03*
Y1481267D03*
X1172944Y1476136D03*
X1164283Y1487159D03*
Y1491890D03*
Y1496621D03*
X1172944Y1491490D03*
Y1485598D03*
Y1496221D03*
X1164283Y1507245D03*
Y1502514D03*
X1172944Y1506845D03*
Y1500952D03*
Y1511576D03*
X1164283Y1511976D03*
X1172944Y1516307D03*
X1164283Y1558813D03*
Y1563544D03*
X1172944Y1563144D03*
Y1567875D03*
X1164283Y1574167D03*
Y1578898D03*
X1172944Y1578498D03*
Y1572606D03*
X1164283Y1568275D03*
Y1583629D03*
X1172944Y1583229D03*
X1164283Y1589522D03*
Y1594253D03*
X1172944Y1593853D03*
Y1587960D03*
Y1598584D03*
Y1603315D03*
X1164283Y1609607D03*
Y1604876D03*
Y1598984D03*
X1172944Y1609207D03*
X1164283Y1614338D03*
X1172944Y1613938D03*
Y1618669D03*
X1172000Y1644980D03*
X1188278Y94017D03*
X1174861Y103037D03*
X1174995Y116496D03*
Y109410D03*
Y130670D03*
Y123583D03*
X1187793Y226141D03*
X1190593D03*
X1179676Y293796D03*
X1187690Y288190D03*
X1185190Y285690D03*
X1187690D03*
X1185190Y288190D03*
X1177176Y293796D03*
X1182911Y336516D03*
X1177036Y334148D03*
X1188598Y390500D03*
X1179184Y410394D03*
Y403307D03*
X1180578Y458406D03*
Y451319D03*
X1180402Y462264D03*
X1175778Y465492D03*
X1180578D03*
X1175778Y472579D03*
X1180578D03*
X1175778Y479666D03*
X1180578Y479665D03*
Y486752D03*
X1175778D03*
X1180578Y493839D03*
X1175778Y509626D03*
X1180578Y523799D03*
Y516713D03*
Y509626D03*
X1175778Y516713D03*
Y523800D03*
X1180578Y537973D03*
X1175778Y530886D03*
X1180578D03*
Y559665D03*
Y566752D03*
X1175778D03*
Y559665D03*
Y580926D03*
X1180578D03*
Y588012D03*
X1175778D03*
X1180578Y573839D03*
X1175778D03*
Y602185D03*
X1180578D03*
X1175778Y595099D03*
X1180578D03*
X1175778Y609272D03*
X1180578Y616358D03*
Y609272D03*
X1177745Y771744D03*
X1177566Y778539D03*
X1190062Y844378D03*
X1187703Y849734D03*
X1186742Y855466D03*
X1183431Y868340D03*
X1177775Y894053D03*
X1178480Y915220D03*
X1178000Y936500D03*
X1187200Y963400D03*
X1181291Y1350683D03*
Y1345691D03*
X1176335D03*
Y1350683D03*
X1181291Y1362595D03*
Y1357603D03*
X1176335Y1362595D03*
Y1357603D03*
X1181291Y1369889D03*
Y1381801D03*
Y1374881D03*
X1176335Y1369889D03*
Y1381801D03*
Y1374881D03*
X1181291Y1386793D03*
Y1399079D03*
Y1394087D03*
X1176335Y1386793D03*
Y1399079D03*
Y1394087D03*
X1181291Y1405999D03*
Y1410991D03*
X1176335Y1405999D03*
Y1410991D03*
X1181605Y1465913D03*
Y1456451D03*
Y1461182D03*
Y1471805D03*
Y1476536D03*
Y1481267D03*
Y1487159D03*
Y1491890D03*
Y1496621D03*
Y1507245D03*
Y1502514D03*
Y1511976D03*
Y1558813D03*
Y1563544D03*
Y1568275D03*
Y1574167D03*
Y1578898D03*
Y1583629D03*
Y1589522D03*
Y1594253D03*
Y1598984D03*
Y1609607D03*
Y1604876D03*
Y1614338D03*
X1205355Y84140D03*
Y76140D03*
Y80140D03*
X1196278Y94017D03*
X1200287D03*
X1192278D03*
X1202808Y117557D03*
X1197398Y110445D03*
Y115401D03*
X1192406Y110445D03*
Y115401D03*
X1197398Y129574D03*
Y124618D03*
X1192406D03*
Y129574D03*
X1202808Y122513D03*
Y131731D03*
X1205899Y146461D03*
X1202808Y136687D03*
X1204801Y152367D03*
X1190319Y151540D03*
X1200469Y184619D03*
X1193969Y191941D03*
X1193836Y188727D03*
X1202449Y206760D03*
X1203663Y256535D03*
X1195663D03*
X1204693Y279208D03*
X1194716Y290755D03*
X1202716D03*
X1190490Y285690D03*
Y288190D03*
X1198716Y290755D03*
X1198248Y381500D03*
X1198689Y465492D03*
X1198655Y460250D03*
X1196420Y470136D03*
X1198689Y472579D03*
Y486752D03*
Y479665D03*
Y493839D03*
Y509626D03*
Y516713D03*
X1195149Y537973D03*
X1197629Y525483D03*
X1197550Y532756D03*
X1198689Y559665D03*
Y566752D03*
X1198539Y579978D03*
X1198689Y573839D03*
X1198753Y608117D03*
X1198997Y790610D03*
X1198845Y998504D03*
X1204919Y1021860D03*
X1202268Y1013551D03*
X1190267Y1465513D03*
Y1460782D03*
X1198928Y1465914D03*
Y1456452D03*
Y1461183D03*
Y1481268D03*
X1190267Y1476136D03*
Y1470244D03*
Y1480867D03*
X1198928Y1476537D03*
Y1471806D03*
X1190267Y1485598D03*
Y1496221D03*
X1198928Y1491891D03*
Y1487160D03*
Y1496622D03*
X1190267Y1491490D03*
Y1506845D03*
Y1500952D03*
Y1511576D03*
X1198928Y1507246D03*
Y1502515D03*
Y1511977D03*
X1190267Y1516307D03*
X1198928Y1558813D03*
X1190267Y1563144D03*
X1198928Y1563544D03*
X1190267Y1567875D03*
X1198928Y1568275D03*
X1190267Y1578498D03*
Y1572606D03*
X1198928Y1578898D03*
Y1574167D03*
X1190267Y1583229D03*
X1198928Y1583629D03*
X1190267Y1593853D03*
Y1587960D03*
X1198928Y1594253D03*
Y1589522D03*
X1190267Y1609207D03*
Y1598584D03*
Y1603315D03*
X1198928Y1609607D03*
Y1598984D03*
Y1604876D03*
X1190267Y1613938D03*
Y1618669D03*
X1198928Y1614338D03*
X1192000Y1644980D03*
X1218730Y117261D03*
X1207800Y117557D03*
Y122513D03*
Y131731D03*
Y136687D03*
X1206501Y180572D03*
X1211184Y180527D03*
X1214907Y192421D03*
X1206501Y185165D03*
X1211139Y185121D03*
X1208797Y281307D03*
X1220985Y342319D03*
X1212680Y445908D03*
X1216630Y445787D03*
X1212000Y1644980D03*
X1222933Y55513D03*
X1228097Y60922D03*
X1225041Y97080D03*
X1228910Y110784D03*
X1226261Y113394D03*
X1229195Y130898D03*
X1236504Y133298D03*
X1230651Y134579D03*
X1226437Y180665D03*
Y172665D03*
X1226469Y200864D03*
Y212864D03*
Y216864D03*
Y221864D03*
X1228226Y252371D03*
X1238055Y303839D03*
X1230077Y336324D03*
X1234656Y353506D03*
X1223431Y393924D03*
Y389912D03*
Y385912D03*
Y409924D03*
Y405924D03*
Y401924D03*
X1229548Y1350683D03*
Y1345691D03*
X1234504D03*
Y1350683D03*
X1229548Y1362595D03*
Y1357603D03*
X1234504D03*
Y1362595D03*
X1229548Y1369889D03*
Y1374881D03*
Y1381801D03*
X1234504Y1369889D03*
Y1374881D03*
Y1381801D03*
X1229548Y1386793D03*
X1234504D03*
X1232000Y1644980D03*
X1243503Y106495D03*
X1244496Y109172D03*
X1241496D03*
X1247247Y116497D03*
X1254547Y109410D03*
Y116497D03*
X1252047D03*
X1247247Y123584D03*
Y130670D03*
X1252047Y123584D03*
X1254547Y123583D03*
Y130670D03*
X1252047D03*
X1243237Y146012D03*
X1245143Y141228D03*
X1247247Y137757D03*
X1252047D03*
X1250307Y140296D03*
X1248031Y150847D03*
X1249999Y247292D03*
X1242708Y253198D03*
X1248064Y567813D03*
Y572769D03*
Y581987D03*
Y586943D03*
Y601116D03*
Y596160D03*
Y615289D03*
Y610333D03*
X1246800Y1001600D03*
X1249200Y1014000D03*
X1248721Y1025864D03*
X1251802Y1186071D03*
X1254028Y1350683D03*
Y1345691D03*
X1241788D03*
Y1350683D03*
X1246744Y1345691D03*
Y1350683D03*
X1254028Y1357603D03*
Y1362595D03*
X1241788D03*
Y1357603D03*
X1246744Y1362595D03*
Y1357603D03*
X1254028Y1381801D03*
Y1374881D03*
Y1369889D03*
X1241788Y1374881D03*
Y1369795D03*
Y1381801D03*
X1246744Y1374881D03*
Y1369795D03*
Y1381801D03*
X1254028Y1386793D03*
Y1399079D03*
Y1394087D03*
X1241788Y1399079D03*
Y1393993D03*
Y1386793D03*
X1246744Y1393993D03*
Y1399079D03*
Y1386793D03*
X1254028Y1410991D03*
Y1405999D03*
X1241788Y1410991D03*
Y1405999D03*
X1246744Y1410991D03*
Y1405999D03*
X1245900Y1528000D03*
X1267709Y82984D03*
Y75184D03*
Y77784D03*
Y80384D03*
X1270263Y92849D03*
X1267709Y85584D03*
X1259247Y116496D03*
Y102323D03*
Y109410D03*
Y130670D03*
Y123583D03*
Y137756D03*
X1258925Y324075D03*
X1270951Y491870D03*
X1270515Y908277D03*
X1269876Y1132319D03*
X1263873Y1148000D03*
X1266709Y1160168D03*
X1258736Y1188223D03*
X1268573Y1193019D03*
X1264573D03*
X1266268Y1345691D03*
Y1350683D03*
X1258984D03*
Y1345691D03*
X1266268Y1362595D03*
Y1357603D03*
X1258984Y1362595D03*
Y1357603D03*
X1266268Y1369889D03*
Y1374881D03*
Y1381801D03*
X1258984D03*
Y1369889D03*
Y1374881D03*
X1266268Y1399079D03*
Y1394087D03*
Y1386793D03*
X1258984Y1394087D03*
Y1386793D03*
Y1399079D03*
X1266268Y1410991D03*
Y1405999D03*
X1258984D03*
Y1410991D03*
X1263242Y1523458D03*
X1262985Y1519459D03*
X1260260Y1546500D03*
X1277223Y103037D03*
X1277357Y116496D03*
Y109410D03*
Y130670D03*
Y123583D03*
X1273555Y137756D03*
X1279538Y293796D03*
X1282038D03*
X1283494Y339495D03*
X1287437Y370010D03*
X1280616Y472189D03*
X1273451Y491870D03*
X1279539Y772576D03*
Y776576D03*
X1274417Y861964D03*
X1282317Y880193D03*
X1285493Y892175D03*
X1277039Y916484D03*
X1284021Y940008D03*
X1273865Y1132497D03*
X1282830Y1146937D03*
X1272120Y1159455D03*
X1280306Y1162817D03*
X1276573Y1193019D03*
X1280573D03*
X1272573D03*
X1277108Y1211664D03*
X1279402Y1213958D03*
X1275032Y1209589D03*
X1284198Y1218754D03*
X1283464Y1345691D03*
Y1350683D03*
X1278508Y1345691D03*
Y1350683D03*
X1271224Y1345691D03*
Y1350683D03*
X1283464Y1362595D03*
Y1357603D03*
X1278508D03*
Y1362595D03*
X1271224D03*
Y1357603D03*
X1283464Y1381801D03*
Y1369889D03*
Y1374881D03*
X1278508Y1381801D03*
Y1369889D03*
Y1374881D03*
X1271224Y1369889D03*
Y1374881D03*
Y1381801D03*
X1283464Y1386793D03*
Y1399079D03*
Y1394087D03*
X1278508Y1386793D03*
Y1399079D03*
Y1394087D03*
X1271224D03*
Y1399079D03*
Y1386793D03*
X1283464Y1410991D03*
Y1405999D03*
X1278508Y1410991D03*
Y1405999D03*
X1271224Y1410991D03*
Y1405999D03*
X1291756Y-25143D03*
X1288503Y-25157D03*
X1291741Y-27658D03*
X1288488Y-27672D03*
X1294781Y-26463D03*
X1302649Y94017D03*
X1298640D03*
X1290640D03*
X1294640D03*
X1299760Y110445D03*
Y115401D03*
X1294768Y110445D03*
Y115401D03*
Y129574D03*
X1299760D03*
Y124618D03*
X1294768D03*
X1296331Y191941D03*
X1302831Y184619D03*
X1296198Y188727D03*
X1292955Y226141D03*
X1290155D03*
X1298025Y256535D03*
X1290052Y288190D03*
X1292852D03*
Y285690D03*
X1305078Y290755D03*
X1297078D03*
X1301078D03*
X1287552Y288190D03*
X1290052Y285690D03*
X1287552D03*
X1294425Y321425D03*
X1299959Y351454D03*
X1296783Y511956D03*
X1303520Y748403D03*
X1300516Y832047D03*
X1300504Y835985D03*
X1300204Y859088D03*
X1300097Y851193D03*
X1300091Y854824D03*
X1291955Y901295D03*
X1289547Y928047D03*
X1298090Y940852D03*
X1295453Y940953D03*
X1302988Y1345691D03*
Y1350683D03*
X1290748D03*
Y1345691D03*
X1295704Y1350683D03*
Y1345691D03*
X1302988Y1362595D03*
Y1357603D03*
X1290748Y1362595D03*
Y1357603D03*
X1295704Y1362595D03*
Y1357603D03*
X1302988Y1374881D03*
Y1381801D03*
Y1369889D03*
X1290748D03*
Y1381801D03*
Y1374881D03*
X1295704Y1381801D03*
Y1374881D03*
Y1369889D03*
X1302988Y1386793D03*
Y1399079D03*
Y1394087D03*
X1290748Y1399079D03*
Y1394087D03*
Y1386793D03*
X1295704Y1394087D03*
Y1399079D03*
Y1386793D03*
X1302988Y1410991D03*
Y1405999D03*
X1290748Y1410991D03*
Y1405999D03*
X1295704Y1410991D03*
Y1405999D03*
X1302866Y1461182D03*
Y1456451D03*
Y1465913D03*
Y1476536D03*
Y1471805D03*
Y1481267D03*
Y1491890D03*
Y1487159D03*
Y1496621D03*
Y1507245D03*
Y1502514D03*
Y1511976D03*
Y1558813D03*
Y1563544D03*
Y1578898D03*
Y1574167D03*
Y1568275D03*
Y1594253D03*
Y1589522D03*
Y1583629D03*
Y1609607D03*
Y1598984D03*
Y1604876D03*
Y1614338D03*
X1292000Y1644980D03*
X1307717Y84140D03*
Y76140D03*
Y80140D03*
X1310162Y117557D03*
X1305170D03*
X1310162Y122513D03*
Y131731D03*
X1305170Y122513D03*
Y131731D03*
X1310162Y136687D03*
X1305170D03*
X1313546Y180527D03*
X1308863Y180572D03*
Y185165D03*
X1317269Y192421D03*
X1313501Y185121D03*
X1304811Y206760D03*
X1306025Y256535D03*
X1307055Y279208D03*
X1311159Y281307D03*
X1314569Y318013D03*
X1312069D03*
X1317584Y313058D03*
X1316017Y349889D03*
X1308410Y370899D03*
X1313691Y402642D03*
X1316191D03*
X1309117Y398949D03*
X1306617Y401949D03*
X1308066Y413611D03*
X1310866D03*
X1313366D03*
X1315866D03*
X1315806Y423944D03*
X1313306D03*
X1310806D03*
X1308006D03*
X1307919Y478382D03*
X1307825Y482382D03*
X1305134Y812065D03*
X1313756Y829871D03*
X1308857Y836076D03*
X1316906Y842470D03*
Y867665D03*
Y883413D03*
Y892862D03*
X1316893Y925603D03*
X1318375Y943951D03*
X1303907Y960093D03*
X1307580Y990314D03*
X1304664Y1023462D03*
X1309937Y1037038D03*
X1319326Y1040723D03*
X1317437Y1152684D03*
X1307167Y1245696D03*
X1308276Y1276446D03*
X1315228Y1345691D03*
Y1350683D03*
X1307944D03*
Y1345691D03*
X1315228Y1362595D03*
Y1357603D03*
X1307944D03*
Y1362595D03*
X1315228Y1381801D03*
Y1369889D03*
Y1374881D03*
X1307944D03*
Y1381801D03*
Y1369889D03*
X1315228Y1399079D03*
Y1394087D03*
Y1386793D03*
X1307944D03*
Y1399079D03*
Y1394087D03*
X1315228Y1410991D03*
Y1405999D03*
X1307944Y1410991D03*
Y1405999D03*
X1311527Y1465513D03*
Y1460782D03*
Y1480867D03*
Y1476136D03*
Y1470244D03*
Y1491490D03*
Y1485598D03*
Y1496221D03*
Y1506845D03*
Y1500952D03*
Y1511576D03*
Y1516307D03*
Y1563144D03*
Y1567875D03*
Y1578498D03*
Y1572606D03*
Y1583229D03*
Y1593853D03*
Y1587960D03*
Y1609207D03*
Y1598584D03*
Y1603315D03*
Y1613938D03*
Y1618669D03*
X1312000Y1644980D03*
X1331756Y-64193D03*
X1328503Y-64207D03*
X1331741Y-66708D03*
X1328488Y-66722D03*
X1334781Y-65513D03*
X1321092Y117261D03*
X1328799Y172665D03*
Y180665D03*
X1328831Y212864D03*
Y200864D03*
Y221864D03*
Y216864D03*
X1330414Y310058D03*
X1325458D03*
X1322540Y313058D03*
X1333332D03*
X1331085Y334347D03*
X1323816D03*
Y341615D03*
X1331085Y348868D03*
X1323816D03*
X1332927Y468607D03*
X1326912Y493153D03*
X1325630Y513238D03*
X1335000Y590500D03*
Y586500D03*
Y633000D03*
Y637000D03*
Y677500D03*
Y681500D03*
Y724500D03*
Y728500D03*
X1324217Y780595D03*
X1332654Y836170D03*
X1323205Y861367D03*
X1335803Y851918D03*
Y877114D03*
X1326355Y886562D03*
X1328457Y959986D03*
X1321104Y964398D03*
X1323554Y967623D03*
X1331890Y1051919D03*
X1331359Y1098898D03*
X1334161Y1098518D03*
X1333905Y1123101D03*
X1331405D03*
X1323405D03*
X1320279Y1131935D03*
Y1134435D03*
Y1136935D03*
Y1139435D03*
X1334305Y1129301D03*
X1331805D03*
X1329305D03*
X1326805D03*
X1324305D03*
X1321805D03*
X1334305Y1125801D03*
X1331805D03*
X1323405D03*
X1320279Y1141935D03*
Y1146935D03*
Y1144435D03*
X1326269Y1152713D03*
Y1155213D03*
X1320493Y1204405D03*
X1334793Y1204617D03*
X1320493Y1206905D03*
Y1211905D03*
Y1209405D03*
X1334793Y1207117D03*
Y1209617D03*
Y1212117D03*
X1330070Y1297498D03*
X1335470D03*
X1332424Y1345691D03*
Y1350683D03*
X1327468D03*
Y1345691D03*
X1320184Y1350683D03*
Y1345691D03*
X1332424Y1362595D03*
Y1357603D03*
X1327468D03*
Y1362595D03*
X1320184D03*
Y1357603D03*
X1332424Y1381801D03*
Y1369889D03*
Y1374881D03*
X1327468Y1381801D03*
Y1369889D03*
Y1374881D03*
X1320184Y1381801D03*
Y1374881D03*
Y1369889D03*
X1332424Y1386793D03*
Y1394087D03*
Y1399079D03*
X1327468Y1386793D03*
Y1394087D03*
Y1399079D03*
X1320184D03*
Y1394087D03*
Y1386793D03*
X1332424Y1410991D03*
Y1405999D03*
X1327468Y1410991D03*
Y1405999D03*
X1320184Y1410991D03*
Y1405999D03*
X1328850Y1465513D03*
Y1460782D03*
X1320189Y1465913D03*
Y1456451D03*
Y1461182D03*
X1328850Y1476136D03*
Y1470244D03*
X1320189Y1481267D03*
X1328850Y1480867D03*
X1320189Y1471805D03*
Y1476536D03*
X1328850Y1491490D03*
Y1485598D03*
X1320189Y1496621D03*
X1328850Y1496221D03*
X1320189Y1487159D03*
Y1491890D03*
Y1502514D03*
X1328850Y1506845D03*
Y1500952D03*
Y1511576D03*
X1320189Y1511976D03*
Y1507245D03*
X1328850Y1516307D03*
X1320189Y1558813D03*
Y1563544D03*
X1328850Y1563144D03*
Y1567875D03*
X1320189Y1574167D03*
Y1578898D03*
X1328850Y1578498D03*
Y1572606D03*
X1320189Y1568275D03*
X1328850Y1583229D03*
X1320189Y1589522D03*
Y1594253D03*
X1328850Y1593853D03*
Y1587960D03*
X1320189Y1583629D03*
X1328850Y1603315D03*
X1320189Y1609607D03*
Y1604876D03*
Y1598984D03*
X1328850Y1609207D03*
Y1598584D03*
Y1613938D03*
Y1618669D03*
X1320189Y1614338D03*
X1332000Y1644980D03*
X1340320Y151540D03*
X1338288Y313058D03*
X1338378Y334347D03*
X1338275Y341603D03*
X1338378Y348830D03*
X1345451Y699032D03*
X1347136Y780040D03*
X1351550Y839320D03*
Y855068D03*
X1345252D03*
X1342103D03*
Y861367D03*
X1338953D03*
Y858218D03*
X1338952Y855067D03*
X1338953Y870814D03*
X1342103Y867665D03*
X1338953D03*
X1351550Y873964D03*
X1345252D03*
X1342103D03*
X1338952Y873965D03*
X1345252Y892862D03*
X1341820Y947407D03*
X1347380Y1057998D03*
Y1055498D03*
X1344880D03*
Y1057998D03*
X1347380Y1060498D03*
Y1062998D03*
X1344880D03*
Y1060498D03*
X1339349Y1098767D03*
X1339305Y1129301D03*
X1336805D03*
X1339305Y1125801D03*
X1336805D03*
X1343505Y1136935D03*
Y1134435D03*
Y1139435D03*
Y1131935D03*
X1349907D03*
Y1134435D03*
Y1136935D03*
Y1139435D03*
X1352407Y1131935D03*
Y1134435D03*
Y1136935D03*
Y1139435D03*
X1343505Y1146935D03*
Y1144435D03*
Y1141935D03*
X1349907D03*
Y1146935D03*
Y1144435D03*
X1352407Y1141935D03*
Y1146935D03*
Y1144435D03*
X1336669Y1152713D03*
Y1155213D03*
X1351405Y1154902D03*
Y1152402D03*
X1347423Y1204405D03*
X1337108Y1200821D03*
Y1198321D03*
X1347423Y1209405D03*
Y1211905D03*
Y1206905D03*
X1340870Y1297498D03*
X1346270D03*
X1351670D03*
X1351948Y1350683D03*
Y1345691D03*
X1339708Y1345597D03*
Y1350683D03*
X1344664Y1345597D03*
Y1350683D03*
X1351948Y1357603D03*
Y1362595D03*
X1339708D03*
Y1357603D03*
X1344664Y1362595D03*
Y1357603D03*
X1351948Y1374881D03*
Y1381801D03*
Y1369889D03*
X1339708Y1374881D03*
Y1381801D03*
Y1369889D03*
X1344664D03*
Y1374881D03*
Y1381801D03*
X1351948Y1386793D03*
Y1394087D03*
Y1399079D03*
X1339708D03*
Y1393993D03*
Y1386793D03*
X1344664Y1393993D03*
Y1399079D03*
Y1386793D03*
X1351948Y1410991D03*
Y1405999D03*
X1339708Y1410991D03*
Y1405999D03*
X1344664Y1410991D03*
Y1405999D03*
X1337512Y1461182D03*
X1346173Y1465513D03*
Y1460782D03*
X1337512Y1465913D03*
Y1456451D03*
X1346173Y1476136D03*
Y1470244D03*
X1337512Y1481267D03*
X1346173Y1480867D03*
X1337512Y1471805D03*
Y1476536D03*
X1346173Y1485598D03*
Y1491490D03*
X1337512Y1487159D03*
Y1491890D03*
Y1496621D03*
X1346173Y1496221D03*
X1337512Y1507245D03*
Y1502514D03*
X1346173Y1506845D03*
Y1500952D03*
Y1511576D03*
X1337512Y1511976D03*
X1346173Y1516307D03*
X1337512Y1558813D03*
Y1563544D03*
X1346173Y1563144D03*
X1337512Y1574167D03*
Y1578898D03*
X1346173Y1578498D03*
Y1572606D03*
X1337512Y1568275D03*
X1346173Y1567875D03*
X1337512Y1583629D03*
X1346173Y1583229D03*
X1337512Y1589522D03*
Y1594253D03*
X1346173Y1593853D03*
Y1587960D03*
X1337512Y1609607D03*
Y1604876D03*
Y1598984D03*
X1346173Y1609207D03*
Y1598584D03*
Y1603315D03*
X1337512Y1614338D03*
X1346173Y1613938D03*
Y1618669D03*
X1352000Y1644980D03*
X1355900Y146461D03*
X1354802Y152367D03*
X1355255Y561032D03*
Y607532D03*
Y652032D03*
X1364148Y836170D03*
X1354699Y855068D03*
X1357849Y861367D03*
X1354699D03*
X1357849Y858218D03*
X1357850Y855067D03*
X1360999Y851918D03*
Y877114D03*
X1357850Y873965D03*
X1354699Y873964D03*
X1357849Y870814D03*
Y867665D03*
X1354699D03*
X1363173Y994483D03*
X1363905Y1000855D03*
X1366493Y1000828D03*
X1367884Y1018825D03*
X1357265Y1022766D03*
X1364237Y1043140D03*
X1357265Y1030266D03*
X1363941Y1047047D03*
X1366289Y1098518D03*
X1361037Y1098428D03*
X1355533Y1123101D03*
X1363533D03*
X1366033D03*
X1366433Y1129301D03*
X1355533Y1125801D03*
X1363933D03*
X1366433D03*
X1353933Y1129301D03*
X1356433D03*
X1358933D03*
X1361433D03*
X1363933D03*
X1357397Y1155213D03*
Y1152713D03*
X1366797D03*
Y1155213D03*
X1361723Y1204617D03*
X1364038Y1198321D03*
Y1200821D03*
X1361723Y1212117D03*
Y1209617D03*
Y1207117D03*
X1357070Y1297498D03*
X1356904Y1345691D03*
Y1350683D03*
Y1357603D03*
Y1362595D03*
Y1381801D03*
Y1369889D03*
Y1374881D03*
Y1386793D03*
Y1394087D03*
Y1399079D03*
Y1410991D03*
Y1405999D03*
X1354834Y1465913D03*
Y1456451D03*
Y1461182D03*
X1363496Y1465513D03*
Y1460782D03*
X1354834Y1481267D03*
X1363496Y1476136D03*
Y1470244D03*
Y1480867D03*
X1354834Y1471805D03*
Y1476536D03*
Y1487159D03*
Y1496621D03*
X1363496Y1485598D03*
Y1491490D03*
Y1496221D03*
X1354834Y1491890D03*
Y1502514D03*
Y1511976D03*
X1363496Y1511576D03*
Y1506845D03*
Y1500952D03*
X1354834Y1507245D03*
X1363496Y1516307D03*
X1354834Y1558813D03*
Y1563544D03*
X1363496Y1563144D03*
Y1572606D03*
X1354834Y1568275D03*
Y1574167D03*
Y1578898D03*
X1363496Y1567875D03*
Y1578498D03*
X1354834Y1583629D03*
Y1589522D03*
Y1594253D03*
X1363496Y1583229D03*
Y1593853D03*
Y1587960D03*
X1354834Y1609607D03*
Y1604876D03*
Y1598984D03*
X1363496Y1609207D03*
Y1598584D03*
Y1603315D03*
X1354834Y1614338D03*
X1363496Y1613938D03*
Y1618669D03*
X1376262Y113394D03*
X1378911Y110784D03*
X1378505Y133298D03*
X1380652Y134579D03*
X1378227Y252371D03*
X1383556Y558338D03*
X1383184Y587653D03*
X1383425Y593575D03*
X1383556Y604838D03*
X1381118Y634033D03*
X1383425Y640075D03*
X1381244Y673623D03*
X1383425Y684140D03*
X1381932Y722547D03*
X1383425Y731575D03*
X1383046Y829871D03*
X1379896Y842470D03*
Y858218D03*
X1370447Y867665D03*
Y886562D03*
X1371379Y986717D03*
X1370384Y1004680D03*
X1376601Y1030218D03*
X1374451Y1090568D03*
Y1093068D03*
X1371477Y1098767D03*
X1375633Y1136935D03*
Y1134435D03*
Y1139435D03*
Y1131935D03*
X1383366D03*
Y1134435D03*
Y1136935D03*
Y1139435D03*
X1368933Y1125801D03*
X1371433D03*
X1368933Y1129301D03*
X1371433D03*
X1383024Y1152684D03*
X1376861D03*
X1375633Y1146935D03*
Y1144435D03*
Y1141935D03*
X1383366D03*
Y1146935D03*
Y1144435D03*
X1377390Y1244055D03*
Y1250760D03*
Y1254164D03*
X1372300Y1422900D03*
X1372157Y1461183D03*
Y1456452D03*
Y1465914D03*
Y1471806D03*
Y1476537D03*
Y1481268D03*
Y1487160D03*
Y1491891D03*
Y1496622D03*
Y1502515D03*
Y1507246D03*
Y1511977D03*
Y1558813D03*
Y1563544D03*
Y1568275D03*
Y1574167D03*
Y1578898D03*
Y1583629D03*
Y1589522D03*
Y1594253D03*
Y1604876D03*
Y1598984D03*
Y1609607D03*
Y1614338D03*
X1372000Y1644980D03*
X1391497Y109172D03*
X1394497D03*
X1393504Y106495D03*
X1397248Y116497D03*
X1386505Y133298D03*
X1397248Y130670D03*
Y123584D03*
X1393238Y146012D03*
X1395144Y141228D03*
X1397248Y137757D03*
X1398032Y150847D03*
X1400000Y247292D03*
X1392709Y253198D03*
X1391086Y577192D03*
X1400912Y581222D03*
Y591215D03*
X1391587Y627817D03*
X1388414Y675000D03*
X1388241Y722000D03*
X1396916Y862829D03*
X1395561Y876204D03*
X1396163Y868597D03*
X1398247Y926261D03*
X1390322Y1057998D03*
Y1055498D03*
X1392822D03*
Y1057998D03*
X1390322Y1060498D03*
Y1062998D03*
X1392822D03*
Y1060498D03*
X1399748Y1098518D03*
X1394496Y1098428D03*
X1388992Y1123101D03*
X1396992D03*
X1399492D03*
X1385866Y1131935D03*
Y1134435D03*
Y1136935D03*
Y1139435D03*
X1388992Y1125801D03*
X1397392D03*
X1399892D03*
X1387392Y1129301D03*
X1389892D03*
X1392392D03*
X1394892D03*
X1397392D03*
X1399892D03*
X1391856Y1155213D03*
Y1152713D03*
X1385866Y1141935D03*
Y1146935D03*
Y1144435D03*
X1393695Y1204405D03*
Y1206905D03*
Y1211905D03*
Y1209405D03*
X1385992Y1285466D03*
X1390492D03*
X1392000Y1644980D03*
X1409248Y109410D03*
Y102323D03*
X1404548Y116497D03*
X1402048D03*
X1404548Y109410D03*
X1409248Y116496D03*
X1402048Y130670D03*
Y123584D03*
X1404548Y123583D03*
X1409248Y130670D03*
Y123583D03*
X1404548Y130670D03*
X1409248Y137756D03*
X1402048Y137757D03*
X1408666Y324733D03*
X1411950Y448466D03*
X1408103Y555194D03*
X1410903D03*
X1408103Y563194D03*
X1410903D03*
X1408103Y571194D03*
X1410903D03*
X1406512Y581222D03*
X1403712D03*
Y591215D03*
X1406512D03*
X1405514Y611091D03*
X1405000Y656000D03*
Y699000D03*
X1404689Y910897D03*
X1413575Y915186D03*
X1413322Y958908D03*
X1404317Y989436D03*
X1411038Y985379D03*
X1404936Y1098767D03*
X1415494Y1139435D03*
Y1136935D03*
Y1134435D03*
Y1131935D03*
X1409092Y1136935D03*
Y1134435D03*
Y1139435D03*
Y1131935D03*
X1402392Y1125801D03*
X1404892D03*
X1402392Y1129301D03*
X1404892D03*
X1409092Y1141935D03*
X1416736Y1152713D03*
Y1155213D03*
X1402256D03*
Y1152713D03*
X1415494Y1144435D03*
Y1146935D03*
Y1141935D03*
X1409092Y1146935D03*
Y1144435D03*
X1407995Y1204617D03*
X1410310Y1200821D03*
Y1198321D03*
X1407995Y1207117D03*
Y1209617D03*
Y1212117D03*
X1415903Y1282590D03*
X1404019Y1285290D03*
X1414346Y1303020D03*
X1412000Y1644980D03*
X1417710Y82984D03*
Y75184D03*
Y77784D03*
Y80384D03*
X1420264Y92849D03*
X1417710Y85584D03*
X1427224Y103037D03*
X1427358Y116496D03*
Y109410D03*
Y130670D03*
Y123583D03*
X1423515Y137756D03*
X1429539Y293796D03*
X1432039D03*
X1431019Y434508D03*
X1427019D03*
X1424196Y446352D03*
X1428782Y445874D03*
X1417856Y455466D03*
X1433310Y504699D03*
X1430810D03*
X1433012Y516979D03*
X1430512D03*
X1427233Y628183D03*
X1424389Y627948D03*
X1426000Y709000D03*
Y713000D03*
Y757000D03*
Y753000D03*
X1422813Y910065D03*
X1424126Y900295D03*
X1427553Y939200D03*
X1427473Y965621D03*
X1420740Y1004766D03*
Y1000766D03*
Y1016266D03*
Y1030766D03*
X1420107Y1052514D03*
X1431876Y1098518D03*
X1426624Y1098428D03*
X1421120Y1123101D03*
X1429120D03*
X1431620D03*
X1422020Y1129301D03*
X1424520D03*
X1427020D03*
X1429520D03*
X1432020D03*
X1417994Y1139435D03*
Y1136935D03*
Y1134435D03*
Y1131935D03*
X1421120Y1125801D03*
X1429520D03*
X1432020D03*
X1419520Y1129301D03*
X1432384Y1155213D03*
Y1152713D03*
X1422984D03*
Y1155213D03*
X1417994Y1144435D03*
Y1146935D03*
Y1141935D03*
X1420625Y1204405D03*
Y1206905D03*
Y1209405D03*
X1425652Y1297411D03*
X1433386Y1343309D03*
X1428840Y1407740D03*
X1423065Y1508327D03*
X1432499Y1512175D03*
X1424245Y1543338D03*
X1425558Y1537432D03*
X1425260Y1558072D03*
X1433558Y1555366D03*
X1423701Y1563978D03*
X1432000Y1644980D03*
X1444641Y94017D03*
X1448641D03*
X1440641D03*
X1449761Y115401D03*
Y110445D03*
X1444769D03*
Y115401D03*
X1449761Y124618D03*
X1444769D03*
Y129574D03*
X1449761D03*
X1442682Y151540D03*
X1446332Y191941D03*
X1446199Y188727D03*
X1442956Y226141D03*
X1440156D03*
X1448026Y256535D03*
X1440053Y285690D03*
X1437553D03*
X1440053Y288190D03*
X1442853D03*
Y285690D03*
X1447079Y290755D03*
X1437553Y288190D03*
X1437758Y362584D03*
X1435019Y434508D03*
X1437757Y447201D03*
X1437879Y444269D03*
X1435810Y504699D03*
X1447036Y519518D03*
X1435512Y516979D03*
X1444536Y519518D03*
X1439536D03*
X1442036D03*
X1435241Y593796D03*
X1440930Y636005D03*
Y633205D03*
Y638805D03*
X1437784Y683532D03*
X1436567Y727532D03*
X1443000Y798500D03*
Y794500D03*
Y842500D03*
Y838500D03*
X1438188Y867633D03*
X1437703Y880067D03*
X1449072Y892581D03*
X1435288Y897500D03*
X1444453Y938806D03*
X1439449Y979009D03*
X1440610Y1021567D03*
X1435266Y1031522D03*
X1437064Y1098767D03*
X1441220Y1131935D03*
Y1139435D03*
Y1134435D03*
Y1136935D03*
X1434520Y1125801D03*
X1437020D03*
X1434520Y1129301D03*
X1437020D03*
X1441220Y1141935D03*
Y1144435D03*
Y1146935D03*
X1442448Y1152684D03*
X1434925Y1204617D03*
X1437240Y1200821D03*
Y1198321D03*
X1434925Y1207117D03*
Y1209617D03*
Y1212117D03*
X1436408Y1303462D03*
X1444438Y1308312D03*
X1439482D03*
X1441286Y1335776D03*
X1457718Y84140D03*
Y76140D03*
Y80140D03*
X1452650Y94017D03*
X1460163Y117557D03*
X1455171D03*
Y122513D03*
X1460163Y131731D03*
Y122513D03*
X1455171Y131731D03*
X1458262Y146461D03*
X1460163Y136687D03*
X1455171D03*
X1457164Y152367D03*
X1463547Y180527D03*
X1458864Y180572D03*
Y185165D03*
X1463502Y185121D03*
X1452832Y184619D03*
X1454812Y206760D03*
X1456026Y256535D03*
X1457056Y279208D03*
X1461160Y281307D03*
X1455079Y290755D03*
X1451079D03*
X1458982Y356861D03*
X1453000Y633450D03*
Y636250D03*
Y639050D03*
X1453032Y769032D03*
X1453775Y813032D03*
X1461241Y867475D03*
X1462694Y874859D03*
Y877859D03*
X1460472Y885985D03*
X1459420Y899226D03*
X1451005Y931848D03*
X1462819Y949996D03*
X1462000Y960378D03*
X1460655Y964253D03*
X1466076Y979746D03*
X1462388Y1006560D03*
X1455939Y1018368D03*
X1465503Y1030233D03*
X1460592Y1345691D03*
Y1350683D03*
X1465548Y1345691D03*
Y1350683D03*
X1460592Y1357603D03*
Y1362595D03*
X1465548Y1357603D03*
Y1362595D03*
X1460592Y1381801D03*
Y1374881D03*
Y1369889D03*
X1465548Y1381801D03*
Y1374881D03*
Y1369889D03*
X1460592Y1386793D03*
X1465548D03*
X1452000Y1644980D03*
X1480460Y60922D03*
X1475296Y55513D03*
X1471093Y117261D03*
X1478624Y113394D03*
X1481273Y110784D03*
X1481368Y130898D03*
X1478800Y180665D03*
Y172665D03*
X1467270Y192421D03*
X1478832Y200864D03*
Y212864D03*
Y216864D03*
Y221864D03*
X1480589Y252371D03*
X1473900Y433100D03*
X1478710Y685630D03*
X1473525Y710052D03*
X1474425Y716075D03*
X1479962Y727500D03*
X1471415Y748629D03*
X1474425Y760075D03*
X1473634Y864337D03*
X1481454Y911570D03*
X1474075Y920575D03*
X1474349Y949394D03*
X1468500Y974181D03*
X1479096Y997860D03*
X1471096D03*
X1475096D03*
X1467096D03*
X1471854Y1035088D03*
X1479624Y1035102D03*
X1468371Y1030701D03*
X1480193Y1102091D03*
X1474384D03*
X1480193Y1114691D03*
X1474384D03*
X1480193Y1127291D03*
X1474384D03*
X1480193Y1139891D03*
X1474384D03*
X1480193Y1152491D03*
X1474384D03*
X1480193Y1165091D03*
X1474384D03*
X1480193Y1177691D03*
X1474384D03*
X1480675Y1202103D03*
X1477788Y1350683D03*
Y1345691D03*
X1472832Y1350683D03*
Y1345691D03*
X1477788Y1357603D03*
Y1362595D03*
X1472832Y1357603D03*
Y1362595D03*
X1477788Y1381801D03*
Y1369795D03*
Y1374881D03*
X1472832Y1381801D03*
Y1369795D03*
Y1374881D03*
X1477788Y1386793D03*
Y1399079D03*
Y1393993D03*
X1472832Y1386793D03*
Y1393993D03*
Y1399079D03*
X1477788Y1405999D03*
Y1410991D03*
X1472832Y1405999D03*
Y1410991D03*
X1476094Y1465913D03*
Y1461182D03*
Y1456451D03*
Y1471805D03*
Y1481267D03*
Y1476536D03*
Y1491890D03*
Y1487159D03*
Y1496621D03*
Y1502514D03*
Y1511976D03*
Y1507245D03*
Y1563544D03*
Y1558813D03*
Y1568275D03*
Y1578898D03*
Y1574167D03*
Y1583629D03*
Y1594253D03*
Y1589522D03*
Y1609607D03*
Y1598984D03*
Y1604876D03*
Y1614338D03*
X1472000Y1644980D03*
X1493859Y109172D03*
X1496859D03*
X1495866Y106495D03*
X1488867Y133298D03*
X1495600Y146012D03*
X1497506Y141228D03*
X1483014Y134579D03*
X1495071Y253198D03*
X1486360Y358700D03*
Y354200D03*
X1496473Y769000D03*
X1491062Y793003D03*
X1491425Y801575D03*
X1496845Y813000D03*
X1491425Y845575D03*
X1489650Y836985D03*
X1489805Y866386D03*
X1497488Y873839D03*
X1491414Y875383D03*
X1494000Y884000D03*
X1498084Y894825D03*
X1492101Y894860D03*
X1496383Y898023D03*
X1496500Y919000D03*
X1496000Y922000D03*
X1487075Y920925D03*
X1485100Y943900D03*
X1496425Y943075D03*
X1496072Y950044D03*
X1482591Y961909D03*
X1486500Y947000D03*
X1485226Y973886D03*
X1492560Y974654D03*
X1495339Y1009354D03*
X1491839D03*
X1486030D03*
X1491096Y997860D03*
X1483096D03*
X1495096D03*
X1487096D03*
X1495339Y1021954D03*
X1491839D03*
X1486030D03*
X1483693Y1102091D03*
Y1114691D03*
Y1127291D03*
Y1139891D03*
Y1152491D03*
Y1165091D03*
Y1177691D03*
X1498197Y1209607D03*
X1492471Y1215195D03*
X1484055Y1223749D03*
X1497312Y1350683D03*
Y1345691D03*
X1485072D03*
Y1350683D03*
X1490028Y1345691D03*
Y1350683D03*
X1497312Y1357603D03*
Y1362595D03*
X1485072D03*
Y1357603D03*
X1490028D03*
Y1362595D03*
X1485072Y1369889D03*
Y1374881D03*
Y1381801D03*
X1490028Y1369889D03*
Y1374881D03*
Y1381801D03*
X1497312D03*
Y1374881D03*
Y1369889D03*
Y1386793D03*
Y1394087D03*
Y1399079D03*
X1485072Y1394087D03*
Y1399079D03*
Y1386793D03*
X1490028Y1399079D03*
Y1394087D03*
Y1386793D03*
X1497312Y1405999D03*
Y1410991D03*
X1485072Y1405999D03*
Y1410991D03*
X1490028Y1405999D03*
Y1410991D03*
X1484755Y1465513D03*
Y1460782D03*
X1493417Y1465913D03*
Y1456451D03*
Y1461182D03*
Y1471805D03*
Y1476536D03*
Y1481267D03*
X1484755Y1476136D03*
Y1470244D03*
Y1480867D03*
Y1496221D03*
X1493417Y1487159D03*
Y1491890D03*
Y1496621D03*
X1484755Y1491490D03*
Y1485598D03*
Y1506845D03*
Y1500952D03*
Y1511576D03*
X1493417Y1507245D03*
Y1502514D03*
Y1511976D03*
X1484755Y1516307D03*
Y1563144D03*
X1493417Y1558813D03*
Y1563544D03*
Y1578898D03*
X1484755Y1567875D03*
Y1578498D03*
Y1572606D03*
X1493417Y1568275D03*
Y1574167D03*
X1484755Y1583229D03*
Y1593853D03*
Y1587960D03*
X1493417Y1583629D03*
Y1589522D03*
Y1594253D03*
X1484755Y1609207D03*
Y1598584D03*
Y1603315D03*
X1493417Y1609607D03*
Y1604876D03*
Y1598984D03*
X1484755Y1613938D03*
Y1618669D03*
X1493417Y1614338D03*
X1492000Y1644980D03*
X1511610Y116496D03*
Y109410D03*
Y102323D03*
X1499610Y116497D03*
X1506910D03*
X1504410D03*
X1506910Y109410D03*
X1511610Y123583D03*
X1499610Y130670D03*
Y123584D03*
X1506910Y130670D03*
X1504410D03*
Y123584D03*
X1506910Y123583D03*
X1511610Y130670D03*
Y137756D03*
X1499610Y137757D03*
X1504410D03*
X1500394Y150847D03*
X1502362Y247292D03*
X1501807Y323766D03*
X1507864Y450750D03*
X1511963Y536382D03*
X1510280Y899732D03*
X1514354Y938811D03*
X1510500Y931500D03*
X1513955Y950396D03*
X1505888Y965964D03*
X1514000Y968739D03*
X1510740Y973740D03*
X1507096Y997860D03*
X1503096D03*
X1511096D03*
X1499096D03*
X1505130Y1105091D03*
Y1117691D03*
Y1130291D03*
Y1142891D03*
Y1155491D03*
Y1168091D03*
Y1180691D03*
X1509552Y1350683D03*
Y1345691D03*
X1514508Y1350683D03*
Y1345691D03*
X1502268Y1350683D03*
Y1345691D03*
X1509552Y1362595D03*
Y1357603D03*
X1514508D03*
Y1362595D03*
X1502268Y1357603D03*
Y1362595D03*
X1509552Y1374881D03*
Y1369889D03*
Y1381801D03*
X1514508Y1374881D03*
Y1369889D03*
Y1381801D03*
X1502268D03*
Y1374881D03*
Y1369889D03*
X1509552Y1394087D03*
Y1399079D03*
Y1386793D03*
X1514508Y1394087D03*
Y1399079D03*
Y1386793D03*
X1502268D03*
Y1399079D03*
Y1394087D03*
X1509552Y1405999D03*
Y1410991D03*
X1514508Y1405999D03*
Y1410991D03*
X1502268Y1405999D03*
Y1410991D03*
X1502078Y1465513D03*
Y1460782D03*
X1510740Y1465913D03*
Y1456451D03*
Y1461182D03*
X1502078Y1470244D03*
Y1480867D03*
X1510740Y1471805D03*
Y1476536D03*
Y1481267D03*
X1502078Y1476136D03*
Y1491490D03*
Y1485598D03*
Y1496221D03*
X1510740Y1487159D03*
Y1491890D03*
Y1496621D03*
Y1507245D03*
Y1502514D03*
Y1511976D03*
X1502078Y1506845D03*
Y1500952D03*
Y1511576D03*
Y1516307D03*
X1510740Y1563544D03*
X1502078Y1563144D03*
X1510740Y1558813D03*
Y1578898D03*
X1502078Y1567875D03*
Y1578498D03*
Y1572606D03*
X1510740Y1568275D03*
Y1574167D03*
X1502078Y1583229D03*
Y1593853D03*
Y1587960D03*
X1510740Y1583629D03*
Y1589522D03*
Y1594253D03*
X1502078Y1609207D03*
Y1598584D03*
Y1603315D03*
X1510740Y1609607D03*
Y1604876D03*
Y1598984D03*
X1502078Y1613938D03*
Y1618669D03*
X1510740Y1614338D03*
X1512000Y1644980D03*
X1520072Y82984D03*
Y75184D03*
Y77784D03*
Y80384D03*
X1522626Y92849D03*
X1520072Y85584D03*
X1529586Y103037D03*
X1529720Y116496D03*
Y109410D03*
Y130670D03*
Y123583D03*
X1526311Y137756D03*
X1528635Y555234D03*
X1528350Y562003D03*
X1519156Y596095D03*
X1516869Y594668D03*
X1518354Y592354D03*
X1518415Y589556D03*
X1519153Y599588D03*
X1516930Y597580D03*
X1519185Y615600D03*
X1519153Y607588D03*
X1523646Y634946D03*
X1519063Y876339D03*
X1517344Y896999D03*
X1515743Y888133D03*
X1517344Y903179D03*
X1517153Y908367D03*
X1523000Y923740D03*
X1526611Y921442D03*
X1525740Y928740D03*
X1528087Y936394D03*
X1524500Y949500D03*
X1530174Y956986D03*
X1525522Y971075D03*
X1523966Y980281D03*
X1515096Y997860D03*
X1531096D03*
X1519096D03*
X1523096D03*
X1516776Y1024954D03*
Y1012354D03*
X1526748Y1345691D03*
Y1350683D03*
X1521792Y1345691D03*
Y1350683D03*
X1526748Y1357603D03*
Y1362595D03*
X1521792Y1357603D03*
Y1362595D03*
X1526748Y1369889D03*
Y1374881D03*
Y1381801D03*
X1521792Y1374881D03*
Y1381801D03*
Y1369889D03*
X1526748Y1386793D03*
Y1399079D03*
Y1394087D03*
X1521792Y1386793D03*
Y1394087D03*
Y1399079D03*
X1526748Y1405999D03*
Y1410991D03*
X1521792Y1405999D03*
Y1410991D03*
X1519401Y1465513D03*
Y1460782D03*
X1528062Y1465913D03*
Y1456451D03*
Y1461182D03*
Y1481267D03*
X1519401Y1476136D03*
Y1470244D03*
Y1480867D03*
X1528062Y1471805D03*
Y1476536D03*
X1519401Y1491490D03*
Y1485598D03*
Y1496221D03*
X1528062Y1487159D03*
Y1491890D03*
Y1496621D03*
X1519401Y1506845D03*
Y1500952D03*
Y1511576D03*
X1528062Y1507245D03*
Y1502514D03*
Y1511976D03*
X1519401Y1516307D03*
Y1563144D03*
X1528062Y1558813D03*
Y1563544D03*
Y1578898D03*
X1519401Y1567875D03*
Y1578498D03*
Y1572606D03*
X1528062Y1568275D03*
Y1574167D03*
X1519401Y1587960D03*
X1528062Y1583629D03*
Y1589522D03*
Y1594253D03*
X1519401Y1583229D03*
Y1593853D03*
Y1609207D03*
Y1598584D03*
Y1603315D03*
X1528062Y1609607D03*
Y1604876D03*
Y1598984D03*
X1519401Y1613938D03*
Y1618669D03*
X1528062Y1614338D03*
X1547003Y94017D03*
X1543003D03*
X1547131Y110445D03*
Y115401D03*
Y129574D03*
Y124618D03*
X1545044Y151540D03*
X1548561Y188727D03*
X1542518Y226141D03*
X1545318D03*
X1531901Y293796D03*
X1539915Y288190D03*
X1542415Y285690D03*
X1539915D03*
X1542415Y288190D03*
X1545215D03*
Y285690D03*
X1534401Y293796D03*
X1541283Y354553D03*
X1546272Y1350683D03*
Y1345691D03*
X1534032Y1350683D03*
Y1345691D03*
X1538988D03*
Y1350683D03*
X1546272Y1357603D03*
Y1362595D03*
X1534032Y1357603D03*
Y1362595D03*
X1538988D03*
Y1357603D03*
X1546272Y1374881D03*
Y1369889D03*
Y1381801D03*
X1534032Y1369889D03*
Y1381801D03*
Y1374881D03*
X1538988Y1369889D03*
Y1381801D03*
Y1374881D03*
X1546272Y1386793D03*
Y1394087D03*
Y1399079D03*
X1534032Y1394087D03*
Y1399079D03*
Y1386793D03*
X1538988Y1394087D03*
Y1399079D03*
Y1386793D03*
X1546272Y1405999D03*
Y1410991D03*
X1534032Y1405999D03*
Y1410991D03*
X1538988Y1405999D03*
Y1410991D03*
X1545385Y1461183D03*
X1536724Y1465513D03*
Y1460782D03*
X1545385Y1465914D03*
Y1456452D03*
X1536724Y1476136D03*
Y1470244D03*
Y1480867D03*
X1545385Y1476537D03*
Y1471806D03*
Y1481268D03*
X1536724Y1491490D03*
Y1485598D03*
Y1496221D03*
X1545385Y1491891D03*
Y1487160D03*
Y1496622D03*
X1536724Y1506845D03*
Y1500952D03*
Y1511576D03*
X1545385Y1507246D03*
Y1502515D03*
Y1511977D03*
X1536724Y1516307D03*
X1545385Y1563544D03*
Y1558813D03*
X1536724Y1563144D03*
Y1567875D03*
X1545385Y1568275D03*
X1536724Y1578498D03*
Y1572606D03*
X1545385Y1578898D03*
Y1574167D03*
Y1594253D03*
Y1589522D03*
X1536724Y1583229D03*
X1545385Y1583629D03*
X1536724Y1593853D03*
Y1587960D03*
Y1609207D03*
Y1598584D03*
Y1603315D03*
X1545385Y1609607D03*
Y1598984D03*
Y1604876D03*
Y1614338D03*
X1536724Y1613938D03*
Y1618669D03*
X1532000Y1644980D03*
X1560080Y84140D03*
Y76140D03*
Y80140D03*
X1555012Y94017D03*
X1551003D03*
X1562525Y117557D03*
X1557533D03*
X1552123Y115401D03*
Y110445D03*
X1562525Y122513D03*
X1552123Y129574D03*
Y124618D03*
X1557533Y131731D03*
Y122513D03*
X1562525Y131731D03*
X1560624Y146461D03*
X1557533Y136687D03*
X1562525D03*
X1559526Y152367D03*
X1561226Y180572D03*
X1548694Y191941D03*
X1555194Y184619D03*
X1561226Y185165D03*
X1557174Y206760D03*
X1550388Y256535D03*
X1558388D03*
X1559418Y279208D03*
X1563522Y281307D03*
X1549441Y290755D03*
X1553441D03*
X1557441D03*
X1554403Y352363D03*
X1563248Y389154D03*
X1548629D03*
Y403327D03*
Y410413D03*
X1561778Y396240D03*
X1548629D03*
Y417500D03*
Y424587D03*
Y438760D03*
Y431673D03*
Y445847D03*
Y467539D03*
Y474626D03*
Y488799D03*
Y481713D03*
Y495886D03*
Y511673D03*
Y518760D03*
X1562089Y516841D03*
X1548629Y540020D03*
Y525847D03*
Y532933D03*
Y547106D03*
X1556914Y552872D03*
X1557036Y550123D03*
X1556359Y562443D03*
X1558668Y572334D03*
X1558127Y560675D03*
X1556900Y574102D03*
X1547910Y602197D03*
X1548374Y595108D03*
X1561535Y653161D03*
X1565132Y677843D03*
X1547813Y906581D03*
X1551099Y959096D03*
X1558512Y1345691D03*
Y1350683D03*
X1563468D03*
Y1345691D03*
X1551228Y1350683D03*
Y1345691D03*
X1563468Y1362595D03*
X1551228Y1357603D03*
Y1362595D03*
X1558512D03*
Y1357603D03*
X1563468D03*
X1558512Y1374881D03*
Y1369889D03*
Y1381801D03*
X1563468Y1374881D03*
Y1369889D03*
Y1381801D03*
X1551228Y1369889D03*
Y1381801D03*
Y1374881D03*
X1558512Y1399079D03*
Y1394087D03*
Y1386793D03*
X1563468Y1399079D03*
Y1394087D03*
Y1386793D03*
X1551228D03*
Y1394087D03*
Y1399079D03*
X1558512Y1405999D03*
Y1410991D03*
X1563468Y1405999D03*
Y1410991D03*
X1551228Y1405999D03*
Y1410991D03*
X1552000Y1644980D03*
X1576256Y-25273D03*
X1573003Y-25287D03*
X1576241Y-27788D03*
X1572988Y-27802D03*
X1579281Y-26693D03*
X1573455Y117261D03*
X1565909Y180527D03*
X1569632Y192421D03*
X1565864Y185121D03*
X1571625Y333549D03*
X1579340Y396240D03*
Y403327D03*
Y410413D03*
X1566555Y414823D03*
X1565863Y422864D03*
X1579340Y417500D03*
Y424586D03*
X1565933Y429832D03*
X1565538Y436447D03*
X1579340Y431673D03*
Y438760D03*
X1567573Y447953D03*
X1579340Y445847D03*
X1566740Y467539D03*
X1565482Y472772D03*
X1579340Y474626D03*
Y488799D03*
X1566216Y487711D03*
X1566329Y479104D03*
X1579340Y481712D03*
Y495886D03*
X1566740D03*
X1579340Y518760D03*
X1565050Y511673D03*
X1579340Y540020D03*
Y532933D03*
Y525846D03*
X1574222Y629872D03*
X1569926Y668885D03*
X1575950Y662981D03*
X1570331Y691851D03*
X1575942Y705043D03*
X1575708Y1345597D03*
X1570752Y1350683D03*
Y1345597D03*
X1575708Y1350683D03*
X1570752Y1357603D03*
Y1362595D03*
X1575708D03*
Y1357603D03*
Y1381801D03*
Y1374881D03*
Y1369889D03*
X1570752D03*
Y1381801D03*
Y1374881D03*
X1575708Y1386793D03*
Y1399079D03*
Y1393993D03*
X1570752Y1386793D03*
Y1393993D03*
Y1399079D03*
X1575708Y1405999D03*
Y1410991D03*
X1570752Y1405999D03*
Y1410991D03*
X1572000Y1644980D03*
X1586256Y-64207D03*
X1583003D03*
X1586241Y-66722D03*
X1582988D03*
X1589281Y-65613D03*
X1582822Y60922D03*
X1580327Y57448D03*
X1580986Y113394D03*
X1583635Y110784D03*
X1591229Y133298D03*
X1583229D03*
X1585376Y134579D03*
X1581162Y180665D03*
Y172665D03*
X1581194Y212864D03*
Y200864D03*
Y221864D03*
Y216864D03*
X1582951Y252371D03*
X1586640Y389153D03*
X1581840D03*
Y403326D03*
Y410413D03*
X1586640D03*
X1581840Y396240D03*
X1586640D03*
Y403326D03*
Y417499D03*
X1581840D03*
Y424586D03*
X1586640D03*
X1581840Y438760D03*
X1586640D03*
Y431673D03*
X1581840D03*
X1586640Y467539D03*
X1581840D03*
Y474626D03*
X1586640D03*
X1581840Y488799D03*
X1586640D03*
X1581840Y481712D03*
X1586640D03*
X1581840Y518760D03*
Y511673D03*
X1586640D03*
Y518760D03*
Y525846D03*
Y532933D03*
X1581840D03*
Y525846D03*
X1595185Y543925D03*
X1595760Y555000D03*
X1583720Y560500D03*
X1587948Y1350683D03*
Y1345691D03*
X1582992D03*
Y1350683D03*
X1587948Y1362595D03*
Y1357603D03*
X1582992Y1362595D03*
Y1357603D03*
Y1369889D03*
Y1381801D03*
Y1374881D03*
X1587948Y1369889D03*
Y1381801D03*
Y1374881D03*
X1582992Y1399079D03*
Y1394087D03*
Y1386793D03*
X1587948Y1399079D03*
Y1394087D03*
Y1386793D03*
X1582992Y1405999D03*
Y1410991D03*
X1587948Y1405999D03*
Y1410991D03*
X1592020Y1433061D03*
X1591610Y1469940D03*
X1591586Y1505130D03*
X1609272Y109410D03*
X1601972Y116497D03*
X1609272D03*
X1606772D03*
X1596221Y109172D03*
X1599221D03*
X1598228Y106495D03*
X1601972Y123584D03*
Y130670D03*
X1606772Y123584D03*
X1609272Y123583D03*
Y130670D03*
X1606772D03*
Y137757D03*
X1597962Y146012D03*
X1599868Y141228D03*
X1601972Y137757D03*
X1602756Y150847D03*
X1604724Y247292D03*
X1597433Y253198D03*
X1608240Y329000D03*
X1603664Y342596D03*
X1598223Y351003D03*
X1599127Y375587D03*
X1596714Y383003D03*
X1614338Y636842D03*
X1610620Y1345691D03*
Y1350683D03*
Y1357603D03*
Y1362595D03*
Y1381801D03*
Y1374881D03*
Y1369889D03*
Y1386793D03*
X1597225Y1437014D03*
X1603363Y1460570D03*
X1597457Y1452556D03*
X1598500Y1472500D03*
X1606745Y1474242D03*
X1602580Y1483108D03*
X1598000Y1486000D03*
X1604000Y1516000D03*
X1600700Y1534300D03*
X1622434Y82984D03*
Y80384D03*
Y75184D03*
Y77784D03*
X1624988Y92849D03*
X1622434Y85584D03*
X1613972Y116496D03*
Y102323D03*
Y109410D03*
Y130670D03*
Y123583D03*
Y137756D03*
X1625952Y431029D03*
X1626260Y427017D03*
X1625018Y435029D03*
X1625938Y449873D03*
X1625565Y472579D03*
Y479666D03*
Y486752D03*
Y493839D03*
Y523800D03*
Y516713D03*
Y537973D03*
Y530886D03*
Y566752D03*
Y588013D03*
Y573839D03*
Y580926D03*
Y602186D03*
Y595099D03*
Y609272D03*
Y616359D03*
X1620244Y638125D03*
X1617843Y665140D03*
X1613110Y678462D03*
X1624148Y708258D03*
X1627455Y759489D03*
X1619612Y783152D03*
X1620359Y774830D03*
X1619569Y796035D03*
X1620755Y787530D03*
X1613235Y808466D03*
X1620479Y815730D03*
X1620072Y801630D03*
X1616255Y824405D03*
X1619859Y839519D03*
X1615576Y1345691D03*
Y1350683D03*
X1622860D03*
Y1345691D03*
X1627816Y1350683D03*
Y1345691D03*
X1615576Y1357603D03*
Y1362595D03*
X1622860Y1357603D03*
Y1362595D03*
X1627816Y1357603D03*
Y1362595D03*
X1622860Y1381801D03*
Y1369795D03*
Y1374881D03*
X1627816Y1381801D03*
Y1369795D03*
Y1374881D03*
X1615576Y1381801D03*
Y1374881D03*
Y1369889D03*
Y1386793D03*
X1622860D03*
Y1393993D03*
Y1399079D03*
X1627816Y1386793D03*
Y1399079D03*
Y1393993D03*
X1622860Y1405999D03*
Y1410991D03*
X1627816Y1405999D03*
Y1410991D03*
X1618800Y1528558D03*
X1614200Y1519500D03*
X1614360Y1542860D03*
X1618600Y1532000D03*
X1631948Y103037D03*
X1632082Y116496D03*
Y109410D03*
Y130670D03*
Y123583D03*
X1628673Y137756D03*
X1644880Y226141D03*
X1644777Y288190D03*
X1642277Y285690D03*
X1644777D03*
X1642277Y288190D03*
X1636763Y293796D03*
X1634263D03*
X1635987Y335616D03*
X1630703Y350655D03*
X1636468Y345595D03*
X1636271Y410394D03*
Y403307D03*
X1637665Y458406D03*
Y451319D03*
X1637489Y462264D03*
X1632865Y465492D03*
X1637665D03*
Y472579D03*
X1632865D03*
X1630365D03*
Y479666D03*
X1632865D03*
X1637665Y479665D03*
Y486752D03*
X1630365D03*
X1632865D03*
X1630365Y493839D03*
X1637665D03*
X1632865Y509626D03*
Y516713D03*
X1630365D03*
Y523800D03*
X1632865D03*
X1637665Y523799D03*
Y516713D03*
Y509626D03*
X1630365Y530886D03*
X1637665D03*
X1632865D03*
X1637665Y537973D03*
X1630365D03*
X1637665Y559665D03*
Y566752D03*
X1630365D03*
X1632865D03*
Y559665D03*
Y573839D03*
X1630365Y580926D03*
X1632865D03*
X1637665D03*
Y588012D03*
X1630365Y588013D03*
X1632865Y588012D03*
X1637665Y573839D03*
X1630365D03*
X1632865Y602185D03*
X1630365Y602186D03*
X1637665Y602185D03*
Y595099D03*
X1632865D03*
X1630365D03*
Y616359D03*
X1632865Y609272D03*
X1630365D03*
X1637665Y616358D03*
Y609272D03*
X1637526Y699930D03*
X1637472Y717830D03*
X1631031Y732430D03*
X1628813Y727045D03*
X1631187Y750630D03*
X1629969Y740826D03*
X1644304Y891353D03*
X1640056Y1345691D03*
Y1350683D03*
X1635100Y1345691D03*
Y1350683D03*
X1640056Y1357603D03*
Y1362595D03*
X1635100D03*
Y1357603D03*
X1640056Y1369889D03*
Y1374881D03*
Y1381801D03*
X1635100Y1369889D03*
Y1374881D03*
Y1381801D03*
X1640056Y1399079D03*
Y1394087D03*
Y1386793D03*
X1635100Y1394087D03*
Y1399079D03*
Y1386793D03*
Y1405999D03*
Y1410991D03*
X1640056Y1405999D03*
Y1410991D03*
X1649365Y94017D03*
X1657374D03*
X1653365D03*
X1645365D03*
X1659895Y117557D03*
X1654485Y110445D03*
Y115401D03*
X1649493Y110445D03*
Y115401D03*
X1659895Y122513D03*
Y131731D03*
X1654485Y124618D03*
Y129574D03*
X1649493Y124618D03*
Y129574D03*
X1659895Y136687D03*
X1647406Y151540D03*
X1651056Y191941D03*
X1657556Y184619D03*
X1650923Y188727D03*
X1659536Y206760D03*
X1647680Y226141D03*
X1660750Y256535D03*
X1652750D03*
X1647577Y285690D03*
Y288190D03*
X1655803Y290755D03*
X1651803D03*
X1659803D03*
X1645685Y390500D03*
X1655335Y381500D03*
X1653507Y470136D03*
X1655776Y465492D03*
X1655742Y460250D03*
X1655776Y472579D03*
Y486752D03*
Y479665D03*
Y493839D03*
Y509626D03*
Y516713D03*
X1652236Y537973D03*
X1654716Y525483D03*
X1654637Y532756D03*
X1655776Y559665D03*
Y566752D03*
X1655626Y579978D03*
X1655776Y573839D03*
X1655840Y608117D03*
X1654572Y771702D03*
X1645128Y929263D03*
X1645342Y962120D03*
X1657091Y990823D03*
X1649571Y983857D03*
X1647340Y1350683D03*
Y1345691D03*
X1652296Y1350683D03*
Y1345691D03*
X1659580Y1350683D03*
Y1345691D03*
X1647340Y1357603D03*
Y1362595D03*
X1652296Y1357603D03*
Y1362595D03*
X1659580D03*
Y1357603D03*
X1647340Y1381801D03*
Y1374881D03*
Y1369889D03*
X1652296Y1381801D03*
Y1374881D03*
Y1369889D03*
X1659580Y1374881D03*
Y1369889D03*
Y1381801D03*
X1647340Y1386793D03*
Y1394087D03*
Y1399079D03*
X1652296Y1386793D03*
Y1399079D03*
Y1394087D03*
X1659580D03*
Y1399079D03*
Y1386793D03*
X1647340Y1405999D03*
Y1410991D03*
X1652296Y1405999D03*
Y1410991D03*
X1659580Y1405999D03*
Y1410991D03*
X1657983Y1460782D03*
X1649322Y1456451D03*
Y1465913D03*
X1657983Y1465513D03*
X1649322Y1461182D03*
Y1476536D03*
X1657983Y1476136D03*
Y1470244D03*
X1649322Y1471805D03*
Y1481267D03*
X1657983Y1480867D03*
X1649322Y1487159D03*
Y1496621D03*
X1657983Y1496221D03*
X1649322Y1491890D03*
X1657983Y1491490D03*
Y1485598D03*
Y1500952D03*
X1649322Y1502514D03*
X1657983Y1511576D03*
X1649322Y1511976D03*
Y1507245D03*
X1657983Y1506845D03*
Y1516307D03*
X1649322Y1558813D03*
Y1563544D03*
X1657983Y1563144D03*
Y1572606D03*
X1649322Y1574167D03*
Y1568275D03*
X1657983Y1567875D03*
X1649322Y1578898D03*
X1657983Y1578498D03*
X1649322Y1583629D03*
X1657983Y1583229D03*
X1649322Y1594253D03*
X1657983Y1593853D03*
Y1587960D03*
X1649322Y1589522D03*
Y1609607D03*
X1657983Y1609207D03*
X1649322Y1598984D03*
X1657983Y1598584D03*
Y1603315D03*
X1649322Y1604876D03*
Y1614338D03*
X1657983Y1613938D03*
Y1618669D03*
X1652000Y1644980D03*
X1662442Y84140D03*
Y76140D03*
Y80140D03*
X1675817Y117261D03*
X1664887Y117557D03*
Y122513D03*
Y131731D03*
X1662986Y146461D03*
X1664887Y136687D03*
X1661888Y152367D03*
X1663588Y180572D03*
X1668271Y180527D03*
X1671994Y192421D03*
X1663588Y185165D03*
X1668226Y185121D03*
X1661780Y279208D03*
X1665884Y281307D03*
X1669767Y445908D03*
X1673717Y445787D03*
X1664536Y1350683D03*
Y1345691D03*
X1671820D03*
Y1350683D03*
X1676776Y1345691D03*
Y1350683D03*
X1664536Y1357603D03*
Y1362595D03*
X1671820Y1357603D03*
Y1362595D03*
X1676776Y1357603D03*
Y1362595D03*
X1664536Y1374881D03*
Y1369889D03*
Y1381801D03*
X1671820Y1374881D03*
Y1381801D03*
Y1369889D03*
X1676776D03*
Y1374881D03*
Y1381801D03*
X1664536Y1394087D03*
Y1399079D03*
Y1386793D03*
X1671820D03*
Y1394087D03*
Y1399079D03*
X1676776Y1386793D03*
Y1399079D03*
Y1394087D03*
X1664536Y1405999D03*
Y1410991D03*
X1671820Y1405999D03*
Y1410991D03*
X1676776Y1405999D03*
Y1410991D03*
X1666645Y1465913D03*
Y1456451D03*
Y1461182D03*
X1675306Y1465513D03*
Y1460782D03*
X1666645Y1471805D03*
Y1476536D03*
Y1481267D03*
X1675306Y1476136D03*
Y1470244D03*
Y1480867D03*
X1666645Y1487159D03*
Y1491890D03*
Y1496621D03*
X1675306Y1491490D03*
Y1485598D03*
Y1496221D03*
Y1511576D03*
X1666645Y1511976D03*
Y1507245D03*
Y1502514D03*
X1675306Y1506845D03*
Y1500952D03*
Y1516307D03*
X1666645Y1558813D03*
Y1563544D03*
X1675306Y1563144D03*
Y1578498D03*
Y1572606D03*
X1666645Y1568275D03*
X1675306Y1567875D03*
X1666645Y1574167D03*
Y1578898D03*
Y1583629D03*
X1675306Y1583229D03*
X1666645Y1589522D03*
Y1594253D03*
X1675306Y1593853D03*
Y1587960D03*
X1666645Y1604876D03*
Y1598984D03*
X1675306Y1609207D03*
Y1598584D03*
Y1603315D03*
X1666645Y1609607D03*
Y1614338D03*
X1675306Y1613938D03*
Y1618669D03*
X1672000Y1644980D03*
X1685184Y60922D03*
X1680020Y55513D03*
X1683348Y113394D03*
X1685997Y110784D03*
X1686171Y130898D03*
X1693591Y133298D03*
X1687738Y134579D03*
X1683524Y172665D03*
Y180665D03*
X1683556Y200864D03*
Y212864D03*
Y221864D03*
Y216864D03*
X1685313Y252371D03*
X1687164Y336324D03*
X1678072Y342319D03*
X1691743Y353506D03*
X1680518Y385912D03*
Y393924D03*
Y389912D03*
Y409924D03*
Y405924D03*
Y401924D03*
X1677933Y418838D03*
X1689016Y1345691D03*
Y1350683D03*
X1684060D03*
Y1345691D03*
X1689016Y1362595D03*
Y1357603D03*
X1684060D03*
Y1362595D03*
X1689016Y1369889D03*
Y1381801D03*
Y1374881D03*
X1684060Y1369889D03*
Y1381801D03*
Y1374881D03*
X1689016Y1394087D03*
Y1399079D03*
Y1386793D03*
X1684060Y1394087D03*
Y1399079D03*
Y1386793D03*
X1689016Y1405999D03*
Y1410991D03*
X1684060Y1405999D03*
Y1410991D03*
X1683968Y1465913D03*
Y1456451D03*
Y1461182D03*
X1692629Y1465513D03*
Y1460782D03*
X1683968Y1471805D03*
Y1476536D03*
Y1481267D03*
X1692629Y1476136D03*
Y1470244D03*
Y1480867D03*
X1683968Y1487159D03*
Y1491890D03*
Y1496621D03*
X1692629Y1491490D03*
Y1485598D03*
Y1496221D03*
X1683968Y1502514D03*
Y1511976D03*
X1692629Y1506845D03*
Y1500952D03*
Y1511576D03*
X1683968Y1507245D03*
X1692629Y1516307D03*
X1683968Y1558813D03*
Y1563544D03*
X1692629Y1563144D03*
Y1572606D03*
X1683968Y1568275D03*
Y1574167D03*
Y1578898D03*
X1692629Y1567875D03*
Y1578498D03*
X1683968Y1583629D03*
Y1589522D03*
Y1594253D03*
X1692629Y1583229D03*
Y1593853D03*
Y1587960D03*
X1683968Y1598984D03*
X1692629Y1609207D03*
Y1598584D03*
Y1603315D03*
X1683968Y1609607D03*
Y1604876D03*
Y1614338D03*
X1692629Y1613938D03*
Y1618669D03*
X1692000Y1644980D03*
X1698583Y109172D03*
X1701583D03*
X1700590Y106495D03*
X1709134Y116497D03*
X1704334D03*
X1709134Y123584D03*
Y130670D03*
X1704334Y123584D03*
Y130670D03*
X1700324Y146012D03*
X1702230Y141228D03*
X1709134Y137757D03*
X1704334D03*
X1705118Y150847D03*
X1707086Y247292D03*
X1699795Y253198D03*
X1701495Y289735D03*
X1695142Y303839D03*
X1708889Y1189221D03*
X1696300Y1350683D03*
Y1345691D03*
X1701256Y1350683D03*
Y1345691D03*
X1708540D03*
Y1350683D03*
X1696300Y1357603D03*
Y1362595D03*
X1701256Y1357603D03*
Y1362595D03*
X1708540D03*
Y1357603D03*
X1696300Y1374881D03*
Y1369889D03*
Y1381801D03*
X1701256Y1369889D03*
Y1381801D03*
Y1374881D03*
X1708540D03*
Y1369889D03*
Y1381801D03*
X1696300Y1386793D03*
Y1394087D03*
Y1399079D03*
X1701256Y1386793D03*
Y1394087D03*
Y1399079D03*
X1708540D03*
Y1394087D03*
Y1386793D03*
X1696300Y1405999D03*
Y1410991D03*
X1701256Y1405999D03*
Y1410991D03*
X1708540Y1405999D03*
Y1410991D03*
X1701290Y1465913D03*
Y1456451D03*
Y1461182D03*
Y1471805D03*
Y1476536D03*
Y1481267D03*
Y1487159D03*
Y1491890D03*
Y1496621D03*
Y1507245D03*
Y1502514D03*
Y1511976D03*
Y1558813D03*
Y1563544D03*
Y1568275D03*
Y1574167D03*
Y1578898D03*
Y1583629D03*
Y1589522D03*
Y1594253D03*
Y1609607D03*
Y1604876D03*
Y1598984D03*
Y1614338D03*
X1724796Y82984D03*
Y77784D03*
Y80384D03*
Y75184D03*
Y85584D03*
X1716334Y116496D03*
Y109410D03*
Y102323D03*
X1711634Y116497D03*
Y109410D03*
X1716334Y130670D03*
Y123583D03*
X1711634D03*
Y130670D03*
X1716334Y137756D03*
X1720960Y1148000D03*
X1723796Y1160168D03*
X1725660Y1193019D03*
X1721660D03*
X1711783Y1193848D03*
X1713496Y1350683D03*
Y1345691D03*
X1720780Y1350683D03*
Y1345597D03*
X1725736Y1350683D03*
Y1345597D03*
X1713496Y1357603D03*
Y1362595D03*
X1720780Y1357603D03*
Y1362595D03*
X1725736Y1357603D03*
Y1362595D03*
X1713496Y1374881D03*
Y1369889D03*
Y1381801D03*
X1720780Y1369889D03*
Y1381801D03*
Y1374881D03*
X1725736Y1381801D03*
Y1374881D03*
Y1369889D03*
X1713496Y1399079D03*
Y1394087D03*
Y1386793D03*
X1720780D03*
Y1393993D03*
Y1399079D03*
X1725736Y1386793D03*
Y1399079D03*
Y1393993D03*
X1713496Y1405999D03*
Y1410991D03*
X1720780Y1405999D03*
Y1410991D03*
X1725736Y1405999D03*
Y1410991D03*
X1709952Y1465513D03*
Y1460782D03*
X1718613Y1465914D03*
Y1456452D03*
Y1461183D03*
Y1476537D03*
Y1471806D03*
Y1481268D03*
X1709952Y1476136D03*
Y1470244D03*
Y1480867D03*
Y1491490D03*
Y1485598D03*
Y1496221D03*
X1718613Y1491891D03*
Y1487160D03*
Y1496622D03*
Y1502515D03*
Y1511977D03*
X1709952Y1506845D03*
Y1500952D03*
Y1511576D03*
X1718613Y1507246D03*
X1709952Y1516307D03*
Y1563144D03*
X1718613Y1563544D03*
Y1558813D03*
X1709952Y1567875D03*
X1718613Y1568275D03*
X1709952Y1578498D03*
Y1572606D03*
X1718613Y1578898D03*
Y1574167D03*
Y1589522D03*
X1709952Y1583229D03*
X1718613Y1583629D03*
X1709952Y1593853D03*
Y1587960D03*
X1718613Y1594253D03*
Y1609607D03*
Y1598984D03*
Y1604876D03*
X1709952Y1609207D03*
Y1598584D03*
Y1603315D03*
Y1618669D03*
X1718613Y1614338D03*
X1709952Y1613938D03*
X1712000Y1644980D03*
X1727350Y92849D03*
X1734310Y103037D03*
X1734444Y116496D03*
Y109410D03*
Y130670D03*
Y123583D03*
X1730647Y137756D03*
X1739125Y293796D03*
X1736625D03*
X1737703Y472189D03*
X1728038Y491870D03*
X1730538D03*
X1730675Y1132361D03*
X1726963Y1132319D03*
X1739917Y1146937D03*
X1729207Y1159455D03*
X1737393Y1162817D03*
X1733660Y1193019D03*
X1729660D03*
X1737660D03*
X1733695Y1212164D03*
X1735989Y1214458D03*
X1731619Y1210089D03*
X1740785Y1219254D03*
X1737976Y1350683D03*
Y1345691D03*
X1733020D03*
Y1350683D03*
X1737976Y1362595D03*
Y1357603D03*
X1733020Y1362595D03*
Y1357603D03*
X1737976Y1369889D03*
Y1374881D03*
X1733020Y1369889D03*
Y1381801D03*
Y1374881D03*
X1737976Y1381801D03*
Y1399079D03*
Y1394087D03*
Y1386793D03*
X1733020Y1399079D03*
Y1394087D03*
Y1386793D03*
X1737976Y1405999D03*
Y1410991D03*
X1733020Y1405999D03*
Y1410991D03*
X1732000Y1644980D03*
X1755727Y94017D03*
X1747727D03*
X1751727D03*
X1751855Y110445D03*
Y115401D03*
X1756847D03*
Y110445D03*
X1751855Y129574D03*
Y124618D03*
X1756847D03*
Y129574D03*
X1753418Y191941D03*
X1753285Y188727D03*
X1747242Y226141D03*
X1750042D03*
X1755112Y256535D03*
X1749939Y288190D03*
X1747139D03*
X1744639D03*
X1749939Y285690D03*
X1744639D03*
X1747139D03*
X1758165Y290755D03*
X1754165D03*
X1744524Y370010D03*
X1753474Y542699D03*
X1757402Y825111D03*
Y820155D03*
X1744937Y912517D03*
X1747937D03*
X1750751Y910785D03*
X1748081Y984379D03*
X1756192Y996132D03*
X1743224Y1119055D03*
X1752000Y1644980D03*
X1764804Y84140D03*
Y76140D03*
Y80140D03*
X1759736Y94017D03*
X1767249Y117557D03*
X1762257D03*
Y122513D03*
Y131731D03*
X1767249Y122513D03*
Y131731D03*
X1762257Y136687D03*
X1767249D03*
X1765950Y180572D03*
X1770633Y180527D03*
X1774356Y192421D03*
X1759918Y184619D03*
X1770588Y185121D03*
X1765950Y185165D03*
X1761898Y206760D03*
X1763112Y256535D03*
X1764142Y279208D03*
X1768246Y281307D03*
X1762165Y290755D03*
X1765497Y370899D03*
X1766204Y398949D03*
X1770778Y402642D03*
X1773278D03*
X1763704Y401949D03*
X1767953Y413611D03*
X1770453D03*
X1772953D03*
X1772893Y423944D03*
X1770393D03*
X1767893D03*
X1765093D03*
X1765153Y413611D03*
X1764912Y482382D03*
X1765006Y478382D03*
X1761953Y706827D03*
Y865160D03*
X1772599Y993053D03*
X1762898Y992883D03*
X1764744Y1101930D03*
Y1097879D03*
X1766899Y1121122D03*
X1769499D03*
X1772099D03*
X1774799D03*
X1766999Y1130822D03*
X1772199D03*
X1769599D03*
X1774339Y1437975D03*
X1774216Y1470165D03*
X1772000Y1644980D03*
X1788884Y59871D03*
X1782382Y55513D03*
X1778179Y117261D03*
X1785886Y172665D03*
Y180665D03*
X1785918Y200864D03*
Y212864D03*
Y216864D03*
Y221864D03*
X1790014Y468607D03*
X1784602Y564092D03*
X1782600Y874500D03*
X1774899Y1130822D03*
Y1139822D03*
X1777399D03*
Y1147822D03*
X1774899D03*
X1785961Y1224892D03*
X1791099Y1260421D03*
X1779868Y1446668D03*
X1786564Y1478858D03*
X1777131Y1604357D03*
X1791570Y74535D03*
X1793149Y662810D03*
X1798705Y718793D03*
X1805013Y1091877D03*
X1792847Y1099210D03*
X1799012Y1095893D03*
X1805013Y1096470D03*
X1792863Y1103246D03*
X1801147Y1208555D03*
X1802844Y1227695D03*
X1793976Y1440762D03*
X1807270Y1468535D03*
X1793879Y1472952D03*
X1792000Y1644980D03*
X1816322Y977215D03*
X1823074Y992833D03*
X1812296Y1075688D03*
X1809696Y1091832D03*
X1809651Y1096426D03*
X1823028Y1124289D03*
X1817728D03*
X1815128D03*
X1820328D03*
X1822928Y1114589D03*
X1820228D03*
X1815028D03*
X1817628D03*
X1815865Y1133356D03*
X1809897Y1237285D03*
Y1230385D03*
Y1232885D03*
Y1239785D03*
Y1244185D03*
Y1246685D03*
X1807393Y1436345D03*
X1812000Y1644980D03*
X1831511Y978888D03*
X1831914Y992877D03*
X1824706Y1081145D03*
Y1089145D03*
X1837933Y1636171D03*
X1832000Y1644980D03*
G54D33*
X141337Y1228542D03*
X141336Y1247242D03*
Y1239762D03*
X161909Y1129429D03*
X160039Y1228543D03*
X169389Y1121948D03*
X167519Y1198621D03*
Y1213582D03*
X174999Y1228543D03*
X182480D03*
X167519D03*
X189960D03*
X197440D03*
X210531Y1211712D03*
X212401Y1228543D03*
X204921D03*
X213969Y1453293D03*
Y1464293D03*
X218011Y1211712D03*
X227362Y1228543D03*
X219881D03*
X227249Y1464293D03*
Y1453293D03*
X242322Y1250984D03*
X234842D03*
Y1254724D03*
X242322D03*
X249803Y1250984D03*
X257283D03*
Y1254724D03*
X249803D03*
X264763D03*
Y1250984D03*
X272244Y1254724D03*
Y1250984D03*
X279724D03*
Y1254724D03*
X294685Y1127558D03*
Y1135039D03*
Y1194881D03*
Y1202362D03*
X290944Y1191141D03*
X294685Y1209842D03*
X287204Y1254724D03*
Y1250984D03*
X302165Y1108858D03*
X298425Y1112598D03*
X309645D03*
Y1120078D03*
X305905Y1116338D03*
X298425Y1120078D03*
X305905Y1123818D03*
X309645Y1135039D03*
Y1127558D03*
X311515Y1136909D03*
X304035Y1140649D03*
X305905Y1131299D03*
X296555Y1151869D03*
X304035Y1155610D03*
Y1148129D03*
X296555Y1144389D03*
X311515D03*
Y1151869D03*
X296555Y1159350D03*
Y1166830D03*
X304035Y1170570D03*
X300295D03*
X311515Y1159350D03*
X300295Y1185531D03*
Y1178051D03*
X296555Y1174310D03*
X298425Y1187401D03*
X304035Y1185531D03*
Y1178051D03*
Y1193011D03*
X302165Y1198621D03*
X305905Y1206102D03*
X302165Y1213582D03*
Y1206102D03*
X298425Y1221062D03*
Y1217322D03*
X313385Y1105117D03*
X317125Y1116338D03*
Y1123818D03*
X313385D03*
Y1116338D03*
X315255Y1136909D03*
X313384Y1131299D03*
X315255Y1144389D03*
Y1151869D03*
Y1159350D03*
Y1166830D03*
Y1181791D03*
Y1189271D03*
Y1174310D03*
X313385Y1198621D03*
Y1206102D03*
X320866Y1217322D03*
X317125Y1221062D03*
X313385Y1213582D03*
X324606Y1209842D03*
Y1217322D03*
X320866Y1221062D03*
X324606D03*
X320866Y1236023D03*
Y1224803D03*
X324606Y1232283D03*
Y1236023D03*
Y1224803D03*
Y1243503D03*
X598424Y1228542D03*
X598423Y1239762D03*
Y1247242D03*
X618996Y1129429D03*
X617126Y1228543D03*
X626476Y1121948D03*
X624606Y1198621D03*
Y1213582D03*
X632086Y1228543D03*
X624606D03*
X639567D03*
X647047D03*
X667618Y1211712D03*
X654527Y1228543D03*
X662008D03*
X669488D03*
X675098Y1211712D03*
X676968Y1228543D03*
X684449D03*
X699409Y1254724D03*
X691929Y1250984D03*
Y1254724D03*
X699409Y1250984D03*
X706890D03*
X714370Y1254724D03*
Y1250984D03*
X706890Y1254724D03*
X729331Y1250984D03*
X721850D03*
Y1254724D03*
X729331D03*
X748031Y1194881D03*
X744291Y1254724D03*
Y1250984D03*
X736811Y1254724D03*
Y1250984D03*
X762992Y1116338D03*
X766732Y1120078D03*
X762992Y1123818D03*
X766732Y1112598D03*
X759252Y1108858D03*
X755512Y1120078D03*
X761122Y1140649D03*
X762992Y1131299D03*
X766732Y1135039D03*
Y1127558D03*
X751772D03*
Y1135039D03*
X753642Y1144389D03*
X761122Y1148129D03*
Y1155610D03*
X753642Y1151869D03*
X757382Y1170570D03*
X761122D03*
X753642Y1166830D03*
Y1159350D03*
Y1181791D03*
Y1174310D03*
X757382Y1178051D03*
Y1185531D03*
X761122Y1178051D03*
Y1185531D03*
X753642Y1189271D03*
X759252Y1191141D03*
X762992D03*
X755512Y1194881D03*
X759252Y1198621D03*
X751772Y1202362D03*
X755512Y1221062D03*
Y1217322D03*
X759252Y1213582D03*
X762992Y1206102D03*
X759252D03*
X751772Y1209842D03*
X770472Y1105117D03*
Y1123818D03*
X774212D03*
X770472Y1116338D03*
X774212D03*
X770471Y1131299D03*
X770472Y1138779D03*
X772342Y1151869D03*
Y1144389D03*
X768602Y1151869D03*
Y1144389D03*
X772342Y1166830D03*
X768602Y1159350D03*
X772342D03*
Y1174310D03*
Y1181791D03*
Y1196751D03*
X770472Y1198621D03*
X781693Y1217322D03*
X777953D03*
X774212Y1221062D03*
X781693Y1209842D03*
X770472Y1213582D03*
Y1206102D03*
X777953Y1221062D03*
X781693D03*
Y1224803D03*
X777953D03*
X781693Y1232283D03*
X777953Y1236023D03*
X781693D03*
Y1243503D03*
X1055510Y1228542D03*
X1055509Y1239762D03*
Y1247242D03*
X1074212Y1228543D03*
X1083562Y1121948D03*
X1076082Y1129429D03*
X1081692Y1198621D03*
Y1213582D03*
Y1228543D03*
X1089172D03*
X1104133D03*
X1096653D03*
X1124704Y1211712D03*
X1119094Y1228543D03*
X1111613D03*
X1132184Y1211712D03*
X1126574Y1228543D03*
X1134054D03*
X1141535D03*
X1149015Y1254724D03*
X1156495D03*
X1149015Y1250984D03*
X1156495D03*
X1171456D03*
X1163976D03*
X1171456Y1254724D03*
X1163976D03*
X1178936D03*
Y1250984D03*
X1186417D03*
Y1254724D03*
X1203247Y1193011D03*
X1201377Y1250984D03*
X1193897D03*
X1201377Y1254724D03*
X1193897D03*
X1216338Y1108858D03*
X1212598Y1120078D03*
X1220078Y1116338D03*
Y1123818D03*
X1218208Y1140649D03*
X1208858Y1127558D03*
X1220078Y1131299D03*
X1208858Y1135039D03*
X1210728Y1151869D03*
X1218208Y1155610D03*
Y1148129D03*
X1210728Y1144389D03*
Y1159350D03*
Y1166830D03*
X1218208Y1170570D03*
X1214468D03*
X1210728Y1181791D03*
Y1189271D03*
X1218208Y1185531D03*
Y1178051D03*
X1214468Y1185531D03*
Y1178051D03*
X1210728Y1174310D03*
X1212598Y1194881D03*
X1218208Y1193011D03*
X1214468D03*
X1216338Y1198621D03*
X1208858Y1202362D03*
X1220078Y1206102D03*
X1216338D03*
X1212598Y1221062D03*
Y1217322D03*
X1216338Y1213582D03*
X1208858Y1209842D03*
X1227558Y1105117D03*
X1223818Y1112598D03*
Y1120078D03*
X1227558Y1116338D03*
X1231298D03*
X1227558Y1123818D03*
X1231298D03*
X1229428Y1136909D03*
X1223818Y1127558D03*
X1227557Y1131299D03*
X1223818Y1135039D03*
X1225688Y1144389D03*
Y1151869D03*
X1229428Y1144389D03*
Y1151869D03*
Y1159350D03*
X1225688D03*
X1229428Y1166830D03*
Y1181791D03*
Y1189271D03*
Y1174310D03*
Y1196751D03*
X1227558Y1198621D03*
Y1206102D03*
X1235039Y1217322D03*
X1231298Y1221062D03*
X1227558Y1213582D03*
X1235039Y1221062D03*
Y1224803D03*
Y1236023D03*
X1238779Y1217322D03*
Y1209842D03*
Y1221062D03*
Y1224803D03*
Y1232283D03*
Y1236023D03*
Y1243503D03*
X1514468Y1166829D03*
Y1174309D03*
Y1181790D03*
X1512597Y1228542D03*
X1512596Y1239762D03*
Y1247242D03*
X1540649Y1121948D03*
X1533169Y1129429D03*
X1538779Y1198621D03*
Y1213582D03*
X1531299Y1228543D03*
X1538779D03*
X1546259D03*
X1561220D03*
X1553740D03*
X1576181D03*
X1568700D03*
X1589271Y1211712D03*
X1581791D03*
X1583661Y1228543D03*
X1591141D03*
X1598622D03*
X1606102Y1250984D03*
Y1254724D03*
X1621063D03*
X1613582Y1250984D03*
Y1254724D03*
X1621063Y1250984D03*
X1636023Y1254724D03*
Y1250984D03*
X1643504D03*
X1628543D03*
Y1254724D03*
X1643504D03*
X1660334Y1204232D03*
Y1200491D03*
Y1193011D03*
Y1196751D03*
Y1207972D03*
X1650984Y1250984D03*
Y1254724D03*
X1658464D03*
Y1250984D03*
X1673425Y1108858D03*
X1669685Y1112598D03*
Y1120078D03*
X1675295Y1140649D03*
X1665945Y1127558D03*
Y1135039D03*
X1667815Y1151869D03*
X1675295Y1155610D03*
Y1148129D03*
X1667815Y1144389D03*
Y1159350D03*
Y1166830D03*
X1675295Y1170570D03*
X1671555D03*
Y1185531D03*
Y1178051D03*
X1667815Y1174310D03*
Y1181791D03*
Y1189271D03*
X1675295Y1185531D03*
Y1178051D03*
X1669685Y1194881D03*
X1675295Y1193011D03*
X1671555D03*
X1665945Y1202362D03*
X1673425Y1198621D03*
X1669685Y1221062D03*
Y1217322D03*
X1673425Y1213582D03*
X1665945Y1209842D03*
X1673425Y1206102D03*
X1684645Y1105117D03*
X1677165Y1116338D03*
X1680905Y1112598D03*
X1677165Y1123818D03*
X1680905Y1120078D03*
X1684645Y1116338D03*
X1688385D03*
X1684645Y1123818D03*
X1688385D03*
X1686515Y1136909D03*
X1682775D03*
X1680905Y1127558D03*
X1677165Y1131299D03*
X1684644D03*
X1680905Y1135039D03*
X1682775Y1144389D03*
Y1151869D03*
X1686515Y1144389D03*
Y1151869D03*
Y1159350D03*
X1682775D03*
X1686515Y1166830D03*
Y1174310D03*
Y1181791D03*
Y1189271D03*
X1684645Y1198621D03*
X1692126Y1217322D03*
X1688385Y1221062D03*
X1684645Y1213582D03*
Y1206102D03*
X1677165D03*
X1692126Y1221062D03*
Y1224803D03*
Y1236023D03*
X1695866Y1217322D03*
Y1209842D03*
Y1221062D03*
Y1232283D03*
Y1236023D03*
Y1224803D03*
Y1243503D03*
G54D26*
X73872Y1348187D03*
X81752D03*
X73872Y1360099D03*
X81752D03*
X73872Y1384297D03*
Y1372385D03*
X81752Y1384297D03*
Y1372385D03*
X86112Y1348187D03*
X98352D03*
X93992D03*
X86112Y1360099D03*
X98352D03*
X93992D03*
X86112Y1384297D03*
Y1372385D03*
X98352Y1384297D03*
Y1372385D03*
X93992D03*
Y1384297D03*
X86112Y1396583D03*
X93992D03*
X98352D03*
X86112Y1408495D03*
X93992D03*
X98352D03*
X110592Y1348187D03*
X106232D03*
X110592Y1360099D03*
X106232D03*
X110592Y1384297D03*
X106232D03*
Y1372385D03*
X110592D03*
Y1396583D03*
X106232D03*
X110592Y1408495D03*
X106232D03*
X118472Y1348187D03*
X122832D03*
X130712D03*
X118472Y1360099D03*
X122832D03*
X130712D03*
X118472Y1384297D03*
Y1372385D03*
X122832Y1384297D03*
Y1372385D03*
X130712Y1384297D03*
Y1372385D03*
X118472Y1396583D03*
X122832D03*
X130712D03*
X118472Y1408495D03*
X122832D03*
X130712D03*
X146948Y1080806D03*
Y1103247D03*
X143208D03*
X146948Y1133169D03*
Y1140649D03*
X139468Y1136909D03*
X143208Y1125688D03*
Y1133169D03*
Y1140649D03*
X146948Y1125688D03*
X143208Y1144389D03*
Y1151870D03*
X146948Y1144389D03*
Y1151870D03*
X140707Y1170569D03*
X143208Y1159350D03*
X146948D03*
X148818Y1183661D03*
X140707Y1178050D03*
X145078Y1187401D03*
Y1183661D03*
X148818Y1187401D03*
X146947Y1174310D03*
X141337Y1191142D03*
X145078Y1194881D03*
Y1202362D03*
X148818Y1194881D03*
Y1202362D03*
X141337Y1198622D03*
X145078Y1198621D03*
Y1191141D03*
X148818D03*
Y1198621D03*
X145078Y1221062D03*
X148818D03*
X141337Y1206103D03*
X145078Y1209842D03*
Y1217322D03*
X148818Y1209842D03*
Y1217322D03*
X141337Y1213583D03*
Y1221063D03*
X148818Y1213582D03*
X145078D03*
Y1206102D03*
X148818D03*
Y1224803D03*
X145078Y1232283D03*
Y1236023D03*
X148818Y1232283D03*
Y1236023D03*
X145078Y1224803D03*
X148818Y1247243D03*
X145078D03*
X148818Y1254724D03*
Y1239763D03*
X145078D03*
X135072Y1348187D03*
X142952D03*
X147312D03*
X135072Y1360099D03*
X147312D03*
X142952D03*
X135072Y1384297D03*
Y1372385D03*
X147312Y1384297D03*
Y1372385D03*
X142952Y1384297D03*
Y1372385D03*
X135072Y1396583D03*
X147312D03*
X142952D03*
X135072Y1408495D03*
X147312D03*
X142952D03*
X150688Y1077066D03*
X158169Y1106988D03*
X165649D03*
X161909D03*
X158169Y1118208D03*
Y1121948D03*
X154429D03*
X150689D03*
X165649Y1114468D03*
X161909D03*
X158169Y1133169D03*
X161909Y1140649D03*
X158169Y1125688D03*
X154429Y1129429D03*
X150689D03*
Y1136909D03*
X154429Y1140649D03*
X150689D03*
X165649D03*
Y1129429D03*
Y1136909D03*
X158169Y1140649D03*
X150689Y1151870D03*
X158169Y1155610D03*
X154429D03*
X150689D03*
X161909Y1144389D03*
Y1148129D03*
Y1151870D03*
Y1155610D03*
X150689Y1144389D03*
Y1148129D03*
Y1159350D03*
X158169Y1166830D03*
X150688D03*
X154429Y1170570D03*
X150688D03*
X161909Y1159350D03*
X160039Y1187401D03*
X156299Y1183661D03*
X152559D03*
X161909Y1174310D03*
Y1178051D03*
X165649Y1181791D03*
X161909D03*
X158169Y1174310D03*
X154429D03*
X150688Y1178051D03*
Y1174310D03*
X156299Y1179921D03*
X160039Y1183661D03*
X163779D03*
X156299Y1187401D03*
X163779D03*
X152559D03*
X156299Y1198621D03*
X152559D03*
X163779D03*
X160039D03*
X152559Y1191141D03*
X156299D03*
X160039D03*
X163779D03*
X156299Y1202362D03*
Y1194881D03*
X152559Y1202362D03*
Y1194881D03*
X163779D03*
Y1202362D03*
X160039Y1206102D03*
X156299D03*
X152559D03*
X163779D03*
X156299Y1213582D03*
X152559D03*
X160039Y1221062D03*
X156299D03*
X152559D03*
X163779D03*
X156299Y1217322D03*
Y1209842D03*
X152559D03*
X163779D03*
Y1217322D03*
X152559D03*
Y1228543D03*
X160039Y1224803D03*
X152559D03*
X156299Y1232283D03*
Y1236023D03*
X163779D03*
Y1232283D03*
Y1224803D03*
X156299D03*
Y1228543D03*
X163779D03*
X152559Y1250984D03*
Y1254724D03*
X160039D03*
X156299Y1243503D03*
X160039Y1239763D03*
X152559D03*
Y1243503D03*
X160039D03*
X163779Y1239763D03*
X156299Y1247243D03*
X163779Y1243503D03*
X160039Y1250984D03*
X163779Y1247243D03*
X152559Y1258465D03*
X160039D03*
X159552Y1348187D03*
X155192D03*
X159552Y1360099D03*
X155192D03*
X159552Y1372385D03*
Y1384297D03*
X155192D03*
Y1372385D03*
X159552Y1396583D03*
X155192D03*
X159552Y1408495D03*
X155192D03*
X174998Y1071455D03*
X182479D03*
X178740Y1090157D03*
X174999D03*
X171259D03*
X182480D03*
X178740Y1093897D03*
Y1097637D03*
X174999Y1101377D03*
X169389Y1106988D03*
X171259Y1093897D03*
X174999Y1105117D03*
X182480Y1101377D03*
Y1105117D03*
X174999Y1108858D03*
X178740D03*
X176870Y1114468D03*
Y1118208D03*
Y1121948D03*
X178740Y1112598D03*
X173129Y1110728D03*
X169389D03*
X180610Y1114468D03*
Y1118208D03*
Y1121948D03*
X182480Y1112598D03*
Y1108858D03*
X180610Y1136909D03*
X173129Y1133169D03*
X169389D03*
X176870Y1140649D03*
Y1125688D03*
Y1129429D03*
Y1133169D03*
Y1136909D03*
X173129Y1140649D03*
X169389D03*
X180610D03*
Y1125688D03*
Y1129429D03*
Y1133169D03*
Y1148129D03*
X173129Y1144389D03*
X169389D03*
X173129Y1148129D03*
Y1155610D03*
Y1151870D03*
X180610Y1155610D03*
Y1151870D03*
Y1144389D03*
X176870Y1170570D03*
X173129Y1159350D03*
Y1166830D03*
Y1170570D03*
X180610Y1166830D03*
Y1159350D03*
Y1174310D03*
Y1181791D03*
X173129Y1174310D03*
Y1178051D03*
Y1181791D03*
X171259Y1187401D03*
X174999D03*
X180610Y1178051D03*
X167519Y1183661D03*
X178740Y1187401D03*
X182480D03*
X176870Y1185531D03*
X173129D03*
X167519Y1187401D03*
X171259Y1202362D03*
Y1194881D03*
X174999Y1202362D03*
Y1194881D03*
X167519Y1191141D03*
X178740D03*
Y1194881D03*
Y1198621D03*
Y1202362D03*
X182480Y1191141D03*
Y1198621D03*
Y1202362D03*
X174999Y1198621D03*
Y1191141D03*
X167519Y1194881D03*
X171259Y1198621D03*
Y1191141D03*
X167519Y1202362D03*
X171259Y1209842D03*
X174999Y1217322D03*
X171259Y1221062D03*
X174999D03*
X171259Y1217322D03*
X167519Y1206102D03*
X178740D03*
Y1209842D03*
Y1213582D03*
Y1221062D03*
X182480D03*
X178740Y1217322D03*
X182480Y1206102D03*
Y1209842D03*
Y1213582D03*
Y1217322D03*
X167519Y1209842D03*
X171259Y1213582D03*
Y1206102D03*
X174999D03*
X167519Y1217322D03*
X174999Y1213582D03*
X178740Y1228543D03*
X171259Y1224803D03*
Y1228543D03*
X178740Y1224803D03*
Y1232283D03*
Y1236023D03*
X171259Y1232283D03*
X174999Y1224803D03*
X171259Y1236023D03*
X182480Y1224803D03*
X167519D03*
Y1254724D03*
X182480Y1243503D03*
X171259Y1250984D03*
X174999Y1247243D03*
Y1239763D03*
X171259D03*
X167519D03*
Y1243503D03*
Y1250984D03*
X178740Y1247243D03*
X182480Y1254724D03*
Y1250984D03*
X171259Y1247243D03*
X174999Y1250984D03*
X171259Y1243503D03*
X174999Y1254724D03*
X178740Y1243503D03*
X175000Y1258465D03*
X182480D03*
X167519D03*
X167432Y1348187D03*
X171792D03*
X179672D03*
X167432Y1360099D03*
X171792D03*
X179672D03*
X167432Y1384297D03*
Y1372385D03*
X171792Y1384297D03*
Y1372385D03*
X179672Y1384297D03*
Y1372385D03*
X171792Y1396583D03*
X179672D03*
X167432D03*
Y1408495D03*
X171792D03*
X179672D03*
X197439Y1071455D03*
X189959D03*
X193700Y1090157D03*
X189960D03*
X186220D03*
X197440D03*
X193700Y1093897D03*
X189960Y1101377D03*
X186220Y1097637D03*
X189960Y1105117D03*
X186220Y1093897D03*
X193700Y1097637D03*
X197440Y1101377D03*
Y1105117D03*
X189960Y1093897D03*
X195570Y1121948D03*
X191830Y1118208D03*
X188090D03*
X184350D03*
X191830Y1121948D03*
X188090D03*
X184350D03*
X195570Y1118208D03*
X186220Y1108858D03*
X189960D03*
X193700D03*
X197440D03*
X191830Y1125688D03*
X188090D03*
X184350D03*
X188090Y1129429D03*
X184350D03*
X188090Y1133169D03*
X184350D03*
X188090Y1136909D03*
Y1140649D03*
X184350D03*
X195570Y1133169D03*
Y1129429D03*
Y1125688D03*
Y1136909D03*
X188090Y1144389D03*
Y1151870D03*
X191830Y1155610D03*
Y1148129D03*
X195570Y1151869D03*
Y1144389D03*
X188090Y1159350D03*
Y1170570D03*
X191830Y1166830D03*
X195570Y1159350D03*
Y1170570D03*
X188090Y1185531D03*
X195570Y1189271D03*
X191830Y1181791D03*
Y1174310D03*
X195570Y1185531D03*
Y1178051D03*
X188090Y1196751D03*
Y1200491D03*
Y1204232D03*
X191830D03*
Y1196751D03*
Y1200491D03*
X184350Y1193011D03*
Y1196751D03*
X195570Y1200491D03*
Y1196751D03*
Y1193011D03*
Y1204232D03*
X186220Y1198621D03*
X193700Y1209842D03*
X191830Y1207972D03*
X189960Y1209842D03*
X195570Y1207972D03*
X193700Y1213582D03*
X191830Y1219192D03*
X186220Y1221062D03*
X189960D03*
X193700D03*
X197440D03*
X186220Y1206102D03*
Y1209842D03*
Y1213582D03*
X197440Y1209842D03*
X186220Y1224803D03*
X193700Y1228543D03*
X197440Y1224803D03*
X193700Y1232283D03*
X186220D03*
X189960Y1224803D03*
X193700Y1236023D03*
X186220D03*
Y1228543D03*
X193700Y1224803D03*
X197440Y1239763D03*
Y1243503D03*
X193700Y1239763D03*
X186220D03*
X189960Y1243503D03*
X197440Y1254724D03*
Y1250984D03*
X193700Y1247243D03*
Y1243503D03*
X189960Y1254724D03*
Y1250984D03*
X186220Y1247243D03*
Y1243503D03*
X189960Y1258465D03*
X197441D03*
X184032Y1348187D03*
X191912D03*
X196272D03*
X184032Y1360099D03*
X196272D03*
X191912D03*
X184032Y1384297D03*
Y1372385D03*
X196272Y1384297D03*
Y1372385D03*
X191912Y1384297D03*
Y1372385D03*
X184032Y1396583D03*
X191912D03*
X196272D03*
X184032Y1408495D03*
X191912D03*
X196272D03*
X204920Y1071455D03*
X212400D03*
X204921Y1090157D03*
X212401D03*
X208661D03*
X201181D03*
X204921Y1101377D03*
X208661Y1097637D03*
X201181D03*
X204921Y1105117D03*
X212401Y1101377D03*
Y1105117D03*
X201181Y1093897D03*
X208661D03*
X199311Y1118208D03*
Y1121948D03*
X206791Y1118208D03*
X203051D03*
Y1121948D03*
X206791D03*
X210531Y1118208D03*
X214271Y1110728D03*
X210531Y1121948D03*
X214271Y1118208D03*
Y1121948D03*
X201181Y1108858D03*
X204921D03*
X208661D03*
X212401D03*
X199311Y1140649D03*
X203051D03*
X206791D03*
X199311Y1125688D03*
X203051D03*
X206791D03*
Y1133169D03*
X203051D03*
X199311D03*
X210531D03*
Y1140649D03*
X214271D03*
Y1125688D03*
X210531D03*
X214271Y1133169D03*
X203051Y1148129D03*
X199311D03*
X206791D03*
X214271D03*
X210531D03*
X199311Y1155610D03*
X206791D03*
X214271D03*
X206791Y1166830D03*
X203051Y1159350D03*
X199311Y1166830D03*
X203051Y1170570D03*
X214271Y1166830D03*
X210531Y1159350D03*
Y1170570D03*
X206791Y1181791D03*
X203051D03*
X199311D03*
X206791Y1189271D03*
X203051D03*
X199311D03*
X214271Y1181791D03*
X210531D03*
X214271Y1189271D03*
X210531D03*
X199311Y1174310D03*
X206791D03*
X214271D03*
X206791Y1196751D03*
X203051D03*
X199311D03*
Y1204232D03*
X203051D03*
X206791D03*
X214271Y1196751D03*
X210531D03*
Y1204232D03*
X214271D03*
X206791Y1207972D03*
X203051D03*
X199311D03*
X210531D03*
X214271D03*
X212401Y1221062D03*
X208661D03*
X204921D03*
X201181D03*
Y1224803D03*
X208661Y1228543D03*
X212401Y1224803D03*
X208661Y1232283D03*
X201181D03*
X204921Y1224803D03*
X201181Y1236023D03*
X208661D03*
Y1224803D03*
X201181Y1228543D03*
X212401Y1243503D03*
X208661Y1239763D03*
X204921Y1243503D03*
X208661D03*
X204921Y1250984D03*
X208661Y1247243D03*
X212401Y1254724D03*
X201181Y1243503D03*
X212401Y1250984D03*
X201181Y1247243D03*
X204921Y1254724D03*
X212401Y1258465D03*
X204921D03*
X204152Y1348187D03*
Y1360099D03*
Y1384297D03*
Y1372385D03*
Y1396583D03*
Y1408495D03*
X219880Y1071455D03*
X227361D03*
X227362Y1090157D03*
X223622D03*
X219881D03*
X231102D03*
X216141D03*
X223622Y1093897D03*
X231102D03*
Y1097637D03*
X227362Y1101377D03*
Y1105117D03*
X219881Y1101377D03*
Y1105117D03*
X223622Y1097637D03*
X216141D03*
Y1093897D03*
X225492Y1118208D03*
Y1121948D03*
X218011Y1118208D03*
X221751D03*
X218011Y1121948D03*
X221751D03*
X229232D03*
Y1118208D03*
Y1114468D03*
X216141Y1108858D03*
X219881D03*
X223622D03*
X227362D03*
X231102D03*
X225492Y1133169D03*
Y1140649D03*
Y1125688D03*
X218011Y1140649D03*
X221751D03*
X218011Y1125688D03*
X221751D03*
Y1133169D03*
X218011D03*
X229330Y1132677D03*
X229232Y1140649D03*
Y1125688D03*
X225492Y1148129D03*
X221751D03*
X218011D03*
X229232D03*
X221751Y1155610D03*
X229232D03*
X225492Y1170570D03*
Y1159350D03*
X218011Y1170570D03*
X221752Y1166830D03*
X218011Y1159350D03*
X229232Y1166830D03*
X225492Y1181791D03*
Y1189271D03*
X221751Y1181791D03*
X218011D03*
X221751Y1189271D03*
X218011D03*
X229232Y1181791D03*
Y1189271D03*
X221751Y1174310D03*
X229232D03*
X218011Y1204232D03*
X229232Y1196751D03*
Y1204232D03*
X225492Y1196751D03*
Y1204232D03*
X221751D03*
Y1196751D03*
X218011D03*
X225492Y1207972D03*
X221751D03*
X218011D03*
X229232D03*
X231102Y1221062D03*
X227362D03*
X219881Y1217322D03*
X223622Y1221062D03*
X219881D03*
X216141D03*
X231102Y1224803D03*
X227362D03*
X223622Y1232283D03*
X219881Y1224803D03*
X223622Y1236023D03*
X231102Y1232283D03*
Y1236023D03*
X216141Y1232283D03*
Y1236023D03*
Y1224803D03*
X223622D03*
Y1228543D03*
X216141D03*
X223622Y1239763D03*
X231102D03*
X227362Y1243503D03*
X219881D03*
X216141Y1239763D03*
X231102Y1243503D03*
Y1247243D03*
X223622Y1243503D03*
X216141Y1247243D03*
X223622D03*
X216141Y1243503D03*
X219881Y1250984D03*
Y1254724D03*
X227362D03*
Y1250984D03*
X219882Y1258465D03*
X227363D03*
X246062Y1075196D03*
X234841Y1071454D03*
X242321Y1071455D03*
X238582Y1075196D03*
X234841Y1075195D03*
X242321Y1075196D03*
X234842Y1090157D03*
X246062D03*
Y1078936D03*
X238582Y1090157D03*
X242322Y1086417D03*
X234842Y1082677D03*
Y1086417D03*
X242322Y1090157D03*
X242321Y1078936D03*
X246061Y1082677D03*
X238581Y1082676D03*
X234841Y1078935D03*
X246061Y1086417D03*
X238581Y1086416D03*
X246062Y1097637D03*
Y1093897D03*
X242322Y1105117D03*
X234842Y1101377D03*
X238582Y1093897D03*
X242322Y1101377D03*
X234842Y1105117D03*
X236712Y1121948D03*
X240452D03*
X244192D03*
X234842Y1108858D03*
X238582D03*
X242322D03*
X246062D03*
X236712Y1133464D03*
X240452Y1133169D03*
X236712Y1140649D03*
X240452D03*
X236712Y1125688D03*
X240452D03*
X244192Y1133169D03*
Y1140649D03*
Y1125688D03*
X236712Y1148129D03*
X240452D03*
X244192D03*
X240452Y1155610D03*
Y1166830D03*
X236712Y1170570D03*
Y1159350D03*
X244192Y1170570D03*
Y1159350D03*
X240452Y1181791D03*
X236712D03*
Y1189271D03*
X240452D03*
X244192Y1181791D03*
Y1189271D03*
X240452Y1174310D03*
Y1204232D03*
X236712D03*
Y1196751D03*
X240452D03*
X244192Y1204232D03*
Y1196751D03*
X240452Y1207972D03*
Y1211712D03*
X242322Y1221062D03*
X244192Y1211712D03*
Y1207972D03*
X236712D03*
X234842Y1221062D03*
X238582D03*
X246062Y1232283D03*
Y1236023D03*
X238582Y1232283D03*
X234842Y1228543D03*
Y1224803D03*
X238582Y1236023D03*
X242322Y1228543D03*
Y1224803D03*
X246062Y1239763D03*
X238582D03*
Y1247243D03*
X246062Y1243503D03*
Y1247243D03*
X238582Y1243503D03*
X234842Y1258465D03*
X242322D03*
X239383Y1348187D03*
X247263D03*
Y1360099D03*
X239383D03*
X247263Y1384297D03*
Y1372385D03*
X239383Y1384297D03*
Y1372385D03*
X253543Y1075196D03*
X261023D03*
X249802Y1071455D03*
X257282D03*
X249802Y1075196D03*
X257282D03*
X253543Y1090157D03*
X249803D03*
Y1086417D03*
X253543Y1078936D03*
X257283Y1090157D03*
Y1086417D03*
X261023Y1090157D03*
Y1078936D03*
X249802D03*
X261022Y1086417D03*
X253542Y1082676D03*
X257282Y1078936D03*
X253542Y1086416D03*
X261022Y1082677D03*
X249803Y1105117D03*
X253543Y1093897D03*
Y1097637D03*
X257283Y1105117D03*
X261023Y1093897D03*
Y1097637D03*
X249802D03*
X257282D03*
X249802Y1093897D03*
X257282D03*
X255413Y1121948D03*
X251673D03*
X247933D03*
X262893D03*
X259153D03*
X249803Y1108858D03*
X253543D03*
X257283D03*
X261023D03*
X247933Y1133169D03*
X251673D03*
X255413D03*
X247933Y1140649D03*
X251673D03*
X255413D03*
X247933Y1125688D03*
X251673D03*
X255413D03*
X259153Y1133169D03*
X262893D03*
Y1140649D03*
X259153Y1125688D03*
X262893D03*
X259153Y1140649D03*
Y1148129D03*
X262893D03*
Y1155610D03*
X247933Y1148129D03*
X251673D03*
X255413D03*
X247933Y1155610D03*
X255413D03*
X262893Y1166830D03*
X251673Y1170570D03*
X255413Y1166830D03*
X247933D03*
X251673Y1159350D03*
X259153D03*
Y1170570D03*
X247933Y1181791D03*
X251673D03*
X255413D03*
X247933Y1189271D03*
X251673D03*
X255413D03*
X262893D03*
Y1174310D03*
X259153Y1181791D03*
X262893D03*
X259153Y1189271D03*
X255413Y1174310D03*
X247933D03*
Y1204232D03*
X255413D03*
X251673D03*
X247933Y1196751D03*
X251673D03*
X255413D03*
X259153Y1204232D03*
X262893D03*
X259153Y1196751D03*
X262893D03*
X247933Y1207972D03*
X251673D03*
X255413Y1211712D03*
Y1207972D03*
X262893D03*
X259153D03*
X262893Y1211712D03*
X259153D03*
X249803Y1228543D03*
X257283D03*
X249803Y1224803D03*
X253543Y1236023D03*
X257283Y1224803D03*
X261023Y1236023D03*
X253543Y1232283D03*
X261023D03*
X257283Y1239763D03*
X261023Y1243503D03*
Y1247243D03*
X253543D03*
Y1243503D03*
X249803Y1258465D03*
X257283D03*
X263863Y1348187D03*
X259503D03*
X251623D03*
X263863Y1360099D03*
X259503D03*
X251623D03*
X263863Y1384297D03*
Y1372385D03*
X259503Y1384297D03*
Y1372385D03*
X251623D03*
Y1384297D03*
X263863Y1396583D03*
X259503D03*
X251623D03*
X263863Y1408495D03*
X259503D03*
X251623D03*
X279723Y1071455D03*
X264762D03*
X272243D03*
X268503Y1075196D03*
X275984D03*
X279723D03*
X264762D03*
X272243D03*
X279724Y1090157D03*
X272244Y1082677D03*
X275984Y1090157D03*
X272244Y1086417D03*
X268503Y1078936D03*
Y1090157D03*
X264763Y1086417D03*
X272244Y1090157D03*
X264763D03*
X275982Y1082677D03*
Y1086417D03*
X268502Y1082676D03*
X272243Y1078936D03*
X268502Y1086416D03*
X279723Y1078936D03*
X264762D03*
X268503Y1093897D03*
Y1097637D03*
X272244Y1105117D03*
X279724D03*
X275984Y1093897D03*
X264763Y1105117D03*
X274114Y1118208D03*
X270373D03*
X266633Y1121948D03*
X270373D03*
X277854Y1118208D03*
X264763Y1108858D03*
X268503D03*
X272244D03*
X275984D03*
X279724D03*
X274114Y1125688D03*
X270373Y1136909D03*
X266633Y1133169D03*
X270373D03*
X266633Y1140649D03*
X270373Y1125688D03*
Y1129429D03*
X266633Y1125688D03*
X270373Y1140649D03*
X277854Y1136909D03*
Y1140649D03*
X274114Y1155610D03*
Y1151869D03*
Y1148129D03*
X266633D03*
X270373Y1144389D03*
Y1148129D03*
Y1151869D03*
X277854Y1144389D03*
Y1148129D03*
Y1151870D03*
X270373Y1155610D03*
X274114Y1166830D03*
Y1159350D03*
Y1170570D03*
X266633Y1181791D03*
X270373Y1189271D03*
X277854Y1178051D03*
Y1189271D03*
Y1185531D03*
X270373Y1174310D03*
X277854Y1181791D03*
X274114D03*
Y1174310D03*
X266633Y1189271D03*
X270373Y1178051D03*
Y1185531D03*
X274114Y1196751D03*
X270393Y1196732D03*
X270373Y1204232D03*
X266633D03*
X270373Y1200491D03*
X266633Y1196751D03*
X270373Y1193011D03*
X277854D03*
X274114Y1207972D03*
X270373Y1211712D03*
X266633Y1207972D03*
Y1211712D03*
X270373Y1207972D03*
X277854Y1211712D03*
X279724Y1221062D03*
X275984D03*
X272244D03*
X268503D03*
X279724Y1224803D03*
X272244D03*
X268503Y1236023D03*
Y1232283D03*
X272244Y1228543D03*
X264763Y1224803D03*
X275984Y1232283D03*
Y1236023D03*
X264763Y1228543D03*
X279724D03*
X268503Y1243503D03*
Y1247243D03*
X275984Y1243503D03*
Y1247243D03*
X268503Y1239763D03*
X279724Y1258465D03*
X264763D03*
X272244D03*
X276103Y1348187D03*
X271743D03*
X276103Y1360099D03*
X271743D03*
X276103Y1384297D03*
Y1372385D03*
X271743Y1384297D03*
Y1372385D03*
X276103Y1396583D03*
X271743D03*
Y1408495D03*
X276103D03*
X294684Y1071455D03*
X290944Y1075196D03*
X287203Y1071455D03*
X283464Y1075196D03*
X287203D03*
X294684D03*
X287204Y1090157D03*
X283464Y1078936D03*
Y1090157D03*
X290943D03*
Y1086417D03*
X287203Y1078936D03*
X290943Y1082677D03*
X283463Y1082676D03*
Y1086416D03*
X294684Y1078936D03*
X290944Y1093897D03*
X287204Y1101377D03*
Y1105117D03*
X294685D03*
X294684Y1120078D03*
Y1112598D03*
X283464Y1108858D03*
X287204D03*
X290944D03*
X294685D03*
X290944Y1112598D03*
Y1116338D03*
Y1120078D03*
Y1123818D03*
X281594Y1140649D03*
Y1136909D03*
X290944Y1127558D03*
Y1131299D03*
Y1135039D03*
Y1138779D03*
X281594Y1148129D03*
Y1155610D03*
Y1151869D03*
X285334D03*
X289074D03*
Y1155610D03*
X292814Y1151869D03*
Y1144389D03*
X281594Y1159350D03*
X289074Y1166830D03*
Y1170570D03*
Y1159350D03*
X281594Y1170570D03*
Y1166830D03*
X292814Y1159350D03*
Y1166830D03*
Y1181791D03*
X285334Y1185531D03*
X289074Y1174310D03*
Y1178051D03*
Y1185531D03*
X281594Y1189271D03*
Y1185531D03*
X285334Y1181791D03*
X281594Y1178051D03*
Y1174310D03*
X292814D03*
Y1189271D03*
X281594Y1196751D03*
Y1204232D03*
Y1193011D03*
X285334D03*
X290944Y1194881D03*
Y1198621D03*
Y1202362D03*
X294685Y1221062D03*
Y1217322D03*
X290944Y1221062D03*
X287204D03*
X283464D03*
X290944Y1206102D03*
Y1209842D03*
Y1213582D03*
Y1217322D03*
X294685Y1228543D03*
Y1224803D03*
X290944Y1232283D03*
Y1236023D03*
X283464Y1232283D03*
X287204Y1228543D03*
X283464Y1236023D03*
X287204Y1224803D03*
X283464Y1243503D03*
Y1239763D03*
X290944D03*
X283464Y1247243D03*
X294685Y1254724D03*
Y1250984D03*
X290944Y1247243D03*
Y1243503D03*
X294685Y1258465D03*
X287204D03*
X288343Y1348187D03*
X296223D03*
X283983D03*
X288343Y1360099D03*
X296223D03*
X283983D03*
X288343Y1384297D03*
Y1372385D03*
X296223Y1384297D03*
Y1372385D03*
X283983D03*
Y1384297D03*
X288343Y1396583D03*
X296223D03*
X283983D03*
X288343Y1408495D03*
X296223D03*
X283983D03*
X309645Y1071455D03*
X302165D03*
X298425Y1075196D03*
X305906D03*
X302164D03*
X309644D03*
X298424Y1090157D03*
X298426Y1078936D03*
X305906D03*
X305904Y1082677D03*
X302164Y1078936D03*
X305904Y1086417D03*
X309644Y1078936D03*
X298424Y1086416D03*
Y1082676D03*
X302165Y1105117D03*
X309645D03*
X298425Y1093897D03*
X305905D03*
X302165Y1123818D03*
X305904Y1108857D03*
X302165Y1116338D03*
X298425Y1108858D03*
X300295Y1140649D03*
X302165Y1131299D03*
X300295Y1148129D03*
Y1159350D03*
Y1166830D03*
X311515D03*
X307775Y1170570D03*
X300295Y1181791D03*
Y1174310D03*
Y1189271D03*
X311515Y1174310D03*
X307775Y1178051D03*
X311515Y1181791D03*
X307775Y1185531D03*
X311515Y1189271D03*
X298425Y1202362D03*
Y1194881D03*
X309645Y1198621D03*
X307775Y1193011D03*
X311515Y1196751D03*
X305905Y1198621D03*
X309645Y1202362D03*
X298425Y1209842D03*
X302165Y1221062D03*
X309645Y1217322D03*
Y1209842D03*
X305905Y1213582D03*
X309645D03*
Y1206102D03*
Y1221062D03*
X305905D03*
X298425Y1236023D03*
Y1232283D03*
X302165Y1228543D03*
Y1224803D03*
X305905Y1232283D03*
X309645Y1228543D03*
Y1224803D03*
X305905Y1236023D03*
X298425Y1239763D03*
X309645D03*
Y1254724D03*
X298425Y1247243D03*
X309645Y1250984D03*
X298425Y1243503D03*
X305905D03*
Y1247243D03*
X302165Y1254724D03*
Y1250984D03*
X309645Y1258465D03*
X302165D03*
X308463Y1348187D03*
X300583D03*
X308463Y1360099D03*
X300583D03*
X308463Y1372385D03*
X300583D03*
Y1384297D03*
X308463D03*
Y1396583D03*
X300583D03*
X308463Y1408495D03*
X300583D03*
X317125Y1071455D03*
X320866Y1075196D03*
X313386D03*
X317124D03*
X320866Y1078936D03*
X313384Y1090157D03*
X313386Y1078936D03*
X328347Y1082677D03*
Y1090158D03*
X324606Y1078936D03*
X317124D03*
X313384Y1082677D03*
Y1086417D03*
X313385Y1093897D03*
X328347Y1101378D03*
Y1116339D03*
Y1123819D03*
Y1108859D03*
X313385Y1108858D03*
X328347Y1131300D03*
X318996Y1140649D03*
Y1155610D03*
Y1148129D03*
X322736Y1170570D03*
X318996D03*
Y1185531D03*
Y1178051D03*
X322736D03*
Y1185531D03*
X328347Y1198621D03*
X322736Y1193011D03*
X320866Y1202362D03*
X318996Y1193011D03*
X326416D03*
X324606Y1202362D03*
X328347Y1206102D03*
Y1221062D03*
Y1213582D03*
X320866Y1209842D03*
X313385Y1221062D03*
X320866Y1206102D03*
Y1232283D03*
X313385D03*
X317125Y1228543D03*
Y1224803D03*
X313385Y1236023D03*
X328347Y1228543D03*
Y1239762D03*
Y1247243D03*
X324606Y1250984D03*
X317125Y1254724D03*
X324606Y1239763D03*
X313385Y1247243D03*
X317125Y1250984D03*
X320866Y1239763D03*
X313385Y1243503D03*
X317125Y1258465D03*
X320703Y1348187D03*
X312823D03*
X325063D03*
X320703Y1360099D03*
X312823D03*
X325063D03*
X320703Y1372385D03*
Y1384297D03*
X312823Y1372385D03*
Y1384297D03*
X325063Y1372385D03*
Y1384297D03*
Y1396583D03*
X320703D03*
X312823D03*
X320703Y1408495D03*
X312823D03*
X325063D03*
X318448Y1750941D03*
Y1760941D03*
X318348Y1796941D03*
Y1806941D03*
X337303Y1348187D03*
X332943D03*
Y1360099D03*
X337303D03*
X332943Y1384297D03*
Y1372385D03*
X337303D03*
Y1384297D03*
X332943Y1396583D03*
X337303D03*
X332943Y1408495D03*
X337303D03*
X349543Y1348187D03*
X357423D03*
X345183D03*
X349543Y1360099D03*
X357423D03*
X345183D03*
Y1372385D03*
Y1384297D03*
X349543D03*
Y1372385D03*
X357423D03*
Y1384297D03*
X345183Y1396583D03*
X349543D03*
X357423D03*
X345183Y1408495D03*
X349543D03*
X357423D03*
X369663Y1348187D03*
X361783D03*
X369663Y1360099D03*
X361783D03*
X369663Y1372385D03*
Y1384297D03*
X361783D03*
Y1372385D03*
X369663Y1396583D03*
X361783D03*
X369663Y1408495D03*
X361783D03*
X458282Y1348187D03*
X446042D03*
X458282Y1360099D03*
X446042D03*
X458282Y1372385D03*
X446042D03*
X458282Y1384297D03*
X446042D03*
X458282Y1396583D03*
Y1408495D03*
X470522Y1348187D03*
Y1360099D03*
Y1384297D03*
Y1372385D03*
Y1396583D03*
Y1408495D03*
X482762Y1348187D03*
Y1360099D03*
Y1384297D03*
Y1372385D03*
Y1396583D03*
Y1408495D03*
X507242Y1348187D03*
X495002D03*
X507242Y1360099D03*
X495002D03*
Y1384297D03*
X507242D03*
X495002Y1372385D03*
X507242D03*
Y1396583D03*
X495002D03*
X507242Y1408495D03*
X495002D03*
X519482Y1348187D03*
Y1360099D03*
Y1384297D03*
Y1372385D03*
Y1396583D03*
Y1408495D03*
X531722Y1348187D03*
Y1360099D03*
Y1384297D03*
Y1372385D03*
Y1396583D03*
Y1408495D03*
X556202Y1348187D03*
X543962D03*
X556202Y1360099D03*
X543962D03*
Y1372385D03*
Y1384297D03*
X556202D03*
Y1372385D03*
Y1396583D03*
X543962D03*
X556202Y1408495D03*
X543962D03*
X568442Y1348187D03*
Y1360099D03*
Y1384297D03*
Y1372385D03*
Y1396583D03*
Y1408495D03*
X604035Y1080806D03*
Y1103247D03*
X600295D03*
Y1125688D03*
Y1133169D03*
Y1140649D03*
X604035Y1125688D03*
Y1133169D03*
Y1140649D03*
X600295Y1144389D03*
Y1151870D03*
X604035Y1144389D03*
Y1151870D03*
X600295Y1159350D03*
X604035D03*
X597795Y1170570D03*
X604034Y1174310D03*
X597795Y1178050D03*
X602165Y1183661D03*
Y1187401D03*
Y1202362D03*
Y1194881D03*
X598424Y1198622D03*
Y1191142D03*
X602165Y1191141D03*
Y1198621D03*
Y1217322D03*
Y1209842D03*
X598424Y1221063D03*
Y1213583D03*
Y1206103D03*
X602165Y1221062D03*
Y1206102D03*
Y1213582D03*
Y1224803D03*
Y1236023D03*
Y1232283D03*
Y1247243D03*
Y1239763D03*
X605386Y1728583D03*
Y1738583D03*
X605312Y1774624D03*
Y1784624D03*
X607775Y1077066D03*
X615256Y1106988D03*
X618996D03*
X615256Y1118208D03*
Y1121948D03*
X611516D03*
X607776D03*
X618996Y1114468D03*
X615256Y1125688D03*
X611516Y1129429D03*
X607776D03*
Y1136909D03*
X615256Y1140649D03*
X611516D03*
X607776D03*
X618996D03*
Y1144389D03*
Y1148129D03*
Y1151870D03*
Y1155610D03*
X607776Y1144389D03*
Y1148129D03*
Y1151870D03*
X615256Y1155610D03*
X611516D03*
X607776D03*
Y1159350D03*
X615256Y1166830D03*
X607775D03*
X611516Y1170570D03*
X607775D03*
X618996Y1159350D03*
Y1174310D03*
Y1178051D03*
X607775Y1174310D03*
Y1178051D03*
X611516Y1174310D03*
X615256D03*
X613386Y1183661D03*
X617126Y1187401D03*
Y1183661D03*
X613386Y1179921D03*
X620866Y1183661D03*
X609646D03*
X605905D03*
Y1187401D03*
X613386D03*
X609646D03*
X620866D03*
X613386Y1198621D03*
X609646Y1191141D03*
X613386D03*
X617126Y1198621D03*
X620866D03*
X617126Y1191141D03*
X620866D03*
X605905Y1202362D03*
Y1194881D03*
X609646Y1198621D03*
X605905Y1191141D03*
X613386Y1194881D03*
X605905Y1198621D03*
X609646Y1194881D03*
Y1202362D03*
X613386D03*
X620866D03*
Y1194881D03*
X613386Y1221062D03*
X609646D03*
Y1213582D03*
X613386D03*
X620866Y1206102D03*
X617126D03*
X620866Y1221062D03*
X617126D03*
X613386Y1206102D03*
X605905Y1217322D03*
Y1209842D03*
X609646Y1206102D03*
X613386Y1217322D03*
X605905Y1221062D03*
X609646Y1217322D03*
Y1209842D03*
X605905Y1206102D03*
Y1213582D03*
X620866Y1209842D03*
X613386D03*
X620866Y1217322D03*
X605905Y1224803D03*
Y1232283D03*
Y1236023D03*
X620866D03*
Y1232283D03*
X617126Y1224803D03*
X609646D03*
Y1228543D03*
X613386Y1232283D03*
Y1236023D03*
X620866Y1228543D03*
Y1224803D03*
X613386Y1228543D03*
Y1224803D03*
X617126Y1243503D03*
Y1239763D03*
X620866D03*
X609646Y1243503D03*
Y1239763D03*
X605905Y1247243D03*
X617126Y1250984D03*
X620866Y1243503D03*
Y1247243D03*
X609646Y1254724D03*
X613386Y1247243D03*
X617126Y1254724D03*
X613386Y1243503D03*
X609646Y1250984D03*
X605905Y1239763D03*
X617126Y1258465D03*
X609646D03*
X632085Y1071455D03*
X626476Y1092027D03*
X635827Y1090157D03*
X628346D03*
X632086D03*
X630216Y1099507D03*
X626476Y1106988D03*
X622736D03*
X626476Y1095767D03*
X630216Y1103247D03*
X635827Y1093897D03*
X632086Y1101377D03*
Y1105117D03*
X628346Y1093897D03*
X635827Y1097637D03*
X633957Y1110728D03*
X630216D03*
X626476D03*
X622736Y1114468D03*
X630216Y1118208D03*
X626476D03*
X633957Y1114468D03*
Y1118208D03*
Y1121948D03*
X635827Y1108858D03*
X632086D03*
X633957Y1140649D03*
Y1125688D03*
Y1129429D03*
Y1133169D03*
Y1136909D03*
X630216Y1140649D03*
X626476D03*
X622736D03*
Y1129429D03*
X630216Y1144389D03*
X626476D03*
X630216Y1148129D03*
Y1155610D03*
Y1151870D03*
Y1159350D03*
Y1166830D03*
Y1170570D03*
X633957D03*
Y1185531D03*
X628346Y1183661D03*
X630216Y1174310D03*
Y1178051D03*
Y1181791D03*
X632086Y1187401D03*
X628346D03*
X624606Y1183661D03*
X635827Y1187401D03*
X624606D03*
Y1191141D03*
X632086Y1202362D03*
X628346D03*
X632086Y1194881D03*
X628346D03*
X635827Y1191141D03*
Y1194881D03*
Y1198621D03*
Y1202362D03*
X628346Y1191141D03*
X624606Y1194881D03*
X632086Y1191141D03*
X628346Y1198621D03*
X624606Y1202362D03*
X632086Y1198621D03*
X624606Y1206102D03*
X628346Y1209842D03*
Y1217322D03*
Y1221062D03*
X632086D03*
Y1217322D03*
X635827Y1221062D03*
Y1206102D03*
Y1209842D03*
Y1213582D03*
Y1217322D03*
X628346Y1206102D03*
X632086D03*
X624606Y1217322D03*
X628346Y1213582D03*
X632086D03*
X624606Y1209842D03*
X632086Y1224803D03*
X624606D03*
X628346Y1236023D03*
Y1232283D03*
X635827Y1236023D03*
Y1232283D03*
X628346Y1224803D03*
Y1228543D03*
X635827D03*
Y1224803D03*
X632086Y1247243D03*
Y1239763D03*
X628346D03*
Y1250984D03*
X624606Y1243503D03*
Y1239763D03*
Y1254724D03*
Y1250984D03*
X632086Y1254724D03*
X635827Y1243503D03*
X632086Y1250984D03*
X635827Y1247243D03*
X628346Y1243503D03*
Y1247243D03*
X632087Y1258465D03*
X624606D03*
X631928Y1396583D03*
Y1408495D03*
X647046Y1071455D03*
X639566D03*
X643307Y1090157D03*
X639567D03*
X650787D03*
X647047D03*
X639567Y1101377D03*
Y1105117D03*
X647047D03*
Y1101377D03*
X650787Y1097637D03*
X643307D03*
Y1093897D03*
X650787D03*
X647047D03*
X637697Y1114468D03*
X648917Y1118208D03*
X645177D03*
X641437D03*
X637697D03*
X648917Y1121948D03*
X645177D03*
X641437D03*
X637697D03*
Y1110728D03*
X652657Y1118208D03*
Y1121948D03*
X650787Y1108858D03*
X647047D03*
X643307D03*
X639567D03*
X641437Y1133169D03*
X637697D03*
X645177Y1136909D03*
X637697D03*
X645177Y1140649D03*
X641437D03*
X652657Y1133169D03*
Y1129429D03*
Y1125688D03*
Y1136909D03*
X637697Y1140649D03*
X648917Y1125688D03*
X645177D03*
X641437D03*
X637697D03*
X645177Y1129429D03*
X641437D03*
X637697D03*
X645177Y1133169D03*
X637697Y1155610D03*
Y1151870D03*
X645177Y1144389D03*
X637697D03*
Y1148129D03*
X645177Y1151870D03*
X648917Y1155610D03*
Y1148129D03*
X652657Y1151869D03*
Y1144389D03*
X645177Y1170570D03*
X637697Y1166830D03*
X645177Y1159350D03*
X637697D03*
X648917Y1166830D03*
X652657Y1159350D03*
Y1170570D03*
X637697Y1189271D03*
X645177Y1185531D03*
X637697D03*
Y1178051D03*
Y1174310D03*
Y1181791D03*
X652657Y1189271D03*
X648917Y1181791D03*
Y1174310D03*
X652657Y1185531D03*
Y1178051D03*
Y1193011D03*
Y1204232D03*
X637697Y1193011D03*
X645177Y1196751D03*
Y1200491D03*
X641437D03*
Y1204232D03*
X645177D03*
X648917D03*
Y1196751D03*
Y1200491D03*
X641437Y1193011D03*
Y1196751D03*
X652657Y1200491D03*
Y1196751D03*
Y1211712D03*
X648917Y1219192D03*
X641437D03*
Y1211712D03*
X645177D03*
X648917D03*
Y1207972D03*
X645177D03*
X641437D03*
X652657D03*
X639567Y1221062D03*
X647047D03*
X643307D03*
X650787D03*
X639567Y1224803D03*
X643307Y1236023D03*
Y1232283D03*
X650787Y1236023D03*
X647047Y1224803D03*
X650787Y1232283D03*
X643307Y1224803D03*
Y1228543D03*
X650787D03*
Y1224803D03*
X639567Y1243503D03*
X647047D03*
X650787Y1239763D03*
X643307D03*
X639567Y1250984D03*
Y1254724D03*
X650787Y1247243D03*
Y1243503D03*
X647047Y1254724D03*
Y1250984D03*
X643307Y1247243D03*
Y1243503D03*
X647047Y1258465D03*
X639567D03*
X644168Y1384297D03*
Y1372385D03*
Y1396583D03*
Y1408495D03*
X669487Y1071455D03*
X662007D03*
X654526D03*
X669488Y1090157D03*
X665748D03*
X654527D03*
X658268D03*
X662008D03*
Y1101377D03*
X665748Y1093897D03*
X658268D03*
X654527Y1105117D03*
Y1101377D03*
X662008Y1105117D03*
X658268Y1097637D03*
X669488Y1101377D03*
Y1105117D03*
X665748Y1097637D03*
X656398Y1118208D03*
Y1121948D03*
X663878Y1118208D03*
X660138D03*
Y1121948D03*
X663878D03*
X667618Y1118208D03*
Y1121948D03*
X669488Y1108858D03*
X665748D03*
X662008D03*
X658268D03*
X654527D03*
X656398Y1140649D03*
X660138D03*
X663878D03*
X656398Y1125688D03*
X660138D03*
X663878D03*
Y1133169D03*
X660138D03*
X656398D03*
X667618D03*
Y1140649D03*
Y1125688D03*
Y1148129D03*
X660138D03*
X656398D03*
X663878D03*
X656398Y1155610D03*
X663878D03*
Y1166830D03*
X660138Y1159350D03*
X656398Y1166830D03*
X660138Y1170570D03*
X667618Y1159350D03*
Y1170570D03*
X663878Y1181791D03*
X660138D03*
X656398D03*
X663878Y1189271D03*
X660138D03*
X656398D03*
X667618Y1181791D03*
Y1189271D03*
X656398Y1174310D03*
X663878D03*
Y1196751D03*
X660138D03*
X656398D03*
Y1204232D03*
X660138D03*
X663878D03*
X667618Y1196751D03*
Y1204232D03*
X663878Y1207972D03*
X660138D03*
X656398D03*
X667618D03*
X654527Y1221062D03*
X658268D03*
X662008D03*
X665748D03*
X669488D03*
X654527Y1224803D03*
X658268Y1236023D03*
Y1232283D03*
X662008Y1224803D03*
X665748Y1236023D03*
Y1232283D03*
X669488Y1224803D03*
X665748D03*
X658268D03*
X665748Y1228543D03*
X658268D03*
X654527Y1239763D03*
Y1243503D03*
X665748Y1239763D03*
X669488Y1243503D03*
X662008D03*
Y1254724D03*
X665748Y1247243D03*
X669488Y1250984D03*
X658268Y1247243D03*
X662008Y1250984D03*
X665748Y1243503D03*
X669488Y1254724D03*
X658268Y1243503D03*
X654527Y1254724D03*
Y1250984D03*
X662008Y1258465D03*
X669488D03*
X654528D03*
X668648Y1348187D03*
X656408D03*
X668648Y1360099D03*
X656408D03*
Y1384297D03*
Y1372385D03*
X668648D03*
Y1384297D03*
Y1396583D03*
X656408D03*
X668648Y1408495D03*
X656408D03*
X684448Y1071455D03*
X676967D03*
X680709Y1090157D03*
X676968D03*
X684449D03*
X673228D03*
X676968Y1105117D03*
X684449Y1101377D03*
Y1105117D03*
X680709Y1093897D03*
X676968Y1101377D03*
X680709Y1097637D03*
X673228D03*
Y1093897D03*
X682579Y1118208D03*
Y1121948D03*
X671358Y1118208D03*
X675098D03*
X678838D03*
X675098Y1121948D03*
X678838D03*
X671358D03*
X684449Y1108858D03*
X680709D03*
X676968D03*
X673228D03*
X682579Y1133169D03*
Y1140649D03*
Y1125688D03*
X671358Y1140649D03*
X675098D03*
X678838D03*
X675098Y1125688D03*
X671358D03*
X678838D03*
Y1133169D03*
X675098D03*
X671358D03*
X682579Y1148129D03*
X678838D03*
X675098D03*
X671358D03*
Y1155610D03*
X678838D03*
X682579Y1170570D03*
Y1159350D03*
X675098Y1170570D03*
X678839Y1166830D03*
X671358D03*
X675098Y1159350D03*
Y1181791D03*
X671358D03*
X678838Y1189271D03*
X675098D03*
X671358D03*
X682579Y1181791D03*
Y1189271D03*
X678838Y1181791D03*
X671358Y1174310D03*
X678838D03*
X682579Y1196751D03*
Y1204232D03*
X678838D03*
Y1196751D03*
X675098D03*
X671358D03*
Y1204232D03*
X675098D03*
X682579Y1207972D03*
X678838Y1219192D03*
Y1207972D03*
X675098D03*
X671358D03*
X673228Y1221062D03*
X676968D03*
X680709D03*
X684449D03*
X673228Y1236023D03*
Y1232283D03*
X676968Y1224803D03*
X680709Y1236023D03*
Y1232283D03*
X684449Y1224803D03*
X673228Y1228543D03*
X680709Y1224803D03*
X673228D03*
X680709Y1228543D03*
X673228Y1239763D03*
X680709D03*
X676968Y1243503D03*
X684449D03*
X673228D03*
X680709Y1247243D03*
X673228D03*
X684449Y1254724D03*
Y1250984D03*
X676968Y1254724D03*
Y1250984D03*
X680709Y1243503D03*
X684450Y1258465D03*
X676969D03*
X680888Y1348187D03*
Y1360099D03*
Y1372385D03*
Y1384297D03*
Y1396583D03*
Y1408495D03*
X695669Y1075196D03*
X699408Y1071455D03*
X691928Y1071454D03*
X699408Y1075196D03*
X691928Y1075195D03*
X688189Y1090157D03*
X691929Y1082677D03*
Y1086417D03*
X695669Y1090157D03*
X699409D03*
Y1086417D03*
X691929Y1090157D03*
X691928Y1078935D03*
X699408Y1078936D03*
X695668Y1086416D03*
Y1082676D03*
X688189Y1097637D03*
X695669Y1093897D03*
X688189D03*
X699409Y1105117D03*
X691929Y1101377D03*
X699409D03*
X691929Y1105117D03*
X693799Y1121948D03*
X697539D03*
X701279D03*
X686319D03*
Y1118208D03*
Y1114468D03*
X699409Y1108858D03*
X695669D03*
X691929D03*
X688189D03*
X693799Y1133464D03*
X697539Y1133169D03*
X686417Y1132677D03*
X693799Y1140649D03*
X697539D03*
X693799Y1125688D03*
X697539D03*
X701279D03*
Y1140649D03*
Y1133169D03*
X686319Y1140649D03*
Y1125688D03*
X697539Y1148129D03*
X701279D03*
X693799D03*
X697539Y1155610D03*
X686319Y1148129D03*
Y1155610D03*
X697539Y1166830D03*
X693799Y1170570D03*
Y1159350D03*
X701279D03*
Y1170570D03*
X686319Y1166830D03*
X693799Y1181791D03*
Y1189271D03*
X697539D03*
X701279D03*
Y1181791D03*
X697539D03*
Y1174310D03*
X686319Y1181791D03*
Y1189271D03*
Y1174310D03*
X697539Y1204232D03*
X693799D03*
Y1196751D03*
X697539D03*
X701279D03*
Y1204232D03*
X686319Y1196751D03*
Y1204232D03*
X693799Y1207972D03*
X697539D03*
Y1211712D03*
X701279Y1207972D03*
Y1211712D03*
X686319Y1207972D03*
X695669Y1221062D03*
X699409D03*
X691929D03*
X688189D03*
Y1236023D03*
Y1232283D03*
X691929Y1224803D03*
Y1228543D03*
X699409Y1224803D03*
Y1228543D03*
X695669Y1236023D03*
Y1232283D03*
X688189Y1224803D03*
Y1239763D03*
X695669D03*
X688189Y1247243D03*
Y1243503D03*
X695669Y1247243D03*
Y1243503D03*
X699409Y1258465D03*
X691929D03*
X693128Y1348187D03*
Y1360099D03*
Y1372385D03*
Y1384297D03*
Y1396583D03*
Y1408495D03*
X703149Y1075196D03*
X718110D03*
X710630D03*
X714369Y1071455D03*
X706889D03*
Y1075196D03*
X714369D03*
X710630Y1078936D03*
X706890Y1086417D03*
Y1090157D03*
X718110Y1078936D03*
X714370Y1086417D03*
Y1090157D03*
X710630D03*
X718110D03*
X703149Y1078936D03*
Y1090157D03*
X706889Y1078936D03*
X718109Y1086417D03*
X714369Y1078936D03*
X703148Y1082677D03*
X710629Y1086416D03*
X703148Y1086417D03*
X718109Y1082677D03*
X710629Y1082676D03*
X706890Y1105117D03*
X714370D03*
X710630Y1097637D03*
Y1093897D03*
X718110Y1097637D03*
Y1093897D03*
X703149D03*
Y1097637D03*
X714369D03*
X706889Y1093897D03*
X714369D03*
X706889Y1097637D03*
X716240Y1121948D03*
X705020D03*
X708760D03*
X712500D03*
X718110Y1108858D03*
X714370D03*
X710630D03*
X706890D03*
X703149D03*
X716240Y1140649D03*
Y1125688D03*
Y1133169D03*
X712500Y1125688D03*
X708760D03*
X705020D03*
X712500Y1140649D03*
X708760D03*
X705020D03*
X712500Y1133169D03*
X708760D03*
X705020D03*
X716240Y1148129D03*
X712500D03*
X708760D03*
X705020D03*
X712500Y1155610D03*
X705020D03*
X716240Y1170570D03*
Y1159350D03*
X708760D03*
X705020Y1166830D03*
X712500D03*
X708760Y1170570D03*
X716240Y1189271D03*
Y1181791D03*
X712500Y1189271D03*
X708760D03*
X705020D03*
X712500Y1181791D03*
X708760D03*
X705020D03*
Y1174310D03*
X712500D03*
X716240Y1196751D03*
Y1204232D03*
X712500Y1196751D03*
X708760D03*
X705020D03*
X708760Y1204232D03*
X712500D03*
X705020D03*
X716240Y1211712D03*
Y1207972D03*
X712500D03*
Y1211712D03*
X708760Y1207972D03*
X705020D03*
X703149Y1221062D03*
X706890D03*
X710630D03*
X714370D03*
X718110D03*
X703149Y1236023D03*
Y1232283D03*
X710630Y1236023D03*
X718110D03*
Y1232283D03*
X710630D03*
X714370Y1224803D03*
Y1228543D03*
X706890Y1224803D03*
Y1228543D03*
X703149Y1239763D03*
X714370D03*
X718110Y1243503D03*
Y1247243D03*
X703149Y1243503D03*
X710630Y1247243D03*
Y1243503D03*
X703149Y1247243D03*
X714370Y1258465D03*
X706890D03*
X705368Y1348187D03*
X717608D03*
X705368Y1360099D03*
X717608D03*
X705368Y1372385D03*
Y1384297D03*
X717608Y1372385D03*
Y1384297D03*
Y1396583D03*
X705368D03*
X717608Y1408495D03*
X705368D03*
X725590Y1075196D03*
X733071D03*
X729330Y1071455D03*
X721849D03*
Y1075196D03*
X729330D03*
X729331Y1086417D03*
Y1082677D03*
X733071Y1090157D03*
X729331D03*
X725590D03*
X721850D03*
X725590Y1078936D03*
X721850Y1086417D03*
X725589Y1086416D03*
X733069Y1086417D03*
X721849Y1078936D03*
X729330D03*
X733069Y1082677D03*
X725589Y1082676D03*
X725590Y1097637D03*
X721850Y1105117D03*
X725590Y1093897D03*
X729331Y1105117D03*
X733071Y1093897D03*
X734941Y1118208D03*
X727460Y1121948D03*
X719980D03*
X723720D03*
X727460Y1118208D03*
X731201D03*
X733071Y1108858D03*
X729331D03*
X725590D03*
X721850D03*
X734941Y1140649D03*
Y1136909D03*
X727460Y1140649D03*
X723720Y1125688D03*
X719980D03*
X727460Y1129429D03*
Y1125688D03*
X723720Y1140649D03*
X719980D03*
X727460Y1133169D03*
X723720D03*
X719980D03*
X727460Y1136909D03*
X731201Y1125688D03*
X727460Y1151869D03*
Y1148129D03*
Y1144389D03*
X723720Y1148129D03*
X719980D03*
X731201D03*
Y1151869D03*
Y1155610D03*
X734941Y1151870D03*
Y1148129D03*
Y1144389D03*
X719980Y1155610D03*
X727460D03*
X731201Y1170570D03*
X719980Y1166830D03*
X731201Y1159350D03*
Y1166830D03*
X727460Y1185531D03*
X734941Y1181791D03*
Y1185531D03*
Y1189271D03*
Y1178051D03*
X727460Y1189271D03*
X723720Y1181791D03*
X719980D03*
Y1174310D03*
X727460Y1178051D03*
X723720Y1189271D03*
X719980D03*
X731201Y1174310D03*
Y1181791D03*
X727460Y1174310D03*
X719980Y1204232D03*
X727460D03*
X727480Y1196732D03*
X731201Y1196751D03*
X734941Y1193011D03*
X727460D03*
X723720Y1196751D03*
X719980D03*
X727460Y1200491D03*
X723720Y1204232D03*
X734941Y1211712D03*
X727460Y1207972D03*
X723720Y1211712D03*
Y1207972D03*
X719980Y1211712D03*
Y1207972D03*
X727460Y1211712D03*
X731201Y1207972D03*
X733071Y1221062D03*
X721850D03*
X725590D03*
X729331D03*
Y1224803D03*
Y1228543D03*
X733071Y1236023D03*
Y1232283D03*
X725590Y1236023D03*
Y1232283D03*
X721850Y1224803D03*
Y1228543D03*
X725590Y1239763D03*
X733071Y1247243D03*
X725590Y1243503D03*
X733071D03*
X725590Y1247243D03*
X729331Y1258465D03*
X721850D03*
X729848Y1348187D03*
Y1360099D03*
Y1372385D03*
Y1384297D03*
Y1396489D03*
Y1408401D03*
X740551Y1075196D03*
X748031D03*
X744290Y1071455D03*
X736810D03*
Y1075196D03*
X744290D03*
X748030Y1090157D03*
X744291D03*
X740551Y1078936D03*
Y1090157D03*
X736811D03*
X744290Y1078936D03*
X748030Y1086417D03*
X740550Y1086416D03*
Y1082676D03*
X736810Y1078936D03*
X748030Y1082677D03*
X744291Y1101377D03*
X748031Y1093897D03*
X744291Y1105117D03*
X736811D03*
X748031Y1123818D03*
Y1120078D03*
Y1116338D03*
Y1112598D03*
Y1108858D03*
X744291D03*
X740551D03*
X736811D03*
X738681Y1136909D03*
Y1140649D03*
X748031Y1138779D03*
Y1135039D03*
Y1131299D03*
Y1127558D03*
X738681Y1155610D03*
Y1148129D03*
X749901Y1144389D03*
Y1151869D03*
X746161Y1155610D03*
Y1151869D03*
X742421D03*
X738681D03*
Y1166830D03*
X746161Y1170570D03*
Y1166830D03*
X738681Y1159350D03*
X749901Y1166830D03*
Y1159350D03*
X738681Y1170570D03*
X746161Y1159350D03*
X749901Y1181791D03*
Y1174310D03*
X738681D03*
Y1178051D03*
X742421Y1181791D03*
X738681Y1185531D03*
Y1189271D03*
X746161Y1185531D03*
Y1178051D03*
Y1174310D03*
X742421Y1185531D03*
X748031Y1191141D03*
X738681Y1204232D03*
Y1193011D03*
Y1196751D03*
X742421Y1193011D03*
X748031Y1202362D03*
Y1198621D03*
X736811Y1221062D03*
X740551D03*
X748031D03*
X744291D03*
X748031Y1217322D03*
Y1213582D03*
Y1209842D03*
Y1206102D03*
X736811Y1224803D03*
Y1228543D03*
X748031Y1236023D03*
Y1232283D03*
X740551Y1236023D03*
X744291Y1228543D03*
X740551Y1232283D03*
X744291Y1224803D03*
X748031Y1239763D03*
X740551D03*
Y1243503D03*
Y1247243D03*
X748031D03*
Y1243503D03*
X744291Y1258465D03*
X736811D03*
X742088Y1348187D03*
Y1360099D03*
Y1384297D03*
Y1372385D03*
Y1396489D03*
Y1408401D03*
X755512Y1075196D03*
X762993D03*
X766732Y1071455D03*
X759252D03*
X751771D03*
Y1075196D03*
X766731D03*
X759251D03*
X755511Y1090157D03*
X762993Y1078936D03*
X755513D03*
X762991Y1086417D03*
X766731Y1078936D03*
X755511Y1086416D03*
X759251Y1078936D03*
X755511Y1082676D03*
X762991Y1082677D03*
X751771Y1078936D03*
X751772Y1105117D03*
X762992Y1093897D03*
X759252Y1105117D03*
X766732D03*
X755512Y1093897D03*
X762991Y1108857D03*
X755512Y1108858D03*
X751772D03*
X759252Y1116338D03*
Y1123818D03*
X751771Y1112598D03*
Y1120078D03*
X757382Y1140649D03*
X759252Y1131299D03*
X757382Y1148129D03*
X764862Y1170570D03*
X757382Y1166830D03*
Y1159350D03*
Y1174310D03*
Y1181791D03*
X764862Y1185531D03*
Y1178051D03*
X755512Y1187401D03*
X764862Y1189271D03*
X766732Y1194881D03*
X751772D03*
X755512Y1202362D03*
X766732D03*
Y1198621D03*
X762992D03*
X766732Y1221062D03*
Y1217322D03*
X762992Y1221062D03*
X759252D03*
X762992Y1213582D03*
X766732D03*
Y1209842D03*
X755512D03*
X766732Y1206102D03*
X751772Y1221062D03*
Y1217322D03*
X759252Y1224803D03*
Y1228543D03*
X755512Y1232283D03*
Y1236023D03*
X766732Y1224803D03*
Y1228543D03*
X762992Y1232283D03*
Y1236023D03*
X751772Y1224803D03*
Y1228543D03*
X755512Y1239763D03*
X766732D03*
Y1250984D03*
X755512Y1243503D03*
X762992D03*
Y1247243D03*
X751772Y1250984D03*
Y1254724D03*
X759252D03*
X766732D03*
X759252Y1250984D03*
X755512Y1247243D03*
X766732Y1258465D03*
X759252D03*
X751772D03*
X766568Y1348187D03*
X754328D03*
X766568Y1360099D03*
X754328D03*
Y1372385D03*
Y1384297D03*
X766568Y1372385D03*
Y1384297D03*
X777953Y1075196D03*
X770473D03*
X774212Y1071455D03*
X774211Y1075196D03*
X777953Y1078936D03*
X781693D03*
X770473D03*
X770471Y1090157D03*
X774211Y1078936D03*
X770471Y1086417D03*
Y1082677D03*
X770472Y1093897D03*
Y1108858D03*
X776083Y1140649D03*
Y1148129D03*
Y1155610D03*
Y1170570D03*
X768602Y1166830D03*
X779823Y1170570D03*
X776083Y1178051D03*
Y1185531D03*
X779823D03*
Y1178051D03*
X768602Y1181791D03*
Y1174310D03*
X772342Y1189271D03*
X783503Y1193011D03*
X776083D03*
X779823D03*
X781693Y1202362D03*
X777953D03*
X770472Y1221062D03*
X777953Y1209842D03*
Y1206102D03*
X774212Y1224803D03*
Y1228543D03*
X770472Y1236023D03*
Y1232283D03*
X777953D03*
X781693Y1250984D03*
X777953Y1239763D03*
X781693D03*
X770472Y1243503D03*
Y1247243D03*
X774212Y1250984D03*
Y1254724D03*
Y1258465D03*
X778808Y1348187D03*
Y1360099D03*
X785434Y1090158D03*
Y1082677D03*
Y1101378D03*
Y1123819D03*
Y1116339D03*
Y1108859D03*
Y1131300D03*
Y1198621D03*
Y1221062D03*
Y1213582D03*
Y1206102D03*
Y1228543D03*
Y1247243D03*
Y1239762D03*
X892183Y1728286D03*
Y1738286D03*
X891761Y1775438D03*
Y1785438D03*
X1057381Y1103247D03*
Y1140649D03*
Y1133169D03*
Y1125688D03*
Y1151870D03*
Y1144389D03*
X1054881Y1170570D03*
X1057381Y1159350D03*
X1054881Y1178050D03*
X1059251Y1187401D03*
Y1183661D03*
Y1194881D03*
Y1202362D03*
X1055510Y1198622D03*
Y1191142D03*
X1059251Y1198621D03*
Y1191141D03*
Y1209842D03*
Y1217322D03*
X1055510Y1221063D03*
Y1213583D03*
Y1206103D03*
X1059251Y1221062D03*
Y1206102D03*
Y1213582D03*
Y1232283D03*
Y1236023D03*
Y1224803D03*
Y1247243D03*
Y1239763D03*
X1052473Y1348187D03*
Y1360099D03*
Y1384297D03*
Y1372385D03*
X1064861Y1077066D03*
X1061121Y1080806D03*
X1072342Y1106988D03*
X1061121Y1103247D03*
X1072342Y1121948D03*
Y1118208D03*
X1064862Y1121948D03*
X1068602D03*
X1072342Y1140649D03*
Y1125688D03*
X1061121D03*
Y1140649D03*
X1064862D03*
X1068602D03*
X1064862Y1136909D03*
X1061121Y1133169D03*
X1064862Y1129429D03*
X1068602D03*
X1072342Y1155610D03*
X1064862D03*
X1068602D03*
X1061121Y1151870D03*
X1064862D03*
Y1148129D03*
X1061121Y1144389D03*
X1064862D03*
X1072342Y1166830D03*
X1064861Y1170570D03*
X1068602D03*
X1064861Y1166830D03*
X1061121Y1159350D03*
X1064862D03*
X1072342Y1181791D03*
Y1174310D03*
X1061120Y1181791D03*
X1064861D03*
X1068602D03*
Y1174310D03*
X1064861Y1178051D03*
X1061120Y1174310D03*
X1064861D03*
X1074212Y1187401D03*
X1062991D03*
Y1183661D03*
X1066732D03*
X1070472D03*
X1074212D03*
X1070472Y1187401D03*
X1066732D03*
X1074212Y1191141D03*
Y1198621D03*
X1070472Y1191141D03*
X1066732D03*
X1070472Y1198621D03*
X1066732D03*
X1062991Y1194881D03*
Y1202362D03*
Y1198621D03*
X1066732Y1194881D03*
X1062991Y1191141D03*
X1070472Y1194881D03*
Y1202362D03*
X1066732D03*
X1074212Y1206102D03*
X1066732D03*
X1070472D03*
Y1213582D03*
X1066732D03*
X1062991Y1209842D03*
Y1217322D03*
X1074212Y1221062D03*
X1066732D03*
X1070472D03*
Y1217322D03*
X1066732D03*
X1062991Y1221062D03*
Y1206102D03*
X1070472Y1209842D03*
X1062991Y1213582D03*
X1066732Y1209842D03*
X1070472Y1236023D03*
Y1232283D03*
X1066732Y1228543D03*
Y1224803D03*
X1074212D03*
X1062991Y1236023D03*
Y1232283D03*
Y1224803D03*
X1070472Y1228543D03*
Y1224803D03*
X1066732Y1239763D03*
Y1243503D03*
X1074212Y1239763D03*
Y1243503D03*
Y1250984D03*
X1066732Y1254724D03*
X1070472Y1247243D03*
X1074212Y1254724D03*
X1062991Y1247243D03*
X1070472Y1243503D03*
X1062991Y1239763D03*
X1066732Y1250984D03*
X1074212Y1258465D03*
X1066732D03*
X1072593Y1348187D03*
X1064713D03*
X1060353D03*
X1072593Y1360099D03*
X1064713D03*
X1060353D03*
X1072593Y1384297D03*
Y1372385D03*
X1064713D03*
Y1384297D03*
X1060353D03*
Y1372385D03*
X1072593Y1396583D03*
X1064713D03*
X1072593Y1408495D03*
X1064713D03*
X1089171Y1071455D03*
X1083562Y1092027D03*
X1089172Y1090157D03*
X1083562Y1095767D03*
X1087302Y1106988D03*
X1079822D03*
X1083562D03*
X1076082D03*
X1089172Y1101377D03*
Y1105117D03*
X1083562Y1118208D03*
X1087302D03*
X1079822Y1114468D03*
X1083562Y1110728D03*
X1087302D03*
X1091043D03*
Y1121948D03*
Y1118208D03*
Y1114468D03*
X1076082D03*
X1089172Y1108858D03*
X1091043Y1125688D03*
Y1140649D03*
X1079822Y1129429D03*
Y1140649D03*
X1083562D03*
X1087302D03*
X1091043Y1136909D03*
Y1133169D03*
Y1129429D03*
X1076082Y1140649D03*
X1087302Y1151870D03*
Y1155610D03*
Y1148129D03*
X1083562Y1144389D03*
X1087302D03*
X1076082Y1155610D03*
Y1151870D03*
Y1148129D03*
Y1144389D03*
X1087302Y1170570D03*
Y1166830D03*
Y1159350D03*
X1091043Y1170570D03*
X1076082Y1159350D03*
X1081692Y1179921D03*
X1083562Y1181791D03*
X1087302D03*
Y1178051D03*
Y1174310D03*
X1076082Y1181791D03*
Y1178051D03*
Y1174310D03*
X1077952Y1183661D03*
X1081692D03*
X1085432D03*
X1089172Y1187401D03*
X1085432D03*
X1091043Y1185531D03*
X1077952Y1187401D03*
X1081692D03*
X1077952Y1191141D03*
Y1198621D03*
X1081692Y1191141D03*
X1085432Y1194881D03*
X1089172D03*
X1085432Y1202362D03*
X1089172D03*
X1077952Y1194881D03*
Y1202362D03*
X1089172Y1191141D03*
Y1198621D03*
X1081692Y1202362D03*
X1085432Y1198621D03*
X1081692Y1194881D03*
X1085432Y1191141D03*
X1077952Y1206102D03*
X1081692D03*
X1085432Y1209842D03*
X1077952Y1221062D03*
X1089172Y1217322D03*
Y1221062D03*
X1085432D03*
Y1217322D03*
X1089172Y1206102D03*
X1077952Y1209842D03*
X1081692D03*
Y1217322D03*
X1089172Y1213582D03*
X1077952Y1217322D03*
X1085432Y1206102D03*
Y1213582D03*
X1077952Y1232283D03*
Y1236023D03*
X1085432Y1232283D03*
Y1236023D03*
X1081692Y1224803D03*
X1089172D03*
X1077952D03*
Y1228543D03*
X1085432Y1224803D03*
Y1228543D03*
X1077952Y1239763D03*
X1081692D03*
Y1243503D03*
X1085432Y1250984D03*
Y1239763D03*
X1089172D03*
Y1247243D03*
X1077952Y1243503D03*
X1081692Y1250984D03*
X1077952Y1247243D03*
X1081692Y1254724D03*
X1085432Y1243503D03*
X1089172Y1254724D03*
Y1250984D03*
X1085432Y1247243D03*
X1089173Y1258465D03*
X1081692D03*
X1089193Y1348187D03*
X1084833D03*
X1076953D03*
X1089193Y1360099D03*
X1084833D03*
X1076953D03*
X1089193Y1384297D03*
Y1372385D03*
X1084833Y1384297D03*
Y1372385D03*
X1076953Y1384297D03*
Y1372385D03*
X1089193Y1396583D03*
X1084833D03*
X1076953D03*
X1089193Y1408495D03*
X1084833D03*
X1076953D03*
X1104132Y1071455D03*
X1096652D03*
X1092913Y1090157D03*
X1104133D03*
X1107873D03*
X1100393D03*
X1096653D03*
X1104133Y1093897D03*
X1092913D03*
Y1097637D03*
X1107873Y1093897D03*
Y1097637D03*
X1104133Y1101377D03*
X1100393Y1097637D03*
Y1093897D03*
X1096653Y1101377D03*
X1104133Y1105117D03*
X1096653D03*
X1094783Y1110728D03*
Y1121948D03*
X1098523D03*
X1102263D03*
X1106003D03*
X1094783Y1118208D03*
X1098523D03*
X1102263D03*
X1106003D03*
X1094783Y1114468D03*
X1107873Y1108858D03*
X1104133D03*
X1100393D03*
X1096653D03*
X1092913D03*
X1098523Y1140649D03*
X1102263D03*
X1094783Y1136909D03*
X1102263D03*
X1094783Y1133169D03*
X1098523D03*
X1102263D03*
X1094783Y1129429D03*
X1098523D03*
X1102263D03*
X1094783Y1125688D03*
X1098523D03*
X1102263D03*
X1106003D03*
X1094783Y1140649D03*
Y1151870D03*
Y1155610D03*
X1102263Y1151870D03*
X1094783Y1148129D03*
Y1144389D03*
X1102263D03*
X1106003Y1148129D03*
Y1155610D03*
X1102263Y1170570D03*
X1094783Y1159350D03*
X1102263D03*
X1094783Y1166830D03*
X1106003D03*
X1094783Y1181791D03*
X1102263Y1185531D03*
X1094783Y1174310D03*
Y1178051D03*
X1106003Y1181791D03*
Y1174310D03*
X1092913Y1187401D03*
X1098523Y1196751D03*
Y1193011D03*
X1106003Y1200491D03*
Y1196751D03*
Y1204232D03*
X1102263D03*
X1098523D03*
Y1200491D03*
X1102263D03*
Y1196751D03*
X1092913Y1191141D03*
Y1194881D03*
Y1198621D03*
Y1202362D03*
X1098523Y1207972D03*
X1102263D03*
X1106003D03*
Y1211712D03*
X1102263D03*
X1098523D03*
Y1219192D03*
X1106003D03*
X1092913Y1206102D03*
Y1209842D03*
Y1213582D03*
Y1217322D03*
X1107873Y1221062D03*
X1104133D03*
X1100393D03*
X1096653D03*
X1092913D03*
Y1232283D03*
Y1236023D03*
X1107873Y1232283D03*
X1104133Y1224803D03*
X1107873Y1236023D03*
X1100393Y1232283D03*
Y1236023D03*
X1096653Y1224803D03*
X1100393Y1228543D03*
X1092913Y1224803D03*
X1107873D03*
X1100393D03*
X1107873Y1228543D03*
X1092913D03*
X1100393Y1239763D03*
X1107873D03*
X1104133Y1243503D03*
X1096653D03*
Y1254724D03*
X1104133D03*
X1092913Y1247243D03*
X1096653Y1250984D03*
X1092913Y1243503D03*
X1107873D03*
X1100393D03*
X1107873Y1247243D03*
X1100393D03*
X1104133Y1250984D03*
Y1258465D03*
X1096653D03*
X1101433Y1348187D03*
X1097073D03*
X1101433Y1360099D03*
X1097073D03*
X1101433Y1384297D03*
Y1372385D03*
X1097073D03*
Y1384297D03*
X1101433Y1396583D03*
X1097073D03*
X1101433Y1408495D03*
X1097073D03*
X1119093Y1071455D03*
X1111612D03*
X1115354Y1090157D03*
X1119094D03*
X1122834D03*
X1111613D03*
X1122834Y1093897D03*
X1115354D03*
X1122834Y1097637D03*
X1115354D03*
X1119094Y1101377D03*
X1111613D03*
X1119094Y1105117D03*
X1111613D03*
X1117224Y1121948D03*
Y1118208D03*
X1120964D03*
X1109743Y1121948D03*
X1113484D03*
X1109743Y1118208D03*
X1113484D03*
X1124704Y1121948D03*
Y1118208D03*
X1120964Y1121948D03*
X1122834Y1108858D03*
X1119094D03*
X1115354D03*
X1111613D03*
X1109743Y1136909D03*
X1124704Y1125688D03*
Y1140649D03*
Y1133169D03*
X1113484D03*
X1117224D03*
X1120964D03*
X1109743Y1125688D03*
X1120964D03*
X1117224D03*
X1113484D03*
X1120964Y1140649D03*
X1117224D03*
X1113484D03*
X1109743Y1129429D03*
Y1133169D03*
X1113484Y1155610D03*
X1109743Y1144389D03*
X1120964Y1155610D03*
X1109743Y1151869D03*
X1120964Y1148129D03*
X1113484D03*
X1117224D03*
X1124704D03*
X1117224Y1170570D03*
X1109743D03*
X1113484Y1166830D03*
X1117224Y1159350D03*
X1120964Y1166830D03*
X1109743Y1159350D03*
X1124704Y1170570D03*
Y1159350D03*
X1109743Y1189271D03*
X1113484D03*
X1117224D03*
X1120964D03*
X1113484Y1181791D03*
X1117224D03*
X1120964D03*
X1124704Y1189271D03*
Y1181791D03*
X1109743Y1178051D03*
X1120964Y1174310D03*
X1109743Y1185531D03*
X1113484Y1174310D03*
X1124704Y1204232D03*
Y1196751D03*
X1120964Y1204232D03*
X1117224D03*
X1113484D03*
X1109743D03*
Y1193011D03*
Y1196751D03*
Y1200491D03*
X1113484Y1196751D03*
X1117224D03*
X1120964D03*
X1113484Y1207972D03*
X1117224D03*
X1120964D03*
X1109743Y1211712D03*
Y1207972D03*
X1124704D03*
X1122834Y1221062D03*
X1119094D03*
X1115354D03*
X1111613D03*
X1122834Y1224803D03*
Y1232283D03*
Y1236023D03*
X1119094Y1224803D03*
X1115354Y1232283D03*
Y1236023D03*
X1111613Y1224803D03*
X1115354Y1228543D03*
Y1224803D03*
X1122834Y1228543D03*
X1119094Y1243503D03*
X1122834Y1239763D03*
X1111613Y1243503D03*
Y1239763D03*
X1122834Y1243503D03*
X1119094Y1250984D03*
X1111613Y1254724D03*
X1119094D03*
X1122834Y1247243D03*
X1115354Y1243503D03*
Y1247243D03*
X1111613Y1250984D03*
X1119094Y1258465D03*
X1111614D03*
X1113673Y1348187D03*
X1121553D03*
X1109313D03*
X1113673Y1360099D03*
X1121553D03*
X1109313D03*
X1113673Y1372385D03*
Y1384297D03*
X1121553Y1372385D03*
Y1384297D03*
X1109313D03*
Y1372385D03*
X1113673Y1396583D03*
X1121553D03*
X1109313D03*
X1113673Y1408495D03*
X1121553D03*
X1109313D03*
X1134053Y1071455D03*
X1126573D03*
X1126574Y1090157D03*
X1130314D03*
X1134054D03*
X1137795D03*
X1126574Y1101377D03*
X1130314Y1097637D03*
Y1093897D03*
X1137795D03*
Y1097637D03*
X1134054Y1101377D03*
X1126574Y1105117D03*
X1134054D03*
X1139665Y1121948D03*
X1130314Y1112598D03*
X1128444Y1118208D03*
X1132184D03*
X1135924D03*
X1132184Y1121948D03*
X1135924D03*
X1128444D03*
X1139665Y1118208D03*
X1137795Y1108858D03*
X1134054D03*
X1130314D03*
X1126574D03*
X1139665Y1125688D03*
X1128444Y1140649D03*
X1132184D03*
X1135924D03*
X1132184Y1125688D03*
X1128444D03*
X1135924D03*
Y1133169D03*
X1132184D03*
X1128444D03*
X1139665D03*
Y1140649D03*
X1135924Y1148129D03*
X1132184D03*
X1128444D03*
X1139665D03*
X1128444Y1155610D03*
X1135924D03*
X1139665Y1170570D03*
Y1159350D03*
X1132184Y1170570D03*
X1135925Y1166830D03*
X1128444D03*
X1132184Y1159350D03*
X1135924Y1181791D03*
X1132184D03*
X1128444D03*
X1135924Y1189271D03*
X1132184D03*
X1128444D03*
Y1174310D03*
X1135924D03*
X1139665Y1181791D03*
Y1189271D03*
Y1196751D03*
Y1204232D03*
X1135924D03*
Y1196751D03*
X1132184D03*
X1128444D03*
Y1204232D03*
X1132184D03*
X1139665Y1207972D03*
X1134054Y1217322D03*
X1135924Y1207972D03*
X1132184D03*
X1128444D03*
X1137795Y1221062D03*
X1134054D03*
X1130314D03*
X1126574D03*
Y1224803D03*
X1137795Y1232283D03*
Y1236023D03*
X1134054Y1224803D03*
X1130314Y1232283D03*
Y1236023D03*
X1137795Y1228543D03*
Y1224803D03*
X1130314Y1228543D03*
Y1224803D03*
X1126574Y1243503D03*
X1134054D03*
X1137795Y1239763D03*
X1130314D03*
X1126574Y1254724D03*
X1137795Y1243503D03*
X1130314Y1247243D03*
X1126574Y1250984D03*
X1137795Y1247243D03*
X1130314Y1243503D03*
X1134054Y1250984D03*
Y1254724D03*
X1134055Y1258465D03*
X1126574D03*
X1138153Y1348187D03*
X1133793D03*
X1125913D03*
X1138153Y1360099D03*
X1133793D03*
X1125913D03*
X1138153Y1384297D03*
Y1372385D03*
X1133793Y1384297D03*
Y1372385D03*
X1125913Y1384297D03*
Y1372385D03*
X1138153Y1396583D03*
X1133793D03*
X1125913D03*
X1138153Y1408495D03*
X1133793D03*
X1125913D03*
X1152755Y1075196D03*
X1156494Y1071455D03*
X1149014Y1071454D03*
X1141534Y1071455D03*
X1156494Y1075196D03*
X1149014Y1075195D03*
X1141535Y1090157D03*
X1149015Y1082677D03*
Y1086417D03*
X1152755Y1090157D03*
X1156495D03*
Y1086417D03*
X1149015Y1090157D03*
X1145275D03*
X1149014Y1078935D03*
X1156494Y1078936D03*
X1152754Y1086416D03*
Y1082676D03*
X1141535Y1101377D03*
X1149015D03*
X1152755Y1093897D03*
X1156495Y1101377D03*
X1145275Y1093897D03*
Y1097637D03*
X1141535Y1105117D03*
X1149015D03*
X1156495D03*
X1150885Y1121948D03*
X1143405D03*
Y1118208D03*
Y1114468D03*
X1154625Y1121948D03*
X1156495Y1108858D03*
X1152755D03*
X1149015D03*
X1145275D03*
X1141535D03*
X1154625Y1125688D03*
X1150885Y1133464D03*
X1154625Y1133169D03*
X1143503Y1132677D03*
X1143405Y1140649D03*
Y1125688D03*
X1150885Y1140649D03*
X1154625D03*
X1150885Y1125688D03*
X1143405Y1148129D03*
X1150885D03*
X1154625D03*
X1143405Y1155610D03*
X1154625D03*
Y1166830D03*
X1150885Y1170570D03*
X1143405Y1166830D03*
X1150885Y1159350D03*
X1143405Y1181791D03*
X1154625D03*
X1150885D03*
Y1189271D03*
X1154625D03*
X1143405D03*
Y1174310D03*
X1154625D03*
X1150885Y1196751D03*
X1154625Y1204232D03*
X1150885D03*
X1154625Y1196751D03*
X1143405D03*
Y1204232D03*
X1150885Y1207972D03*
X1154625D03*
Y1211712D03*
X1143405Y1207972D03*
X1149015Y1221062D03*
X1156495D03*
X1152755D03*
X1145275D03*
X1141535D03*
X1145275Y1224803D03*
X1141535D03*
X1152755Y1232283D03*
Y1236023D03*
X1156495Y1228543D03*
Y1224803D03*
X1149015Y1228543D03*
Y1224803D03*
X1145275Y1232283D03*
Y1236023D03*
X1141535Y1243503D03*
X1152755Y1239763D03*
X1145275D03*
X1141535Y1254724D03*
Y1250984D03*
X1145275Y1247243D03*
X1152755Y1243503D03*
X1145275D03*
X1152755Y1247243D03*
X1156495Y1258465D03*
X1149015D03*
X1141536D03*
X1150393Y1348187D03*
X1146033D03*
X1150393Y1360099D03*
X1146033D03*
X1150393Y1384297D03*
Y1372385D03*
X1146033D03*
Y1384297D03*
X1150393Y1396583D03*
X1146033D03*
X1150393Y1408495D03*
X1146033D03*
X1167716Y1075196D03*
X1160235D03*
X1171455Y1071455D03*
X1163975D03*
Y1075196D03*
X1171455D03*
X1167716Y1078936D03*
X1163976Y1086417D03*
Y1090157D03*
X1171456Y1086417D03*
Y1090157D03*
X1167716D03*
X1160235Y1078936D03*
Y1090157D03*
X1160234Y1086417D03*
X1167715Y1086416D03*
X1163975Y1078936D03*
X1160234Y1082677D03*
X1171455Y1078936D03*
X1167715Y1082676D03*
X1167716Y1097637D03*
Y1093897D03*
X1160235D03*
Y1097637D03*
X1163976Y1105117D03*
X1171456D03*
X1171455Y1093897D03*
Y1097637D03*
X1163975Y1093897D03*
Y1097637D03*
X1169586Y1121948D03*
X1165846D03*
X1162106D03*
X1158365D03*
X1173326D03*
X1171456Y1108858D03*
X1167716D03*
X1163976D03*
X1160235D03*
X1162106Y1133169D03*
X1165846D03*
X1169586D03*
X1158365Y1140649D03*
X1162106D03*
X1165846D03*
X1169586D03*
X1158365Y1125688D03*
X1162106D03*
X1165846D03*
X1169586D03*
X1173326Y1133169D03*
Y1125688D03*
Y1140649D03*
X1158365Y1133169D03*
X1173326Y1148129D03*
X1158365D03*
X1162106D03*
X1165846D03*
X1169586D03*
X1162106Y1155610D03*
X1169586D03*
X1158365Y1170570D03*
X1165846D03*
X1169586Y1166830D03*
X1158365Y1159350D03*
X1162106Y1166830D03*
X1165846Y1159350D03*
X1173326D03*
Y1170570D03*
Y1189271D03*
X1158365Y1181791D03*
X1162106D03*
X1165846D03*
X1169586D03*
X1158365Y1189271D03*
X1162106D03*
X1165846D03*
X1169586D03*
X1173326Y1181791D03*
X1169586Y1174310D03*
X1162106D03*
Y1204232D03*
X1158365D03*
X1169586D03*
X1165846D03*
X1158365Y1196751D03*
X1162106D03*
X1165846D03*
X1169586D03*
X1173326Y1204232D03*
Y1196751D03*
X1158365Y1211712D03*
Y1207972D03*
X1173326D03*
Y1211712D03*
X1162106Y1207972D03*
X1165846D03*
X1169586Y1211712D03*
Y1207972D03*
X1171456Y1221062D03*
X1167716D03*
X1163976D03*
X1160235D03*
X1163976Y1228543D03*
Y1224803D03*
X1171456Y1228543D03*
Y1224803D03*
X1167716Y1232283D03*
Y1236023D03*
X1160235Y1232283D03*
Y1236023D03*
X1171456Y1239763D03*
X1160235D03*
X1167716Y1247243D03*
X1160235D03*
Y1243503D03*
X1167716D03*
X1171456Y1258465D03*
X1163976D03*
X1162633Y1348187D03*
X1170513D03*
X1158273D03*
X1162633Y1360099D03*
X1170513D03*
X1158273D03*
X1162633Y1372385D03*
Y1384297D03*
X1170513Y1372385D03*
Y1384297D03*
X1158273D03*
Y1372385D03*
X1162633Y1396583D03*
X1170513D03*
X1158273D03*
X1162633Y1408495D03*
X1170513D03*
X1158273D03*
X1175196Y1075196D03*
X1182676D03*
X1186416Y1071455D03*
X1178935D03*
Y1075196D03*
X1186416D03*
X1175196Y1078936D03*
Y1090157D03*
X1178936D03*
X1182676Y1078936D03*
X1178936Y1086417D03*
X1182676Y1090157D03*
X1186417D03*
Y1086417D03*
Y1082677D03*
X1175195Y1086417D03*
X1182675Y1086416D03*
X1175195Y1082677D03*
X1178935Y1078936D03*
X1182675Y1082676D03*
X1186416Y1078936D03*
X1175196Y1097637D03*
Y1093897D03*
X1182676Y1097637D03*
Y1093897D03*
X1178936Y1105117D03*
X1186417D03*
X1188287Y1118208D03*
X1184546D03*
X1180806Y1121948D03*
X1177066D03*
X1184546D03*
X1186417Y1108858D03*
X1182676D03*
X1178936D03*
X1175196D03*
X1188287Y1125688D03*
X1184546Y1136909D03*
X1177066Y1133169D03*
X1180806D03*
X1184546D03*
X1177066Y1140649D03*
X1180806D03*
X1184546Y1125688D03*
Y1129429D03*
X1177066Y1125688D03*
X1180806D03*
X1184546Y1140649D03*
X1188287Y1155610D03*
Y1151869D03*
Y1148129D03*
X1177066D03*
X1180806D03*
X1184546Y1144389D03*
Y1148129D03*
Y1151869D03*
X1177066Y1155610D03*
X1184546D03*
X1177066Y1166830D03*
X1188287D03*
Y1159350D03*
Y1170570D03*
Y1181791D03*
Y1174310D03*
X1177066Y1189271D03*
X1180806D03*
X1184546Y1178051D03*
X1177066Y1174310D03*
X1184546Y1185531D03*
X1177066Y1181791D03*
X1180806D03*
X1184546Y1189271D03*
Y1174310D03*
Y1204232D03*
X1177066D03*
X1180806D03*
X1184546Y1200491D03*
X1177066Y1196751D03*
X1180806D03*
X1184546Y1193011D03*
X1188287Y1196751D03*
X1184566Y1196732D03*
X1188287Y1207972D03*
X1184546Y1211712D03*
X1177066Y1207972D03*
Y1211712D03*
X1180806Y1207972D03*
Y1211712D03*
X1184546Y1207972D03*
X1186417Y1221062D03*
X1182676D03*
X1178936D03*
X1175196D03*
Y1232283D03*
Y1236023D03*
X1178936Y1228543D03*
Y1224803D03*
X1182676Y1232283D03*
Y1236023D03*
X1186417Y1228543D03*
Y1224803D03*
X1182676Y1239763D03*
X1175196Y1243503D03*
X1182676Y1247243D03*
Y1243503D03*
X1175196Y1247243D03*
X1186417Y1258465D03*
X1178936D03*
X1182753Y1348187D03*
X1174873D03*
X1182753Y1360099D03*
X1174873D03*
X1182753Y1384297D03*
Y1372385D03*
X1174873Y1384297D03*
Y1372385D03*
X1182753Y1396583D03*
X1174873D03*
X1182753Y1408495D03*
X1174873D03*
X1179329Y1728990D03*
Y1738990D03*
X1179123Y1776014D03*
Y1786014D03*
X1190157Y1075196D03*
X1197637D03*
X1205117D03*
X1201376Y1071455D03*
X1193896D03*
Y1075196D03*
X1201376D03*
X1190157Y1090157D03*
X1197637Y1078936D03*
Y1090157D03*
X1201377D03*
X1205116D03*
X1193897D03*
X1190155Y1086417D03*
X1205116Y1082677D03*
X1190155D03*
X1197636Y1082676D03*
X1193896Y1078936D03*
X1205116Y1086417D03*
X1201376Y1078936D03*
X1197636Y1086416D03*
X1190157Y1093897D03*
X1201377Y1101377D03*
X1205117Y1093897D03*
X1201377Y1105117D03*
X1193897D03*
X1192027Y1118208D03*
X1205117Y1123818D03*
Y1120078D03*
Y1116338D03*
Y1108858D03*
X1201377D03*
X1197637D03*
X1193897D03*
X1190157D03*
X1192027Y1136909D03*
X1195767Y1140649D03*
X1192027D03*
X1195767Y1136909D03*
X1205117Y1135039D03*
Y1131299D03*
Y1127558D03*
X1195767Y1148129D03*
X1192027Y1144389D03*
X1195767Y1155610D03*
X1192027Y1148129D03*
X1195767Y1151869D03*
X1199507D03*
X1203247D03*
Y1155610D03*
X1192027Y1151870D03*
X1195767Y1170570D03*
Y1159350D03*
X1203247Y1166830D03*
Y1170570D03*
Y1159350D03*
X1195767Y1166830D03*
X1192027Y1181791D03*
X1199507Y1185531D03*
X1203247Y1174310D03*
Y1178051D03*
Y1185531D03*
X1192027Y1178051D03*
Y1189271D03*
X1195767D03*
X1192027Y1185531D03*
X1195767D03*
X1199507Y1181791D03*
X1195767Y1178051D03*
Y1174310D03*
Y1204232D03*
X1199507Y1193011D03*
X1195767Y1196751D03*
Y1193011D03*
X1192027D03*
X1205117Y1198621D03*
Y1202362D03*
X1192027Y1211712D03*
X1205117Y1206102D03*
Y1209842D03*
Y1213582D03*
Y1217322D03*
Y1221062D03*
X1201377D03*
X1197637D03*
X1193897D03*
X1190157D03*
Y1232283D03*
Y1236023D03*
X1197637Y1232283D03*
X1201377Y1228543D03*
X1197637Y1236023D03*
X1201377Y1224803D03*
X1205117Y1232283D03*
Y1236023D03*
X1193897Y1228543D03*
Y1224803D03*
X1197637Y1239763D03*
X1205117D03*
X1190157Y1243503D03*
X1197637Y1247243D03*
Y1243503D03*
X1190157Y1247243D03*
X1205117Y1243503D03*
Y1247243D03*
X1201377Y1258465D03*
X1193897D03*
X1212598Y1075196D03*
X1220079D03*
X1216338Y1071455D03*
X1208857D03*
X1216337Y1075196D03*
X1208857D03*
X1220079Y1078936D03*
X1212599D03*
X1212597Y1090157D03*
Y1082676D03*
Y1086416D03*
X1220077Y1086417D03*
X1208857Y1078936D03*
X1216337D03*
X1220077Y1082677D03*
X1212598Y1093897D03*
X1220078D03*
X1216338Y1105117D03*
X1208858D03*
X1212598Y1108858D03*
X1216338Y1116338D03*
Y1123818D03*
X1208857Y1112598D03*
Y1120078D03*
X1220077Y1108857D03*
X1208858Y1108858D03*
X1214468Y1140649D03*
X1206987Y1136909D03*
X1216338Y1131299D03*
X1206987Y1151869D03*
X1214468Y1148129D03*
X1206987Y1144389D03*
Y1159350D03*
X1214468D03*
X1206987Y1166830D03*
X1214468D03*
X1221948Y1170570D03*
X1206987Y1181791D03*
X1214468Y1189271D03*
X1221948Y1178051D03*
Y1185531D03*
X1206987Y1174310D03*
Y1189271D03*
X1214468Y1181791D03*
Y1174310D03*
X1208858Y1194881D03*
X1221948Y1193011D03*
X1212598Y1202362D03*
X1220078Y1198621D03*
Y1221062D03*
X1216338D03*
X1220078Y1213582D03*
X1212598Y1209842D03*
X1208858Y1221062D03*
Y1217322D03*
X1216338Y1224803D03*
Y1228543D03*
X1212598Y1232283D03*
Y1236023D03*
X1220078Y1232283D03*
Y1236023D03*
X1208858Y1224803D03*
Y1228543D03*
X1212598Y1239763D03*
Y1243503D03*
X1220078Y1247243D03*
Y1243503D03*
X1212598Y1247243D03*
X1208858Y1254724D03*
Y1250984D03*
X1216338Y1254724D03*
Y1250984D03*
Y1258465D03*
X1208858D03*
X1227559Y1075196D03*
X1235039D03*
X1231298Y1071455D03*
X1223818D03*
X1231297Y1075196D03*
X1223817D03*
X1235039Y1078936D03*
X1227559D03*
X1227557Y1090157D03*
X1231297Y1078936D03*
X1227557Y1086417D03*
X1223817Y1078936D03*
X1227557Y1082677D03*
X1227558Y1093897D03*
X1223818Y1105117D03*
X1227558Y1108858D03*
X1233169Y1140649D03*
Y1155610D03*
Y1148129D03*
X1236909Y1170570D03*
X1225688Y1166830D03*
X1233169Y1170570D03*
X1236909Y1178051D03*
Y1185531D03*
X1233169D03*
Y1178051D03*
X1225688Y1174310D03*
Y1181791D03*
Y1189271D03*
X1233169Y1193011D03*
X1223818Y1194881D03*
X1236909Y1193011D03*
X1223818Y1202362D03*
Y1198621D03*
X1235039Y1202362D03*
X1223818Y1206102D03*
Y1221062D03*
Y1217322D03*
Y1213582D03*
Y1209842D03*
X1227558Y1221062D03*
X1235039Y1209842D03*
Y1206102D03*
X1223818Y1224803D03*
Y1228543D03*
X1231298Y1224803D03*
Y1228543D03*
X1227558Y1236023D03*
Y1232283D03*
X1235039D03*
X1225688Y1222932D03*
X1223818Y1239763D03*
X1227558Y1247243D03*
X1231298Y1254724D03*
X1223818D03*
Y1250984D03*
X1235039Y1239763D03*
X1227558Y1243503D03*
X1231298Y1250984D03*
Y1258465D03*
X1223818D03*
X1235966Y1348187D03*
X1228086D03*
X1235966Y1360099D03*
X1228086D03*
X1235966Y1372385D03*
Y1384297D03*
X1228086Y1372385D03*
Y1384297D03*
X1238779Y1078936D03*
X1242520Y1090158D03*
Y1082677D03*
Y1101378D03*
Y1123819D03*
Y1116339D03*
Y1108859D03*
Y1131300D03*
X1240589Y1193011D03*
X1238779Y1202362D03*
X1242520Y1198621D03*
Y1221062D03*
Y1213582D03*
Y1206102D03*
Y1228543D03*
X1238779Y1250984D03*
X1242520Y1247243D03*
Y1239762D03*
X1238779Y1239763D03*
X1252566Y1348187D03*
X1240326D03*
X1248206D03*
X1252566Y1360099D03*
X1240326D03*
X1248206D03*
X1252566Y1372385D03*
Y1384297D03*
X1240326D03*
Y1372385D03*
X1248206D03*
Y1384297D03*
X1252566Y1396583D03*
X1240326D03*
X1248206D03*
X1252566Y1408495D03*
X1240326D03*
X1248206D03*
X1264806Y1348187D03*
X1260446D03*
X1264806Y1360099D03*
X1260446D03*
X1264806Y1372385D03*
Y1384297D03*
X1260446Y1372385D03*
Y1384297D03*
X1264806Y1396583D03*
X1260446D03*
X1264806Y1408495D03*
X1260446D03*
X1284926Y1348187D03*
X1277046D03*
X1272686D03*
X1284926Y1360099D03*
X1277046D03*
X1272686D03*
X1284926Y1372385D03*
Y1384297D03*
X1277046Y1372385D03*
Y1384297D03*
X1272686D03*
Y1372385D03*
X1284926Y1396583D03*
X1277046D03*
X1272686D03*
X1284926Y1408495D03*
X1277046D03*
X1272686D03*
X1301526Y1348187D03*
X1289286D03*
X1297166D03*
X1301526Y1360099D03*
X1289286D03*
X1297166D03*
X1301526Y1372385D03*
Y1384297D03*
X1289286D03*
Y1372385D03*
X1297166Y1384297D03*
Y1372385D03*
X1301526Y1396583D03*
X1289286D03*
X1297166D03*
X1301526Y1408495D03*
X1289286D03*
X1297166D03*
X1313766Y1348187D03*
X1309406D03*
X1313766Y1360099D03*
X1309406D03*
X1313766Y1372385D03*
Y1384297D03*
X1309406Y1372385D03*
Y1384297D03*
X1313766Y1396583D03*
X1309406D03*
X1313766Y1408495D03*
X1309406D03*
X1333886Y1348187D03*
X1326006D03*
X1321646D03*
X1333886Y1360099D03*
X1326006D03*
X1321646D03*
X1333886Y1372385D03*
Y1384297D03*
X1326006Y1372385D03*
Y1384297D03*
X1321646D03*
Y1372385D03*
X1333886Y1396583D03*
X1326006D03*
X1321646D03*
X1333886Y1408495D03*
X1326006D03*
X1321646D03*
X1350486Y1348187D03*
X1338246D03*
X1346126D03*
X1350486Y1360099D03*
X1338246D03*
X1346126D03*
X1350486Y1372385D03*
Y1384297D03*
X1338246D03*
Y1372385D03*
X1346126Y1384297D03*
Y1372385D03*
X1350486Y1396583D03*
X1338246D03*
X1346126D03*
X1350486Y1408495D03*
X1338246D03*
X1346126D03*
X1358366Y1348187D03*
Y1360099D03*
Y1372385D03*
Y1384297D03*
Y1396583D03*
Y1408495D03*
X1459130Y1348187D03*
Y1360099D03*
Y1384297D03*
Y1372385D03*
X1479250Y1348187D03*
X1471370D03*
X1467010D03*
X1479250Y1360099D03*
X1471370D03*
X1467010D03*
X1479250Y1384297D03*
Y1372385D03*
X1471370D03*
Y1384297D03*
X1467010D03*
Y1372385D03*
X1479250Y1396583D03*
X1471370D03*
X1479250Y1408495D03*
X1471370D03*
X1495850Y1348187D03*
X1483610D03*
X1491490D03*
X1495850Y1360099D03*
X1483610D03*
X1491490D03*
X1483610Y1384297D03*
Y1372385D03*
X1491490Y1384297D03*
Y1372385D03*
X1495850Y1384297D03*
Y1372385D03*
Y1396583D03*
X1483610D03*
X1491490D03*
X1495850Y1408495D03*
X1483610D03*
X1491490D03*
X1514468Y1103247D03*
Y1125688D03*
Y1133169D03*
Y1140649D03*
Y1144389D03*
Y1151870D03*
Y1159350D03*
X1512597Y1198622D03*
Y1191142D03*
Y1221063D03*
Y1213583D03*
Y1206103D03*
X1508090Y1348187D03*
X1503730D03*
X1508090Y1360099D03*
X1503730D03*
X1508090Y1384297D03*
Y1372385D03*
X1503730D03*
Y1384297D03*
X1508090Y1396583D03*
X1503730D03*
X1508090Y1408495D03*
X1503730D03*
X1521948Y1077066D03*
X1518208Y1080806D03*
Y1103247D03*
X1529429Y1106988D03*
Y1118208D03*
Y1121948D03*
X1525689D03*
X1521949D03*
X1529429Y1125688D03*
X1518208D03*
X1525689Y1129429D03*
X1521949D03*
X1518208Y1133169D03*
X1521949Y1136909D03*
X1529429Y1140649D03*
X1525689D03*
X1521949D03*
X1518208D03*
X1521949Y1144389D03*
X1518208D03*
X1521949Y1148129D03*
Y1151870D03*
X1518208D03*
X1529429Y1155610D03*
X1525689D03*
X1521949D03*
Y1159350D03*
X1518208D03*
X1529429Y1166830D03*
X1521948D03*
X1525689Y1170570D03*
X1521948D03*
Y1174310D03*
X1518207D03*
X1521948Y1178051D03*
X1525689Y1174310D03*
X1529429D03*
X1527559Y1179921D03*
X1523819D03*
X1518207Y1181791D03*
X1516338Y1187401D03*
X1520078D03*
X1527559Y1183661D03*
X1523819D03*
X1520078D03*
X1516338D03*
X1523819Y1187401D03*
X1527559D03*
X1516338Y1194881D03*
Y1202362D03*
X1527559Y1191141D03*
X1523819D03*
X1527559Y1198621D03*
X1523819D03*
X1520078Y1194881D03*
Y1202362D03*
X1516338Y1198621D03*
X1523819Y1194881D03*
X1520078Y1198621D03*
X1523819Y1202362D03*
X1516338Y1191141D03*
X1527559Y1202362D03*
Y1194881D03*
X1520078Y1191141D03*
X1516338Y1209842D03*
Y1217322D03*
X1523819Y1206102D03*
X1527559D03*
Y1213582D03*
X1523819D03*
X1520078Y1209842D03*
Y1217322D03*
X1523819Y1221062D03*
X1527559D03*
X1520078D03*
X1516338Y1213582D03*
Y1206102D03*
X1520078D03*
X1527559Y1217322D03*
X1523819Y1209842D03*
X1516338Y1221062D03*
X1527559Y1209842D03*
X1523819Y1217322D03*
X1520078Y1213582D03*
X1527559Y1228543D03*
X1516338Y1232283D03*
Y1236023D03*
Y1224803D03*
X1527559Y1236023D03*
Y1232283D03*
X1523819Y1228543D03*
Y1224803D03*
X1520078Y1236023D03*
Y1232283D03*
Y1224803D03*
X1527559D03*
X1516338Y1239763D03*
X1523819D03*
Y1243503D03*
X1520078Y1239763D03*
Y1247243D03*
X1516338D03*
X1527559Y1243503D03*
Y1247243D03*
X1523819Y1250984D03*
Y1254724D03*
Y1258465D03*
X1528210Y1348187D03*
X1520330D03*
X1515970D03*
X1528210Y1360099D03*
X1520330D03*
X1515970D03*
X1528210Y1372385D03*
Y1384297D03*
X1520330Y1372385D03*
Y1384297D03*
X1515970D03*
Y1372385D03*
X1528210Y1396583D03*
X1520330D03*
X1515970D03*
X1528210Y1408495D03*
X1520330D03*
X1515970D03*
X1546258Y1071455D03*
X1540649Y1092027D03*
X1546259Y1090157D03*
X1544389Y1099507D03*
X1540649Y1106988D03*
X1536909D03*
X1533169D03*
X1544389D03*
X1540649Y1095767D03*
X1546259Y1101377D03*
Y1105117D03*
X1544389Y1118208D03*
X1540649D03*
X1544389Y1110728D03*
X1540649D03*
X1536909Y1114468D03*
X1533169D03*
X1544389Y1140649D03*
X1540649D03*
X1536909D03*
X1533169D03*
X1536909Y1129429D03*
X1544389Y1144389D03*
X1540649D03*
X1533169D03*
Y1148129D03*
Y1151870D03*
Y1155610D03*
X1544389Y1148129D03*
Y1155610D03*
Y1151870D03*
X1533169Y1159350D03*
X1544389D03*
Y1166830D03*
Y1170570D03*
X1535039Y1187401D03*
X1533169Y1174310D03*
Y1178051D03*
X1544389Y1174310D03*
Y1178051D03*
Y1181791D03*
X1540649D03*
X1538779Y1179921D03*
X1531299D03*
Y1187401D03*
X1546259D03*
X1542519D03*
Y1183661D03*
X1538779D03*
X1535039D03*
X1531299D03*
X1538779Y1187401D03*
X1542519Y1191141D03*
X1538779Y1202362D03*
X1535039Y1194881D03*
X1542519Y1198621D03*
X1535039Y1191141D03*
X1531299D03*
X1535039Y1198621D03*
X1531299D03*
X1538779Y1191141D03*
X1542519Y1194881D03*
X1546259D03*
X1542519Y1202362D03*
X1546259D03*
Y1198621D03*
Y1191141D03*
X1535039Y1202362D03*
X1538779Y1194881D03*
X1542519Y1213582D03*
Y1206102D03*
X1546259Y1213582D03*
X1535039Y1209842D03*
X1531299Y1206102D03*
X1535039D03*
X1538779D03*
X1542519Y1209842D03*
X1531299Y1221062D03*
X1535039D03*
X1546259Y1217322D03*
Y1221062D03*
X1542519D03*
Y1217322D03*
X1535039D03*
X1546259Y1206102D03*
X1538779Y1209842D03*
Y1217322D03*
X1535039Y1224803D03*
X1542519Y1228543D03*
X1535039D03*
X1531299Y1224803D03*
X1535039Y1232283D03*
Y1236023D03*
X1542519Y1232283D03*
Y1236023D03*
X1538779Y1224803D03*
X1546259D03*
X1542519D03*
X1535039Y1239763D03*
X1531299D03*
Y1243503D03*
X1538779Y1239763D03*
Y1243503D03*
X1542519Y1250984D03*
Y1239763D03*
X1546259D03*
Y1247243D03*
Y1250984D03*
X1542519Y1243503D03*
X1546259Y1254724D03*
X1542519Y1247243D03*
X1538779Y1250984D03*
Y1254724D03*
X1535039Y1243503D03*
X1531299Y1250984D03*
X1535039Y1247243D03*
X1531299Y1254724D03*
X1546260Y1258465D03*
X1538779D03*
X1531299D03*
X1544810Y1348187D03*
X1532570D03*
X1540450D03*
X1544810Y1360099D03*
X1532570D03*
X1540450D03*
X1544810Y1384297D03*
Y1372385D03*
X1532570Y1384297D03*
Y1372385D03*
X1540450Y1384297D03*
Y1372385D03*
X1544810Y1396583D03*
X1532570D03*
X1540450D03*
X1544810Y1408495D03*
X1532570D03*
X1540450D03*
X1561219Y1071455D03*
X1553739D03*
X1561220Y1090157D03*
X1557480D03*
X1553740D03*
X1550000D03*
X1561220Y1093897D03*
Y1105117D03*
X1553740D03*
X1561220Y1101377D03*
X1557480Y1097637D03*
Y1093897D03*
X1553740Y1101377D03*
X1550000Y1093897D03*
Y1097637D03*
X1551870Y1114468D03*
X1548130D03*
X1563090Y1118208D03*
X1559350D03*
X1555610D03*
X1551870D03*
X1548130D03*
X1563090Y1121948D03*
X1559350D03*
X1555610D03*
X1551870D03*
X1548130D03*
Y1110728D03*
X1561220Y1108858D03*
X1557480D03*
X1553740D03*
X1550000D03*
X1551870Y1110728D03*
X1548130Y1140649D03*
X1563090Y1125688D03*
X1559350D03*
X1555610D03*
X1551870D03*
X1548130D03*
X1559350Y1129429D03*
X1555610D03*
X1551870D03*
X1548130D03*
X1559350Y1133169D03*
X1555610D03*
X1551870D03*
X1548130D03*
X1559350Y1136909D03*
X1551870D03*
X1548130D03*
X1559350Y1140649D03*
X1555610D03*
X1551870D03*
Y1155610D03*
Y1151870D03*
X1559350Y1144389D03*
X1551870D03*
Y1148129D03*
X1559350Y1151870D03*
X1563090Y1155610D03*
Y1148129D03*
X1559350Y1170570D03*
X1551870Y1166830D03*
X1559350Y1159350D03*
X1551870D03*
X1548130Y1170570D03*
X1563090Y1166830D03*
X1551870Y1189271D03*
X1559350Y1185531D03*
X1551870D03*
Y1178051D03*
Y1174310D03*
Y1181791D03*
X1563090D03*
Y1174310D03*
X1550000Y1187401D03*
X1548130Y1185531D03*
X1551870Y1193011D03*
X1559350Y1196751D03*
Y1200491D03*
X1555610D03*
Y1204232D03*
X1559350D03*
X1563090D03*
Y1196751D03*
Y1200491D03*
X1555610Y1193011D03*
Y1196751D03*
X1550000Y1191141D03*
Y1194881D03*
Y1198621D03*
Y1202362D03*
X1555610Y1211712D03*
X1559350D03*
X1563090D03*
Y1207972D03*
X1559350D03*
X1555610D03*
X1563090Y1219192D03*
X1550000Y1221062D03*
X1553740D03*
X1557480D03*
X1561220D03*
X1550000Y1206102D03*
Y1209842D03*
Y1213582D03*
Y1217322D03*
X1553740D03*
X1550000Y1228543D03*
Y1224803D03*
X1557480Y1228543D03*
X1550000Y1232283D03*
Y1236023D03*
X1561220Y1224803D03*
X1557480Y1232283D03*
Y1236023D03*
X1553740Y1224803D03*
X1557480D03*
Y1239763D03*
X1561220Y1243503D03*
X1553740D03*
X1561220Y1250984D03*
Y1254724D03*
X1550000Y1243503D03*
X1557480Y1247243D03*
X1550000D03*
X1557480Y1243503D03*
X1553740Y1250984D03*
Y1254724D03*
X1561220Y1258465D03*
X1553740D03*
X1557050Y1348187D03*
X1552690D03*
Y1360099D03*
X1557050D03*
Y1384297D03*
Y1372385D03*
X1552690D03*
Y1384297D03*
X1557050Y1396583D03*
X1552690D03*
X1557050Y1408495D03*
X1552690D03*
X1576180Y1071455D03*
X1568699D03*
X1564960Y1090157D03*
X1572441D03*
X1576181D03*
X1568700D03*
X1576181Y1105117D03*
X1568700D03*
X1564960Y1093897D03*
Y1097637D03*
X1572441Y1093897D03*
Y1097637D03*
X1576181Y1101377D03*
X1568700D03*
X1566830Y1121948D03*
X1578051Y1118208D03*
X1574311D03*
Y1121948D03*
X1578051D03*
X1570571Y1118208D03*
X1566830D03*
X1570571Y1121948D03*
X1576181Y1108858D03*
X1572441D03*
X1568700D03*
X1564960D03*
X1566830Y1133169D03*
Y1129429D03*
X1570571Y1140649D03*
X1574311D03*
X1578051D03*
X1570571Y1125688D03*
X1574311D03*
X1578051D03*
X1566830D03*
X1578051Y1133169D03*
X1574311D03*
X1570571D03*
X1566830Y1136909D03*
X1574311Y1148129D03*
X1570571D03*
X1578051D03*
X1570571Y1155610D03*
X1566830Y1151869D03*
X1578051Y1155610D03*
X1566830Y1144389D03*
Y1159350D03*
X1578051Y1166830D03*
X1574311Y1159350D03*
X1570571Y1166830D03*
X1566830Y1170570D03*
X1574311D03*
X1578051Y1181791D03*
X1574311D03*
X1570571D03*
X1578051Y1189271D03*
X1574311D03*
X1570571D03*
X1566830D03*
Y1178051D03*
X1570571Y1174310D03*
X1566830Y1185531D03*
X1578051Y1174310D03*
X1574311Y1204232D03*
X1578051D03*
Y1196751D03*
X1574311D03*
X1570571D03*
X1566830Y1200491D03*
Y1196751D03*
Y1193011D03*
Y1204232D03*
X1570571D03*
X1566830Y1207972D03*
Y1211712D03*
X1578051Y1207972D03*
X1574311D03*
X1570571D03*
X1564960Y1221062D03*
X1568700D03*
X1572441D03*
X1576181D03*
X1572441Y1228543D03*
X1564960Y1224803D03*
Y1232283D03*
Y1236023D03*
X1576181Y1224803D03*
X1572441Y1232283D03*
Y1236023D03*
X1568700Y1224803D03*
X1572441D03*
X1564960Y1228543D03*
Y1239763D03*
X1576181Y1243503D03*
X1568700D03*
Y1239763D03*
Y1254724D03*
X1572441Y1247243D03*
X1576181Y1254724D03*
X1564960Y1243503D03*
Y1247243D03*
X1576181Y1250984D03*
X1572441Y1243503D03*
X1568700Y1250984D03*
X1576181Y1258465D03*
X1568701D03*
X1564930Y1348187D03*
X1569290D03*
X1577170D03*
X1569290Y1360099D03*
X1577170D03*
X1564930D03*
X1577170Y1372385D03*
Y1384297D03*
X1569290Y1372385D03*
Y1384297D03*
X1564930D03*
Y1372385D03*
X1577170Y1396583D03*
X1569290D03*
X1564930D03*
X1577170Y1408495D03*
X1569290D03*
X1564930D03*
X1591140Y1071455D03*
X1583660D03*
X1579921Y1090157D03*
X1583661D03*
X1587401D03*
X1591141D03*
X1594882D03*
X1583661Y1105117D03*
X1591141D03*
X1579921Y1093897D03*
Y1097637D03*
X1583661Y1101377D03*
X1587401Y1097637D03*
Y1093897D03*
X1594882D03*
Y1097637D03*
X1591141Y1101377D03*
X1581791Y1121948D03*
X1585531Y1118208D03*
X1589271D03*
X1593011D03*
X1589271Y1121948D03*
X1593011D03*
X1585531D03*
X1581791Y1118208D03*
X1594882Y1108858D03*
X1591141D03*
X1587401D03*
X1583661D03*
X1579921D03*
X1587401Y1112598D03*
X1581791Y1133169D03*
Y1140649D03*
X1585531D03*
X1589271D03*
X1593011D03*
X1589271Y1125688D03*
X1585531D03*
X1581791D03*
X1593011D03*
Y1133169D03*
X1589271D03*
X1585531D03*
X1593011Y1148129D03*
X1589271D03*
X1585531D03*
X1581791D03*
X1593011Y1155610D03*
X1585531D03*
X1589271Y1170570D03*
X1593012Y1166830D03*
X1585531D03*
X1581791Y1159350D03*
X1589271D03*
X1581791Y1170570D03*
X1593011Y1181791D03*
X1589271D03*
X1585531D03*
X1581791D03*
X1593011Y1189271D03*
X1589271D03*
X1585531D03*
X1581791D03*
X1585531Y1174310D03*
X1593011D03*
Y1204232D03*
Y1196751D03*
X1589271D03*
X1585531D03*
X1581791D03*
Y1204232D03*
X1585531D03*
X1589271D03*
X1593011Y1219192D03*
X1591141Y1217322D03*
X1593011Y1207972D03*
X1589271D03*
X1585531D03*
X1581791D03*
X1591141Y1221062D03*
X1587401D03*
X1579921D03*
X1583661D03*
X1594882D03*
Y1224803D03*
X1579921Y1228543D03*
X1594882D03*
X1583661Y1224803D03*
X1579921Y1232283D03*
Y1236023D03*
X1594882Y1232283D03*
Y1236023D03*
X1591141Y1224803D03*
X1587401Y1232283D03*
Y1236023D03*
X1579921Y1224803D03*
X1587401Y1228543D03*
Y1224803D03*
X1583661Y1243503D03*
X1579921Y1239763D03*
X1591141Y1243503D03*
X1594882Y1239763D03*
X1587401D03*
X1583661Y1254724D03*
X1579921Y1247243D03*
X1591141Y1254724D03*
X1587401Y1247243D03*
Y1243503D03*
X1594882D03*
X1579921D03*
X1594882Y1247243D03*
X1583661Y1250984D03*
X1591141D03*
X1591142Y1258465D03*
X1583661D03*
X1589410Y1348187D03*
X1581530D03*
X1589410Y1360099D03*
X1581530D03*
Y1384297D03*
Y1372385D03*
X1589410Y1384297D03*
Y1372385D03*
X1581530Y1396583D03*
X1589410D03*
X1581530Y1408495D03*
X1589410D03*
X1609842Y1075196D03*
X1606101Y1071454D03*
X1598621Y1071455D03*
X1606101Y1075195D03*
X1598622Y1090157D03*
X1606102Y1082677D03*
Y1086417D03*
X1609842Y1090157D03*
X1606102D03*
X1602362D03*
X1609841Y1086416D03*
X1606101Y1078935D03*
X1609841Y1082676D03*
X1598622Y1105117D03*
X1606102D03*
X1598622Y1101377D03*
X1606102D03*
X1609842Y1093897D03*
X1602362D03*
Y1097637D03*
X1596752Y1121948D03*
X1600492Y1118208D03*
Y1114468D03*
X1611712Y1121948D03*
X1607972D03*
X1596752Y1118208D03*
X1600492Y1121948D03*
X1609842Y1108858D03*
X1606102D03*
X1602362D03*
X1598622D03*
X1607972Y1125688D03*
X1611712D03*
X1607972Y1133464D03*
X1611712Y1133169D03*
X1600590Y1132677D03*
X1596752Y1133169D03*
Y1140649D03*
X1600492D03*
Y1125688D03*
X1596752D03*
X1607972Y1140649D03*
X1611712D03*
X1600492Y1148129D03*
X1596752D03*
X1607972D03*
X1611712D03*
X1600492Y1155610D03*
X1611712D03*
X1596752Y1170570D03*
Y1159350D03*
X1611712Y1166830D03*
X1607972Y1170570D03*
X1600492Y1166830D03*
X1607972Y1159350D03*
X1600492Y1181791D03*
X1611712D03*
X1607972D03*
Y1189271D03*
X1611712D03*
X1596752Y1181791D03*
X1600492Y1189271D03*
X1596752D03*
X1600492Y1174310D03*
X1611712D03*
Y1204232D03*
X1607972D03*
Y1196751D03*
X1611712D03*
X1600492D03*
X1596752D03*
Y1204232D03*
X1600492D03*
X1606102Y1221062D03*
X1596752Y1207972D03*
X1607972D03*
X1611712D03*
Y1211712D03*
X1596752Y1219192D03*
X1600492Y1207972D03*
X1598622Y1221062D03*
X1609842D03*
X1602362D03*
Y1224803D03*
X1598622D03*
X1609842Y1232283D03*
Y1236023D03*
X1606102Y1228543D03*
Y1224803D03*
X1602362Y1232283D03*
Y1236023D03*
X1598622Y1243503D03*
X1609842Y1239763D03*
X1602362D03*
X1598622Y1254724D03*
Y1250984D03*
X1609842Y1247243D03*
Y1243503D03*
X1602362Y1247243D03*
Y1243503D03*
X1606102Y1258465D03*
X1598623D03*
X1609158Y1348187D03*
Y1360099D03*
Y1384297D03*
Y1372385D03*
X1624803Y1075196D03*
X1617322D03*
X1621062Y1071455D03*
X1613581D03*
Y1075196D03*
X1621062D03*
X1617322Y1090157D03*
Y1078936D03*
X1613582Y1090157D03*
Y1086417D03*
X1624803Y1078936D03*
X1621063Y1086417D03*
Y1090157D03*
X1624803D03*
X1613581Y1078936D03*
X1624802Y1082676D03*
X1617321Y1082677D03*
X1621062Y1078936D03*
X1617321Y1086417D03*
X1624802Y1086416D03*
X1621062Y1093897D03*
X1617322D03*
Y1097637D03*
X1624803Y1093897D03*
Y1097637D03*
X1621063Y1105117D03*
X1613582D03*
Y1101377D03*
X1621062Y1097637D03*
X1626673Y1121948D03*
X1622933D03*
X1619193D03*
X1615452D03*
X1624803Y1108858D03*
X1621063D03*
X1617322D03*
X1613582D03*
X1615452Y1133169D03*
X1619193D03*
X1622933D03*
X1626673D03*
X1615452Y1140649D03*
X1619193D03*
X1622933D03*
X1626673D03*
X1615452Y1125688D03*
X1619193D03*
X1622933D03*
X1626673D03*
X1615452Y1148129D03*
X1619193D03*
X1622933D03*
X1626673D03*
X1619193Y1155610D03*
X1626673D03*
X1615452Y1170570D03*
X1622933D03*
X1626673Y1166830D03*
X1615452Y1159350D03*
X1619193Y1166830D03*
X1622933Y1159350D03*
X1615452Y1181791D03*
X1619193D03*
X1622933D03*
X1626673D03*
X1615452Y1189271D03*
X1619193D03*
X1622933D03*
X1626673D03*
Y1174310D03*
X1619193D03*
Y1204232D03*
X1615452D03*
X1626673D03*
X1622933D03*
X1615452Y1196751D03*
X1619193D03*
X1622933D03*
X1626673D03*
X1617322Y1221062D03*
X1619193Y1207972D03*
X1622933D03*
X1626673Y1211712D03*
Y1207972D03*
X1615452Y1211712D03*
Y1207972D03*
X1621063Y1221062D03*
X1613582D03*
X1624803D03*
X1613582Y1228543D03*
Y1224803D03*
X1621063Y1228543D03*
Y1224803D03*
X1624803Y1232283D03*
Y1236023D03*
X1617322Y1232283D03*
Y1236023D03*
Y1239763D03*
X1624803Y1247243D03*
Y1243503D03*
X1617322D03*
Y1247243D03*
X1621063Y1258465D03*
X1613582D03*
X1617038Y1348187D03*
X1621398D03*
X1617038Y1360099D03*
X1621398D03*
X1617038Y1384297D03*
Y1372385D03*
X1621398D03*
Y1384297D03*
Y1396583D03*
Y1408495D03*
X1639763Y1075196D03*
X1632283D03*
X1643503Y1071455D03*
X1636022D03*
X1628542D03*
X1636022Y1075196D03*
X1643503D03*
X1628542D03*
X1636023Y1090157D03*
X1643504Y1082677D03*
X1636023Y1086417D03*
X1643504Y1090157D03*
Y1086417D03*
X1639763Y1090157D03*
Y1078936D03*
X1632283D03*
X1628543Y1086417D03*
Y1090157D03*
X1632283D03*
X1632282Y1082677D03*
X1643503Y1078936D03*
X1628542D03*
X1639762Y1086416D03*
X1632282Y1086417D03*
X1636022Y1078936D03*
X1639762Y1082676D03*
X1628542Y1093897D03*
X1632283D03*
Y1097637D03*
X1639763Y1093897D03*
Y1097637D03*
X1628543Y1105117D03*
X1636023D03*
X1643504D03*
X1628542Y1097637D03*
X1641633Y1118208D03*
X1637893Y1121948D03*
X1634153D03*
X1630413D03*
X1641633D03*
X1643504Y1108858D03*
X1639763D03*
X1636023D03*
X1632283D03*
X1628543D03*
X1641633Y1136909D03*
X1630413Y1133169D03*
X1634153D03*
X1637893D03*
X1641633D03*
X1634153Y1140649D03*
X1637893D03*
X1641633Y1125688D03*
Y1129429D03*
X1630413Y1125688D03*
X1634153D03*
X1637893D03*
X1641633Y1140649D03*
X1630413D03*
Y1148129D03*
X1634153D03*
X1637893D03*
X1641633Y1144389D03*
Y1148129D03*
Y1151869D03*
X1634153Y1155610D03*
X1641633D03*
X1634153Y1166830D03*
X1630413Y1159350D03*
Y1170570D03*
X1634153Y1189271D03*
X1637893D03*
X1641633Y1178051D03*
X1634153Y1174310D03*
X1641633Y1185531D03*
X1630413Y1181791D03*
X1634153D03*
X1637893D03*
X1641633Y1189271D03*
X1630413D03*
X1641633Y1174310D03*
X1641653Y1196732D03*
X1641633Y1204232D03*
X1630413D03*
X1634153D03*
X1637893D03*
X1641633Y1200491D03*
X1630413Y1196751D03*
X1634153D03*
X1637893D03*
X1641633Y1193011D03*
Y1211712D03*
X1634153Y1207972D03*
X1630413D03*
X1634153Y1211712D03*
X1637893Y1207972D03*
Y1211712D03*
X1630413D03*
X1641633Y1207972D03*
X1628543Y1221062D03*
X1632283D03*
X1636023D03*
X1639763D03*
X1643504D03*
X1628543Y1228543D03*
Y1224803D03*
X1632283Y1232283D03*
Y1236023D03*
X1636023Y1228543D03*
Y1224803D03*
X1639763Y1232283D03*
Y1236023D03*
X1643504Y1228543D03*
Y1224803D03*
X1628543Y1239763D03*
X1639763D03*
X1632283Y1243503D03*
X1639763D03*
X1632283Y1247243D03*
X1639763D03*
X1643504Y1258465D03*
X1636023D03*
X1628543D03*
X1629278Y1348187D03*
X1641518D03*
X1633638D03*
X1629278Y1360099D03*
X1641518D03*
X1633638D03*
X1629278Y1384297D03*
Y1372385D03*
X1641518Y1384297D03*
Y1372385D03*
X1633638Y1384297D03*
Y1372385D03*
X1629278Y1396583D03*
X1641518D03*
X1633638D03*
Y1408495D03*
X1629278D03*
X1641518D03*
X1647244Y1075196D03*
X1654724D03*
X1658463Y1071455D03*
X1650983D03*
Y1075196D03*
X1658463D03*
X1654724Y1078936D03*
Y1090157D03*
X1658464D03*
X1650984D03*
X1647244D03*
X1654723Y1086416D03*
Y1082676D03*
X1650983Y1078936D03*
X1647242Y1082677D03*
Y1086417D03*
X1658463Y1078936D03*
X1647244Y1093897D03*
X1658464Y1101377D03*
Y1105117D03*
X1650984D03*
X1645374Y1118208D03*
X1649114D03*
X1658464Y1108858D03*
X1654724D03*
X1650984D03*
X1647244D03*
X1649114Y1140649D03*
X1652854Y1136909D03*
X1645374Y1125688D03*
X1649114Y1136909D03*
X1652854Y1140649D03*
X1645374Y1155610D03*
Y1151869D03*
Y1148129D03*
X1652854D03*
X1649114Y1144389D03*
X1652854Y1155610D03*
X1649114Y1148129D03*
X1652854Y1151869D03*
X1656594D03*
X1660334D03*
Y1155610D03*
X1649114Y1151870D03*
X1645374Y1166830D03*
X1652854Y1159350D03*
X1660334Y1166830D03*
Y1170570D03*
X1645374Y1159350D03*
X1660334D03*
X1645374Y1170570D03*
X1652854D03*
Y1166830D03*
Y1185531D03*
X1656594Y1181791D03*
X1652854Y1178051D03*
Y1174310D03*
X1649114Y1181791D03*
X1656594Y1185531D03*
X1660334Y1174310D03*
Y1178051D03*
Y1185531D03*
X1645374Y1181791D03*
Y1174310D03*
X1649114Y1178051D03*
Y1189271D03*
X1652854D03*
X1649114Y1185531D03*
X1656594Y1193011D03*
X1652854Y1204232D03*
Y1196751D03*
Y1193011D03*
X1649114D03*
X1645374Y1196751D03*
X1649114Y1211712D03*
X1645374Y1207972D03*
X1660334Y1215452D03*
Y1211712D03*
X1654724Y1221062D03*
X1658464D03*
X1650984D03*
X1647244D03*
Y1232283D03*
Y1236023D03*
X1654724Y1232283D03*
X1658464Y1228543D03*
X1654724Y1236023D03*
X1658464Y1224803D03*
X1650984Y1228543D03*
Y1224803D03*
X1654724Y1239763D03*
Y1243503D03*
X1647244Y1247243D03*
X1654724D03*
X1647244Y1243503D03*
X1658464Y1258465D03*
X1650984D03*
X1645878Y1348187D03*
X1653758D03*
X1658118D03*
X1645878Y1360099D03*
X1653758D03*
X1658118D03*
X1645878Y1384297D03*
Y1372385D03*
X1653758D03*
Y1384297D03*
X1658118D03*
Y1372385D03*
X1645878Y1396583D03*
X1653758D03*
X1658118D03*
X1645878Y1408495D03*
X1653758D03*
X1658118D03*
X1662204Y1075196D03*
X1669685D03*
X1673425Y1071455D03*
X1665944D03*
X1673424Y1075196D03*
X1665944D03*
X1662203Y1090157D03*
X1669686Y1078936D03*
X1669684Y1090157D03*
X1662203Y1086417D03*
Y1082677D03*
X1669684Y1086416D03*
X1665944Y1078936D03*
X1673424D03*
X1669684Y1082676D03*
X1662204Y1093897D03*
X1669685D03*
X1673425Y1105117D03*
X1665945D03*
X1669685Y1108858D03*
X1673425Y1116338D03*
Y1123818D03*
X1665944Y1112598D03*
Y1120078D03*
X1665945Y1108858D03*
X1662204Y1123818D03*
Y1120078D03*
Y1116338D03*
Y1108858D03*
X1671555Y1140649D03*
X1673425Y1131299D03*
X1662204Y1135039D03*
Y1131299D03*
Y1127558D03*
Y1138779D03*
X1664074Y1151869D03*
X1671555Y1148129D03*
X1664074Y1144389D03*
Y1159350D03*
X1671555D03*
X1664074Y1166830D03*
X1671555D03*
X1664074Y1189271D03*
Y1174310D03*
X1671555Y1181791D03*
Y1174310D03*
X1664074Y1181791D03*
X1671555Y1189271D03*
X1665945Y1194881D03*
X1664074Y1204232D03*
X1669685Y1202362D03*
X1673425Y1221062D03*
X1669685Y1209842D03*
X1665945Y1221062D03*
Y1217322D03*
X1662204Y1221062D03*
Y1232283D03*
Y1236023D03*
X1673425Y1224803D03*
Y1228543D03*
X1669685Y1232283D03*
Y1236023D03*
X1665945Y1224803D03*
Y1228543D03*
X1662204Y1239763D03*
X1669685D03*
X1673425Y1250984D03*
X1662204Y1247243D03*
X1665945Y1254724D03*
X1673425D03*
X1662204Y1243503D03*
X1665945Y1250984D03*
X1669685Y1247243D03*
Y1243503D03*
X1673425Y1258465D03*
X1665945D03*
X1665998Y1348187D03*
X1670358D03*
X1665998Y1360099D03*
X1670358D03*
X1665998Y1384297D03*
Y1372385D03*
X1670358D03*
Y1384297D03*
X1665998Y1396583D03*
X1670358D03*
X1665998Y1408495D03*
X1670358D03*
X1677166Y1075196D03*
X1684646D03*
X1692126D03*
X1688385Y1071455D03*
X1680905D03*
X1680904Y1075196D03*
X1688384D03*
X1677166Y1078936D03*
X1692126D03*
X1684646D03*
X1684644Y1090157D03*
Y1082677D03*
Y1086417D03*
X1680904Y1078936D03*
X1688384D03*
X1677164Y1086417D03*
Y1082677D03*
X1677165Y1093897D03*
X1684645D03*
X1680905Y1105117D03*
X1677164Y1108857D03*
X1684645Y1108858D03*
X1690256Y1140649D03*
Y1155610D03*
Y1148129D03*
X1682775Y1166830D03*
X1679035Y1170570D03*
X1690256D03*
Y1178051D03*
X1682775Y1174310D03*
X1679035Y1178051D03*
X1682775Y1181791D03*
X1679035Y1185531D03*
X1682775Y1189271D03*
X1690256Y1185531D03*
X1680905Y1194881D03*
X1690256Y1193011D03*
X1679035D03*
X1692126Y1202362D03*
X1680905D03*
Y1198621D03*
X1677165D03*
X1684645Y1221062D03*
X1692126Y1209842D03*
X1680905Y1221062D03*
Y1217322D03*
X1677165Y1221062D03*
Y1213582D03*
X1680905D03*
Y1209842D03*
Y1206102D03*
X1692126D03*
X1688385Y1224803D03*
Y1228543D03*
X1684645Y1236023D03*
Y1232283D03*
X1692126D03*
X1680905Y1224803D03*
Y1228543D03*
X1677165Y1232283D03*
Y1236023D03*
X1680905Y1239763D03*
X1684645Y1243503D03*
X1677165D03*
X1684645Y1247243D03*
X1677165D03*
X1688385Y1254724D03*
Y1250984D03*
X1692126Y1239763D03*
X1680905Y1254724D03*
Y1250984D03*
X1688385Y1258465D03*
X1680905D03*
X1678238Y1348187D03*
X1690478D03*
X1682598D03*
X1678238Y1360099D03*
X1690478D03*
X1682598D03*
X1678238Y1372385D03*
Y1384297D03*
X1690478D03*
Y1372385D03*
X1682598Y1384297D03*
Y1372385D03*
X1678238Y1396583D03*
X1690478D03*
X1682598D03*
X1678238Y1408495D03*
X1690478D03*
X1682598D03*
X1695866Y1078936D03*
X1699607Y1090158D03*
Y1082677D03*
Y1101378D03*
Y1123819D03*
Y1116339D03*
Y1108859D03*
Y1131300D03*
X1693996Y1170570D03*
Y1178051D03*
Y1185531D03*
Y1193011D03*
X1697676D03*
X1695866Y1202362D03*
X1699607Y1198621D03*
Y1221062D03*
Y1213582D03*
Y1206102D03*
Y1228543D03*
X1695866Y1250984D03*
X1699607Y1247243D03*
Y1239762D03*
X1695866Y1239763D03*
X1694838Y1348187D03*
X1702718D03*
X1707078D03*
X1702718Y1360099D03*
X1707078D03*
X1694838D03*
Y1384297D03*
Y1372385D03*
X1702718D03*
Y1384297D03*
X1707078D03*
Y1372385D03*
X1694838Y1396583D03*
X1702718D03*
X1707078D03*
X1694838Y1408495D03*
X1702718D03*
X1707078D03*
X1714958Y1348187D03*
X1719318D03*
X1714958Y1360099D03*
X1719318D03*
X1714958Y1384297D03*
Y1372385D03*
X1719318D03*
Y1384297D03*
X1714958Y1396583D03*
X1719318D03*
X1714958Y1408495D03*
X1719318D03*
X1727198Y1348187D03*
X1739438D03*
X1731558D03*
X1727198Y1360099D03*
X1739438D03*
X1731558D03*
X1739438Y1372385D03*
X1731558Y1384297D03*
Y1372385D03*
X1727198D03*
Y1384297D03*
X1739438D03*
X1727198Y1396583D03*
X1739438D03*
X1731558D03*
X1727198Y1408495D03*
X1739438D03*
X1731558D03*
G54D49*
X956448Y-30304D03*
Y-33204D03*
X953192Y-25085D03*
X956445Y-25099D03*
X950167Y-26405D03*
X953207Y-27600D03*
X956460Y-27614D03*
X978036Y-64265D03*
X975011Y-65585D03*
X978051Y-66780D03*
X981289Y-64279D03*
X981292Y-69484D03*
Y-72384D03*
X981304Y-66794D03*
X1231351Y-77080D03*
X1234592Y-79984D03*
X1234604Y-77094D03*
X1234592Y-82584D03*
Y-71970D03*
X1231336Y-74565D03*
X1234589Y-74579D03*
X1231336Y-64265D03*
X1234589D03*
X1234592Y-69470D03*
X1231351Y-66780D03*
X1234604D03*
X1228311Y-65585D03*
Y-75885D03*
X1236692Y-35515D03*
X1236707Y-38030D03*
X1233667Y-36835D03*
X1236692Y-25215D03*
X1236707Y-27730D03*
X1233667Y-26535D03*
X1239948Y-32920D03*
X1239945Y-35529D03*
X1239948Y-30420D03*
Y-40934D03*
X1239960Y-38044D03*
X1239948Y-43534D03*
X1239945Y-25215D03*
X1239960Y-27730D03*
X1487851Y-77080D03*
X1491092Y-79984D03*
X1491104Y-77094D03*
X1491092Y-82584D03*
Y-71970D03*
X1487836Y-74565D03*
X1491089Y-74579D03*
X1487836Y-64265D03*
X1491089D03*
X1491092Y-69470D03*
X1487851Y-66780D03*
X1491104D03*
X1484811Y-65585D03*
Y-75885D03*
X1526448Y-33050D03*
X1523192Y-35645D03*
X1526445Y-35659D03*
X1526448Y-30550D03*
X1523207Y-38160D03*
X1526448Y-41064D03*
X1526460Y-38174D03*
X1526448Y-43664D03*
X1520167Y-36965D03*
X1523192Y-25345D03*
X1526445D03*
X1523207Y-27860D03*
X1526460D03*
X1520167Y-26665D03*
X1742336Y-74565D03*
Y-64265D03*
X1739311Y-65585D03*
Y-75885D03*
X1742351Y-77080D03*
X1745592Y-79984D03*
X1745604Y-77094D03*
X1745592Y-82584D03*
Y-71970D03*
X1745589Y-74579D03*
Y-64265D03*
X1745592Y-69470D03*
X1742351Y-66780D03*
X1745604D03*
X1804667Y-37095D03*
Y-26795D03*
X1810948Y-33180D03*
X1807692Y-35775D03*
X1810945Y-35789D03*
X1810948Y-30680D03*
X1807707Y-38290D03*
X1810948Y-41194D03*
X1810960Y-38304D03*
X1810948Y-43794D03*
X1807692Y-25475D03*
X1810945D03*
X1807707Y-27990D03*
X1810960D03*
G54D23*
X46348Y1727941D03*
Y1737941D03*
Y1773941D03*
Y1783941D03*
X333112Y1751624D03*
Y1761624D03*
X333212Y1797624D03*
Y1807624D03*
X619861Y1751765D03*
Y1761765D03*
X619475Y1798845D03*
Y1808845D03*
X907163Y1752566D03*
Y1762566D03*
X907166Y1800435D03*
Y1810435D03*
G54D38*
X266841Y421555D03*
Y550020D03*
X295856Y421555D03*
Y550020D03*
X723927Y421555D03*
Y550020D03*
X752942Y421555D03*
Y550020D03*
X1181014Y421555D03*
Y550020D03*
X1210029Y421555D03*
Y550020D03*
X1638101Y421555D03*
Y550020D03*
X1667116Y421555D03*
Y550020D03*
G54D54*
X1236871Y1715189D03*
X1236864Y1773377D03*
X1235371Y1802909D03*
G54D55*
X1236871Y1744208D03*
%LPC*%
G75*
G54D62*
G01X-20602Y-468335D02*
Y-543335D01*
X479398D01*
Y-468335D01*
X-20602D01*
G01X-8602Y-533335D02*
Y-538335D01*
G01X-10059Y-533335D02*
X-7145D01*
G01X-2235Y-538335D02*
X-4769D01*
Y-533335D01*
X-2235D01*
G01X-3249Y-535752D02*
X-4769D01*
G01X331Y-533335D02*
Y-538335D01*
X2865D01*
G01X6698Y-538502D02*
X6571Y-538418D01*
Y-538252D01*
X6698Y-538168D01*
X6825Y-538252D01*
Y-538418D01*
X6698Y-538502D01*
G01Y-536252D02*
X6571Y-536168D01*
Y-536002D01*
X6698Y-535918D01*
X6825Y-536002D01*
Y-536168D01*
X6698Y-536252D01*
G01X11481Y-540002D02*
X10848Y-539168D01*
X10531Y-538335D01*
Y-535002D01*
X10848Y-534168D01*
X11481Y-533335D01*
G01X16898D02*
X16391Y-533502D01*
X16011Y-533918D01*
X15758Y-534418D01*
X15568Y-535085D01*
X15505Y-535835D01*
X15568Y-536585D01*
X15758Y-537252D01*
X16011Y-537752D01*
X16391Y-538168D01*
X16898Y-538335D01*
X17405Y-538168D01*
X17785Y-537752D01*
X18038Y-537252D01*
X18228Y-536585D01*
X18291Y-535835D01*
X18228Y-535085D01*
X18038Y-534418D01*
X17785Y-533918D01*
X17405Y-533502D01*
X16898Y-533335D01*
G01X20605Y-537335D02*
X20985Y-537918D01*
X21491Y-538252D01*
X22061Y-538335D01*
X22568Y-538252D01*
X23075Y-537835D01*
X23391Y-537335D01*
X23455Y-536835D01*
X23328Y-536252D01*
X22885Y-535835D01*
X22441Y-535668D01*
X21871D01*
G01X22441D02*
X22821Y-535418D01*
X23138Y-535002D01*
X23265Y-534502D01*
X23138Y-534002D01*
X22821Y-533585D01*
X22251Y-533335D01*
X21681Y-533418D01*
X21111Y-533752D01*
G01X27415Y-540002D02*
X28048Y-539168D01*
X28365Y-538335D01*
Y-535002D01*
X28048Y-534168D01*
X27415Y-533335D01*
G01X30805Y-537335D02*
X31185Y-537918D01*
X31691Y-538252D01*
X32261Y-538335D01*
X32768Y-538252D01*
X33275Y-537835D01*
X33591Y-537335D01*
X33655Y-536835D01*
X33528Y-536252D01*
X33085Y-535835D01*
X32641Y-535668D01*
X32071D01*
G01X32641D02*
X33021Y-535418D01*
X33338Y-535002D01*
X33465Y-534502D01*
X33338Y-534002D01*
X33021Y-533585D01*
X32451Y-533335D01*
X31881Y-533418D01*
X31311Y-533752D01*
G01X36095Y-534168D02*
X36475Y-533668D01*
X36918Y-533418D01*
X37425Y-533335D01*
X38058Y-533502D01*
X38501Y-533918D01*
X38628Y-534418D01*
X38565Y-534918D01*
X38311Y-535335D01*
X37045Y-536168D01*
X36475Y-536752D01*
X36095Y-537585D01*
X35968Y-538335D01*
X38628D01*
G01X42271D02*
X42398Y-537252D01*
X42588Y-536335D01*
X42841Y-535502D01*
X43158Y-534585D01*
X43665Y-533335D01*
X41131D01*
G01X46675Y-536668D02*
X48321D01*
G01X51395Y-534168D02*
X51775Y-533668D01*
X52218Y-533418D01*
X52725Y-533335D01*
X53358Y-533502D01*
X53801Y-533918D01*
X53928Y-534418D01*
X53865Y-534918D01*
X53611Y-535335D01*
X52345Y-536168D01*
X51775Y-536752D01*
X51395Y-537585D01*
X51268Y-538335D01*
X53928D01*
G01X56305Y-537335D02*
X56685Y-537918D01*
X57191Y-538252D01*
X57761Y-538335D01*
X58268Y-538252D01*
X58775Y-537835D01*
X59091Y-537335D01*
X59155Y-536835D01*
X59028Y-536252D01*
X58585Y-535835D01*
X58141Y-535668D01*
X57571D01*
G01X58141D02*
X58521Y-535418D01*
X58838Y-535002D01*
X58965Y-534502D01*
X58838Y-534002D01*
X58521Y-533585D01*
X57951Y-533335D01*
X57381Y-533418D01*
X56811Y-533752D01*
G01X63558Y-538335D02*
Y-533335D01*
X61215Y-536918D01*
X64381D01*
G01X66505Y-537585D02*
X66885Y-538002D01*
X67328Y-538252D01*
X67898Y-538335D01*
X68468Y-538168D01*
X68911Y-537835D01*
X69228Y-537252D01*
X69291Y-536585D01*
X69165Y-535918D01*
X68848Y-535502D01*
X68405Y-535168D01*
X67961Y-535085D01*
X67518Y-535168D01*
X66948Y-535502D01*
X67138Y-533335D01*
X68848D01*
G01X76895Y-538335D02*
Y-533335D01*
X79301D01*
G01X78415Y-535752D02*
X76895D01*
G01X81615Y-538335D02*
X83198Y-533335D01*
X84781Y-538335D01*
G01X84211Y-536585D02*
X82185D01*
G01X86968Y-538335D02*
X89628Y-533335D01*
G01X86968D02*
X89628Y-538335D01*
G01X93398Y-538502D02*
X93271Y-538418D01*
Y-538252D01*
X93398Y-538168D01*
X93525Y-538252D01*
Y-538418D01*
X93398Y-538502D01*
G01Y-536252D02*
X93271Y-536168D01*
Y-536002D01*
X93398Y-535918D01*
X93525Y-536002D01*
Y-536168D01*
X93398Y-536252D01*
G01X98181Y-540002D02*
X97548Y-539168D01*
X97231Y-538335D01*
Y-535002D01*
X97548Y-534168D01*
X98181Y-533335D01*
G01X103598D02*
X103091Y-533502D01*
X102711Y-533918D01*
X102458Y-534418D01*
X102268Y-535085D01*
X102205Y-535835D01*
X102268Y-536585D01*
X102458Y-537252D01*
X102711Y-537752D01*
X103091Y-538168D01*
X103598Y-538335D01*
X104105Y-538168D01*
X104485Y-537752D01*
X104738Y-537252D01*
X104928Y-536585D01*
X104991Y-535835D01*
X104928Y-535085D01*
X104738Y-534418D01*
X104485Y-533918D01*
X104105Y-533502D01*
X103598Y-533335D01*
G01X107305Y-537335D02*
X107685Y-537918D01*
X108191Y-538252D01*
X108761Y-538335D01*
X109268Y-538252D01*
X109775Y-537835D01*
X110091Y-537335D01*
X110155Y-536835D01*
X110028Y-536252D01*
X109585Y-535835D01*
X109141Y-535668D01*
X108571D01*
G01X109141D02*
X109521Y-535418D01*
X109838Y-535002D01*
X109965Y-534502D01*
X109838Y-534002D01*
X109521Y-533585D01*
X108951Y-533335D01*
X108381Y-533418D01*
X107811Y-533752D01*
G01X114115Y-540002D02*
X114748Y-539168D01*
X115065Y-538335D01*
Y-535002D01*
X114748Y-534168D01*
X114115Y-533335D01*
G01X117505Y-537335D02*
X117885Y-537918D01*
X118391Y-538252D01*
X118961Y-538335D01*
X119468Y-538252D01*
X119975Y-537835D01*
X120291Y-537335D01*
X120355Y-536835D01*
X120228Y-536252D01*
X119785Y-535835D01*
X119341Y-535668D01*
X118771D01*
G01X119341D02*
X119721Y-535418D01*
X120038Y-535002D01*
X120165Y-534502D01*
X120038Y-534002D01*
X119721Y-533585D01*
X119151Y-533335D01*
X118581Y-533418D01*
X118011Y-533752D01*
G01X122921Y-537752D02*
X123365Y-538168D01*
X123871Y-538335D01*
X124378Y-538168D01*
X124821Y-537668D01*
X125138Y-536918D01*
X125265Y-536168D01*
Y-535252D01*
X125138Y-534502D01*
X124821Y-533835D01*
X124441Y-533502D01*
X123998Y-533335D01*
X123491Y-533502D01*
X123111Y-533835D01*
X122858Y-534335D01*
X122731Y-535002D01*
X122858Y-535585D01*
X123175Y-536168D01*
X123555Y-536502D01*
X123998Y-536585D01*
X124505Y-536418D01*
X124885Y-536002D01*
X125265Y-535252D01*
G01X128971Y-538335D02*
X129098Y-537252D01*
X129288Y-536335D01*
X129541Y-535502D01*
X129858Y-534585D01*
X130365Y-533335D01*
X127831D01*
G01X133375Y-536668D02*
X135021D01*
G01X137905Y-537335D02*
X138285Y-537918D01*
X138791Y-538252D01*
X139361Y-538335D01*
X139868Y-538252D01*
X140375Y-537835D01*
X140691Y-537335D01*
X140755Y-536835D01*
X140628Y-536252D01*
X140185Y-535835D01*
X139741Y-535668D01*
X139171D01*
G01X139741D02*
X140121Y-535418D01*
X140438Y-535002D01*
X140565Y-534502D01*
X140438Y-534002D01*
X140121Y-533585D01*
X139551Y-533335D01*
X138981Y-533418D01*
X138411Y-533752D01*
G01X143195Y-536252D02*
X143638Y-535668D01*
X144018Y-535335D01*
X144525Y-535168D01*
X144968Y-535335D01*
X145285Y-535668D01*
X145538Y-536168D01*
X145601Y-536752D01*
X145538Y-537252D01*
X145285Y-537752D01*
X144905Y-538168D01*
X144461Y-538335D01*
X143955Y-538168D01*
X143511Y-537668D01*
X143258Y-536918D01*
X143195Y-536085D01*
X143321Y-535002D01*
X143511Y-534418D01*
X143828Y-533835D01*
X144271Y-533418D01*
X144715Y-533335D01*
X145158Y-533502D01*
X145475Y-533918D01*
G01X149498Y-538335D02*
Y-533335D01*
X148738Y-534335D01*
G01Y-538335D02*
X150258D01*
G01X155358D02*
Y-533335D01*
X153015Y-536918D01*
X156181D01*
G01X174398Y-468335D02*
Y-543335D01*
G01Y-518335D02*
X277398D01*
Y-493335D01*
G01X174398D02*
X277398D01*
G01Y-468335D02*
Y-543335D01*
G01X279398Y-468335D02*
Y-543335D01*
G01X284905Y-528335D02*
Y-523335D01*
X286171D01*
X286678Y-523585D01*
X287058Y-523918D01*
X287375Y-524418D01*
X287628Y-525002D01*
X287691Y-525835D01*
X287628Y-526668D01*
X287375Y-527252D01*
X287058Y-527752D01*
X286678Y-528085D01*
X286171Y-528335D01*
X284905D01*
G01X289815D02*
X291398Y-523335D01*
X292981Y-528335D01*
G01X292411Y-526585D02*
X290385D01*
G01X296498Y-523335D02*
Y-528335D01*
G01X295041Y-523335D02*
X297955D01*
G01X302865Y-528335D02*
X300331D01*
Y-523335D01*
X302865D01*
G01X301851Y-525752D02*
X300331D01*
G01X306698Y-528502D02*
X306571Y-528418D01*
Y-528252D01*
X306698Y-528168D01*
X306825Y-528252D01*
Y-528418D01*
X306698Y-528502D01*
G01Y-526252D02*
X306571Y-526168D01*
Y-526002D01*
X306698Y-525918D01*
X306825Y-526002D01*
Y-526168D01*
X306698Y-526252D01*
G01X279398Y-518335D02*
X479398D01*
G01X285031Y-503335D02*
Y-498335D01*
X286551D01*
X287058Y-498585D01*
X287438Y-499168D01*
X287565Y-499835D01*
X287438Y-500502D01*
X287121Y-501002D01*
X286551Y-501252D01*
X285031D01*
G01X290258Y-503502D02*
X292538Y-498335D01*
G01X295041Y-503335D02*
Y-498335D01*
X297955Y-503335D01*
Y-498335D01*
G01X301598Y-503502D02*
X301471Y-503418D01*
Y-503252D01*
X301598Y-503168D01*
X301725Y-503252D01*
Y-503418D01*
X301598Y-503502D01*
G01Y-501252D02*
X301471Y-501168D01*
Y-501002D01*
X301598Y-500918D01*
X301725Y-501002D01*
Y-501168D01*
X301598Y-501252D01*
G01X279398Y-493335D02*
X479398D01*
G01X285031Y-478335D02*
Y-473335D01*
X286551D01*
X287058Y-473585D01*
X287438Y-474168D01*
X287565Y-474835D01*
X287438Y-475502D01*
X287121Y-476002D01*
X286551Y-476252D01*
X285031D01*
G01X290131Y-478335D02*
Y-473335D01*
X291715D01*
X292221Y-473585D01*
X292538Y-473918D01*
X292665Y-474585D01*
X292538Y-475252D01*
X292158Y-475668D01*
X291715Y-475918D01*
X290131D01*
G01X291715D02*
X292665Y-478335D01*
G01X296498D02*
X295991Y-478252D01*
X295548Y-477918D01*
X295168Y-477418D01*
X294915Y-476835D01*
X294788Y-476168D01*
Y-475502D01*
X294915Y-474835D01*
X295168Y-474252D01*
X295548Y-473752D01*
X295991Y-473418D01*
X296498Y-473335D01*
X297005Y-473418D01*
X297448Y-473752D01*
X297828Y-474252D01*
X298081Y-474835D01*
X298208Y-475502D01*
Y-476168D01*
X298081Y-476835D01*
X297828Y-477418D01*
X297448Y-477918D01*
X297005Y-478252D01*
X296498Y-478335D01*
G01X300331Y-477335D02*
X300648Y-477835D01*
X301028Y-478168D01*
X301471Y-478335D01*
X301978Y-478168D01*
X302358Y-477835D01*
X302738Y-477335D01*
X302865Y-476668D01*
Y-473335D01*
G01X307965Y-478335D02*
X305431D01*
Y-473335D01*
X307965D01*
G01X306951Y-475752D02*
X305431D01*
G01X313191Y-473752D02*
X312811Y-473502D01*
X312368Y-473335D01*
X311861D01*
X311291Y-473585D01*
X310848Y-474002D01*
X310531Y-474502D01*
X310278Y-475335D01*
X310215Y-476085D01*
X310341Y-476835D01*
X310531Y-477335D01*
X310911Y-477835D01*
X311355Y-478168D01*
X311798Y-478335D01*
X312241D01*
X312685Y-478168D01*
X313065Y-477918D01*
X313381Y-477585D01*
G01X316898Y-473335D02*
Y-478335D01*
G01X315441Y-473335D02*
X318355D01*
G01X321998Y-478502D02*
X321871Y-478418D01*
Y-478252D01*
X321998Y-478168D01*
X322125Y-478252D01*
Y-478418D01*
X321998Y-478502D01*
G01Y-476252D02*
X321871Y-476168D01*
Y-476002D01*
X321998Y-475918D01*
X322125Y-476002D01*
Y-476168D01*
X321998Y-476252D01*
G01X394258Y-543563D02*
Y-518563D01*
G01X397031Y-520835D02*
Y-525835D01*
X399565D01*
G01X402638Y-520835D02*
X404158D01*
G01X403398D02*
Y-525835D01*
G01X402638D02*
X404158D01*
G01X409005Y-523168D02*
X409258Y-522918D01*
X409448Y-522502D01*
X409575Y-521918D01*
X409448Y-521418D01*
X409195Y-521085D01*
X408751Y-520835D01*
X407041D01*
Y-525835D01*
X409131D01*
X409575Y-525502D01*
X409828Y-525002D01*
X409955Y-524418D01*
X409828Y-523835D01*
X409448Y-523335D01*
X409005Y-523168D01*
X407041D01*
G01X413598Y-526002D02*
X413471Y-525918D01*
Y-525752D01*
X413598Y-525668D01*
X413725Y-525752D01*
Y-525918D01*
X413598Y-526002D01*
G01Y-523752D02*
X413471Y-523668D01*
Y-523502D01*
X413598Y-523418D01*
X413725Y-523502D01*
Y-523668D01*
X413598Y-523752D01*
G01X437258Y-518563D02*
Y-543563D01*
G01X437398Y-518335D02*
Y-543335D01*
G01X441298Y-520835D02*
Y-525835D01*
G01X439841Y-520835D02*
X442755D01*
G01X446398Y-525835D02*
X446018Y-525752D01*
X445638Y-525418D01*
X445385Y-524835D01*
X445258Y-524168D01*
X445385Y-523502D01*
X445638Y-522918D01*
X446018Y-522585D01*
X446398Y-522502D01*
X446778Y-522585D01*
X447158Y-522918D01*
X447411Y-523502D01*
X447475Y-524168D01*
X447411Y-524835D01*
X447158Y-525418D01*
X446778Y-525752D01*
X446398Y-525835D01*
G01X451498D02*
X451118Y-525752D01*
X450738Y-525418D01*
X450485Y-524835D01*
X450358Y-524168D01*
X450485Y-523502D01*
X450738Y-522918D01*
X451118Y-522585D01*
X451498Y-522502D01*
X451878Y-522585D01*
X452258Y-522918D01*
X452511Y-523502D01*
X452575Y-524168D01*
X452511Y-524835D01*
X452258Y-525418D01*
X451878Y-525752D01*
X451498Y-525835D01*
G01X456598D02*
Y-520835D01*
G01X461698Y-526002D02*
X461571Y-525918D01*
Y-525752D01*
X461698Y-525668D01*
X461825Y-525752D01*
Y-525918D01*
X461698Y-526002D01*
G01Y-523752D02*
X461571Y-523668D01*
Y-523502D01*
X461698Y-523418D01*
X461825Y-523502D01*
Y-523668D01*
X461698Y-523752D01*
G01X437398Y-493335D02*
Y-518335D01*
G01X440031Y-500835D02*
Y-495835D01*
X441615D01*
X442121Y-496085D01*
X442438Y-496418D01*
X442565Y-497085D01*
X442438Y-497752D01*
X442058Y-498168D01*
X441615Y-498418D01*
X440031D01*
G01X441615D02*
X442565Y-500835D01*
G01X447665D02*
X445131D01*
Y-495835D01*
X447665D01*
G01X446651Y-498252D02*
X445131D01*
G01X449915Y-495835D02*
X451498Y-500835D01*
X453081Y-495835D01*
G01X456598Y-501002D02*
X456471Y-500918D01*
Y-500752D01*
X456598Y-500668D01*
X456725Y-500752D01*
Y-500918D01*
X456598Y-501002D01*
G01Y-498752D02*
X456471Y-498668D01*
Y-498502D01*
X456598Y-498418D01*
X456725Y-498502D01*
Y-498668D01*
X456598Y-498752D01*
G01X445411Y-546502D02*
X445518Y-546377D01*
X445598Y-546168D01*
X445651Y-545877D01*
X445598Y-545627D01*
X445491Y-545460D01*
X445305Y-545335D01*
X444585D01*
Y-547835D01*
X445465D01*
X445651Y-547668D01*
X445758Y-547418D01*
X445811Y-547127D01*
X445758Y-546835D01*
X445598Y-546585D01*
X445411Y-546502D01*
X444585D01*
G01X447878Y-547835D02*
Y-546168D01*
G01Y-546460D02*
X447771Y-546293D01*
X447611Y-546210D01*
X447425Y-546168D01*
X447238Y-546252D01*
X447078Y-546418D01*
X446971Y-546668D01*
X446918Y-547002D01*
X446971Y-547335D01*
X447078Y-547585D01*
X447238Y-547752D01*
X447425Y-547835D01*
X447611Y-547793D01*
X447771Y-547668D01*
X447878Y-547502D01*
G01X449198Y-547543D02*
X449331Y-547710D01*
X449518Y-547835D01*
X449678D01*
X449838Y-547752D01*
X449945Y-547627D01*
X449998Y-547460D01*
X449971Y-547210D01*
X449865Y-547085D01*
X449385Y-546835D01*
X449278Y-546543D01*
X449331Y-546335D01*
X449438Y-546210D01*
X449598Y-546168D01*
X449758Y-546210D01*
X449918Y-546335D01*
G01X451398Y-546710D02*
X452251D01*
X452171Y-546418D01*
X452038Y-546252D01*
X451851Y-546168D01*
X451665Y-546210D01*
X451505Y-546335D01*
X451398Y-546627D01*
X451345Y-546877D01*
Y-547127D01*
X451398Y-547377D01*
X451531Y-547627D01*
X451691Y-547793D01*
X451878Y-547835D01*
X452065Y-547752D01*
X452251Y-547502D01*
G01X453518Y-547835D02*
Y-545335D01*
G01Y-546585D02*
X453651Y-546335D01*
X453811Y-546210D01*
X453971Y-546168D01*
X454211Y-546252D01*
X454371Y-546418D01*
X454478Y-546710D01*
Y-547043D01*
X454425Y-547377D01*
X454318Y-547627D01*
X454131Y-547793D01*
X453971Y-547835D01*
X453811Y-547793D01*
X453651Y-547668D01*
X453518Y-547460D01*
G01X456198Y-547835D02*
X456038Y-547793D01*
X455878Y-547627D01*
X455771Y-547335D01*
X455718Y-547002D01*
X455771Y-546668D01*
X455878Y-546377D01*
X456038Y-546210D01*
X456198Y-546168D01*
X456358Y-546210D01*
X456518Y-546377D01*
X456625Y-546668D01*
X456651Y-547002D01*
X456625Y-547335D01*
X456518Y-547627D01*
X456358Y-547793D01*
X456198Y-547835D01*
G01X458878D02*
Y-546168D01*
G01Y-546460D02*
X458771Y-546293D01*
X458611Y-546210D01*
X458425Y-546168D01*
X458238Y-546252D01*
X458078Y-546418D01*
X457971Y-546668D01*
X457918Y-547002D01*
X457971Y-547335D01*
X458078Y-547585D01*
X458238Y-547752D01*
X458425Y-547835D01*
X458611Y-547793D01*
X458771Y-547668D01*
X458878Y-547502D01*
G01X460225Y-547835D02*
Y-546168D01*
G01Y-546502D02*
X460358Y-546335D01*
X460491Y-546210D01*
X460678Y-546168D01*
X460811Y-546210D01*
X460971Y-546335D01*
G01X463278Y-545335D02*
Y-547835D01*
G01Y-547460D02*
X463171Y-547668D01*
X463011Y-547793D01*
X462825Y-547835D01*
X462611Y-547752D01*
X462451Y-547543D01*
X462345Y-547293D01*
X462318Y-547002D01*
X462345Y-546710D01*
X462451Y-546460D01*
X462611Y-546252D01*
X462825Y-546168D01*
X463011Y-546210D01*
X463145Y-546293D01*
X463278Y-546460D01*
G01X466665Y-547835D02*
Y-545335D01*
X467331D01*
X467545Y-545460D01*
X467678Y-545627D01*
X467731Y-545960D01*
X467678Y-546293D01*
X467518Y-546502D01*
X467331Y-546627D01*
X466665D01*
G01X467331D02*
X467731Y-547835D01*
G01X468998Y-546710D02*
X469851D01*
X469771Y-546418D01*
X469638Y-546252D01*
X469451Y-546168D01*
X469265Y-546210D01*
X469105Y-546335D01*
X468998Y-546627D01*
X468945Y-546877D01*
Y-547127D01*
X468998Y-547377D01*
X469131Y-547627D01*
X469291Y-547793D01*
X469478Y-547835D01*
X469665Y-547752D01*
X469851Y-547502D01*
G01X471118Y-546168D02*
X471598Y-547835D01*
X472078Y-546168D01*
G01X473798Y-547918D02*
X473745Y-547877D01*
Y-547793D01*
X473798Y-547752D01*
X473851Y-547793D01*
Y-547877D01*
X473798Y-547918D01*
G01X475545Y-547543D02*
X475731Y-547752D01*
X475945Y-547835D01*
X476158Y-547752D01*
X476345Y-547502D01*
X476478Y-547127D01*
X476531Y-546752D01*
Y-546293D01*
X476478Y-545918D01*
X476345Y-545585D01*
X476185Y-545418D01*
X475998Y-545335D01*
X475785Y-545418D01*
X475625Y-545585D01*
X475518Y-545835D01*
X475465Y-546168D01*
X475518Y-546460D01*
X475651Y-546752D01*
X475811Y-546918D01*
X475998Y-546960D01*
X476211Y-546877D01*
X476371Y-546668D01*
X476531Y-546293D01*
G01X478411Y-546502D02*
X478518Y-546377D01*
X478598Y-546168D01*
X478651Y-545877D01*
X478598Y-545627D01*
X478491Y-545460D01*
X478305Y-545335D01*
X477585D01*
Y-547835D01*
X478465D01*
X478651Y-547668D01*
X478758Y-547418D01*
X478811Y-547127D01*
X478758Y-546835D01*
X478598Y-546585D01*
X478411Y-546502D01*
X477585D01*
G01X-1490433Y-1677216D02*
Y3837819D01*
X4496476D01*
Y-1677216D01*
X-1490433D01*
G01X-7782Y-515685D02*
X-6215D01*
Y-517575D01*
X-6685Y-518205D01*
X-7234Y-518625D01*
X-8017Y-518835D01*
X-8800Y-518625D01*
X-9349Y-518205D01*
X-9819Y-517575D01*
X-10132Y-516840D01*
X-10289Y-516000D01*
Y-515265D01*
X-10132Y-514635D01*
X-9819Y-513900D01*
X-9349Y-513270D01*
X-8879Y-512850D01*
X-8252Y-512535D01*
X-7704D01*
X-7077Y-512745D01*
X-6607Y-513165D01*
G01X-3675Y-512535D02*
Y-517050D01*
X-3362Y-517995D01*
X-2735Y-518625D01*
X-1952Y-518835D01*
X-1169Y-518625D01*
X-542Y-517995D01*
X-229Y-517050D01*
Y-512535D01*
G01X3408D02*
X5288D01*
G01X4348D02*
Y-518835D01*
G01X3408D02*
X5288D01*
G01X9003Y-517995D02*
X9630Y-518520D01*
X10335Y-518835D01*
X10961D01*
X11588Y-518520D01*
X12058Y-517995D01*
X12293Y-517260D01*
X12136Y-516525D01*
X11745Y-515895D01*
X11040Y-515475D01*
X10100Y-515265D01*
X9551Y-514845D01*
X9316Y-514110D01*
X9473Y-513375D01*
X9865Y-512850D01*
X10413Y-512535D01*
X10961D01*
X11510Y-512745D01*
X11980Y-513270D01*
G01X15303Y-518835D02*
Y-512535D01*
G01X18593D02*
Y-518835D01*
G01Y-515685D02*
X15303D01*
G01X21290Y-518835D02*
X23248Y-512535D01*
X25206Y-518835D01*
G01X24501Y-516630D02*
X21995D01*
G01X27746Y-518835D02*
Y-512535D01*
X31350Y-518835D01*
Y-512535D01*
G01X40425Y-518835D02*
Y-512535D01*
X41991D01*
X42618Y-512850D01*
X43088Y-513270D01*
X43480Y-513900D01*
X43793Y-514635D01*
X43871Y-515685D01*
X43793Y-516735D01*
X43480Y-517470D01*
X43088Y-518100D01*
X42618Y-518520D01*
X41991Y-518835D01*
X40425D01*
G01X47508Y-512535D02*
X49388D01*
G01X48448D02*
Y-518835D01*
G01X47508D02*
X49388D01*
G01X53103Y-517995D02*
X53730Y-518520D01*
X54435Y-518835D01*
X55061D01*
X55688Y-518520D01*
X56158Y-517995D01*
X56393Y-517260D01*
X56236Y-516525D01*
X55845Y-515895D01*
X55140Y-515475D01*
X54200Y-515265D01*
X53651Y-514845D01*
X53416Y-514110D01*
X53573Y-513375D01*
X53965Y-512850D01*
X54513Y-512535D01*
X55061D01*
X55610Y-512745D01*
X56080Y-513270D01*
G01X61048Y-512535D02*
Y-518835D01*
G01X59246Y-512535D02*
X62850D01*
G01X67348Y-519045D02*
X67191Y-518940D01*
Y-518730D01*
X67348Y-518625D01*
X67505Y-518730D01*
Y-518940D01*
X67348Y-519045D01*
G01X73491Y-519990D02*
X73805Y-518625D01*
G01X79948Y-512535D02*
Y-518835D01*
G01X78146Y-512535D02*
X81750D01*
G01X84290Y-518835D02*
X86248Y-512535D01*
X88206Y-518835D01*
G01X87501Y-516630D02*
X84995D01*
G01X92548Y-518835D02*
X91921Y-518730D01*
X91373Y-518310D01*
X90903Y-517680D01*
X90590Y-516945D01*
X90433Y-516105D01*
Y-515265D01*
X90590Y-514425D01*
X90903Y-513690D01*
X91373Y-513060D01*
X91921Y-512640D01*
X92548Y-512535D01*
X93175Y-512640D01*
X93723Y-513060D01*
X94193Y-513690D01*
X94506Y-514425D01*
X94663Y-515265D01*
Y-516105D01*
X94506Y-516945D01*
X94193Y-517680D01*
X93723Y-518310D01*
X93175Y-518730D01*
X92548Y-518835D01*
G01X98848D02*
Y-516000D01*
X97281Y-512535D01*
G01X100415D02*
X98848Y-516000D01*
G01X103425Y-512535D02*
Y-517050D01*
X103738Y-517995D01*
X104365Y-518625D01*
X105148Y-518835D01*
X105931Y-518625D01*
X106558Y-517995D01*
X106871Y-517050D01*
Y-512535D01*
G01X109490Y-518835D02*
X111448Y-512535D01*
X113406Y-518835D01*
G01X112701Y-516630D02*
X110195D01*
G01X115946Y-518835D02*
Y-512535D01*
X119550Y-518835D01*
Y-512535D01*
G01X-6529Y-523060D02*
X-6999Y-522745D01*
X-7547Y-522535D01*
X-8174D01*
X-8879Y-522850D01*
X-9427Y-523375D01*
X-9819Y-524005D01*
X-10132Y-525055D01*
X-10210Y-526000D01*
X-10054Y-526945D01*
X-9819Y-527575D01*
X-9349Y-528205D01*
X-8800Y-528625D01*
X-8252Y-528835D01*
X-7704D01*
X-7155Y-528625D01*
X-6685Y-528310D01*
X-6294Y-527890D01*
G01X-2892Y-522535D02*
X-1012D01*
G01X-1952D02*
Y-528835D01*
G01X-2892D02*
X-1012D01*
G01X4348Y-522535D02*
Y-528835D01*
G01X2546Y-522535D02*
X6150D01*
G01X10648Y-528835D02*
Y-526000D01*
X9081Y-522535D01*
G01X12215D02*
X10648Y-526000D01*
G01X21525Y-527575D02*
X21995Y-528310D01*
X22621Y-528730D01*
X23326Y-528835D01*
X23953Y-528730D01*
X24580Y-528205D01*
X24971Y-527575D01*
X25050Y-526945D01*
X24893Y-526210D01*
X24345Y-525685D01*
X23796Y-525475D01*
X23091D01*
G01X23796D02*
X24266Y-525160D01*
X24658Y-524635D01*
X24815Y-524005D01*
X24658Y-523375D01*
X24266Y-522850D01*
X23561Y-522535D01*
X22856Y-522640D01*
X22151Y-523060D01*
G01X27825Y-527575D02*
X28295Y-528310D01*
X28921Y-528730D01*
X29626Y-528835D01*
X30253Y-528730D01*
X30880Y-528205D01*
X31271Y-527575D01*
X31350Y-526945D01*
X31193Y-526210D01*
X30645Y-525685D01*
X30096Y-525475D01*
X29391D01*
G01X30096D02*
X30566Y-525160D01*
X30958Y-524635D01*
X31115Y-524005D01*
X30958Y-523375D01*
X30566Y-522850D01*
X29861Y-522535D01*
X29156Y-522640D01*
X28451Y-523060D01*
G01X34125Y-527575D02*
X34595Y-528310D01*
X35221Y-528730D01*
X35926Y-528835D01*
X36553Y-528730D01*
X37180Y-528205D01*
X37571Y-527575D01*
X37650Y-526945D01*
X37493Y-526210D01*
X36945Y-525685D01*
X36396Y-525475D01*
X35691D01*
G01X36396D02*
X36866Y-525160D01*
X37258Y-524635D01*
X37415Y-524005D01*
X37258Y-523375D01*
X36866Y-522850D01*
X36161Y-522535D01*
X35456Y-522640D01*
X34751Y-523060D01*
G01X41991Y-528835D02*
X42148Y-527470D01*
X42383Y-526315D01*
X42696Y-525265D01*
X43088Y-524110D01*
X43715Y-522535D01*
X40581D01*
G01X48291Y-528835D02*
X48448Y-527470D01*
X48683Y-526315D01*
X48996Y-525265D01*
X49388Y-524110D01*
X50015Y-522535D01*
X46881D01*
G01X54591Y-529990D02*
X54905Y-528625D01*
G01X61048Y-522535D02*
Y-528835D01*
G01X59246Y-522535D02*
X62850D01*
G01X65390Y-528835D02*
X67348Y-522535D01*
X69306Y-528835D01*
G01X68601Y-526630D02*
X66095D01*
G01X72708Y-522535D02*
X74588D01*
G01X73648D02*
Y-528835D01*
G01X72708D02*
X74588D01*
G01X77598Y-522535D02*
X78695Y-528835D01*
X79948Y-522535D01*
X81201Y-528835D01*
X82298Y-522535D01*
G01X84290Y-528835D02*
X86248Y-522535D01*
X88206Y-528835D01*
G01X87501Y-526630D02*
X84995D01*
G01X90746Y-528835D02*
Y-522535D01*
X94350Y-528835D01*
Y-522535D01*
G01X104756Y-530935D02*
X103973Y-529885D01*
X103581Y-528835D01*
Y-524635D01*
X103973Y-523585D01*
X104756Y-522535D01*
G01X116181Y-528835D02*
Y-522535D01*
X118140D01*
X118766Y-522850D01*
X119158Y-523270D01*
X119315Y-524110D01*
X119158Y-524950D01*
X118688Y-525475D01*
X118140Y-525790D01*
X116181D01*
G01X118140D02*
X119315Y-528835D01*
G01X124048Y-529045D02*
X123891Y-528940D01*
Y-528730D01*
X124048Y-528625D01*
X124205Y-528730D01*
Y-528940D01*
X124048Y-529045D01*
G01X130348Y-528835D02*
X129721Y-528730D01*
X129173Y-528310D01*
X128703Y-527680D01*
X128390Y-526945D01*
X128233Y-526105D01*
Y-525265D01*
X128390Y-524425D01*
X128703Y-523690D01*
X129173Y-523060D01*
X129721Y-522640D01*
X130348Y-522535D01*
X130975Y-522640D01*
X131523Y-523060D01*
X131993Y-523690D01*
X132306Y-524425D01*
X132463Y-525265D01*
Y-526105D01*
X132306Y-526945D01*
X131993Y-527680D01*
X131523Y-528310D01*
X130975Y-528730D01*
X130348Y-528835D01*
G01X136648Y-529045D02*
X136491Y-528940D01*
Y-528730D01*
X136648Y-528625D01*
X136805Y-528730D01*
Y-528940D01*
X136648Y-529045D01*
G01X144671Y-523060D02*
X144201Y-522745D01*
X143653Y-522535D01*
X143026D01*
X142321Y-522850D01*
X141773Y-523375D01*
X141381Y-524005D01*
X141068Y-525055D01*
X140990Y-526000D01*
X141146Y-526945D01*
X141381Y-527575D01*
X141851Y-528205D01*
X142400Y-528625D01*
X142948Y-528835D01*
X143496D01*
X144045Y-528625D01*
X144515Y-528310D01*
X144906Y-527890D01*
G01X149248Y-529045D02*
X149091Y-528940D01*
Y-528730D01*
X149248Y-528625D01*
X149405Y-528730D01*
Y-528940D01*
X149248Y-529045D01*
G01X155940Y-530935D02*
X156723Y-529885D01*
X157115Y-528835D01*
Y-524635D01*
X156723Y-523585D01*
X155940Y-522535D01*
G01X-10054Y-508835D02*
Y-502535D01*
X-6450Y-508835D01*
Y-502535D01*
G01X-1952Y-508835D02*
X-2579Y-508730D01*
X-3127Y-508310D01*
X-3597Y-507680D01*
X-3910Y-506945D01*
X-4067Y-506105D01*
Y-505265D01*
X-3910Y-504425D01*
X-3597Y-503690D01*
X-3127Y-503060D01*
X-2579Y-502640D01*
X-1952Y-502535D01*
X-1325Y-502640D01*
X-777Y-503060D01*
X-307Y-503690D01*
X6Y-504425D01*
X163Y-505265D01*
Y-506105D01*
X6Y-506945D01*
X-307Y-507680D01*
X-777Y-508310D01*
X-1325Y-508730D01*
X-1952Y-508835D01*
G01X4348Y-509045D02*
X4191Y-508940D01*
Y-508730D01*
X4348Y-508625D01*
X4505Y-508730D01*
Y-508940D01*
X4348Y-509045D01*
G01X9160Y-503585D02*
X9630Y-502955D01*
X10178Y-502640D01*
X10805Y-502535D01*
X11588Y-502745D01*
X12136Y-503270D01*
X12293Y-503900D01*
X12215Y-504530D01*
X11901Y-505055D01*
X10335Y-506105D01*
X9630Y-506840D01*
X9160Y-507890D01*
X9003Y-508835D01*
X12293D01*
G01X16948D02*
Y-502535D01*
X16008Y-503795D01*
G01Y-508835D02*
X17888D01*
G01X23248D02*
Y-502535D01*
X22308Y-503795D01*
G01Y-508835D02*
X24188D01*
G01X29391Y-509990D02*
X29705Y-508625D01*
G01X33498Y-502535D02*
X34595Y-508835D01*
X35848Y-502535D01*
X37101Y-508835D01*
X38198Y-502535D01*
G01X43715Y-508835D02*
X40581D01*
Y-502535D01*
X43715D01*
G01X42461Y-505580D02*
X40581D01*
G01X46646Y-508835D02*
Y-502535D01*
X50250Y-508835D01*
Y-502535D01*
G01X53103Y-508835D02*
Y-502535D01*
G01X56393D02*
Y-508835D01*
G01Y-505685D02*
X53103D01*
G01X59325Y-502535D02*
Y-507050D01*
X59638Y-507995D01*
X60265Y-508625D01*
X61048Y-508835D01*
X61831Y-508625D01*
X62458Y-507995D01*
X62771Y-507050D01*
Y-502535D01*
G01X65390Y-508835D02*
X67348Y-502535D01*
X69306Y-508835D01*
G01X68601Y-506630D02*
X66095D01*
G01X78460Y-503585D02*
X78930Y-502955D01*
X79478Y-502640D01*
X80105Y-502535D01*
X80888Y-502745D01*
X81436Y-503270D01*
X81593Y-503900D01*
X81515Y-504530D01*
X81201Y-505055D01*
X79635Y-506105D01*
X78930Y-506840D01*
X78460Y-507890D01*
X78303Y-508835D01*
X81593D01*
G01X84446D02*
Y-502535D01*
X88050Y-508835D01*
Y-502535D01*
G01X90825Y-508835D02*
Y-502535D01*
X92391D01*
X93018Y-502850D01*
X93488Y-503270D01*
X93880Y-503900D01*
X94193Y-504635D01*
X94271Y-505685D01*
X94193Y-506735D01*
X93880Y-507470D01*
X93488Y-508100D01*
X93018Y-508520D01*
X92391Y-508835D01*
X90825D01*
G01X103581D02*
Y-502535D01*
X105540D01*
X106166Y-502850D01*
X106558Y-503270D01*
X106715Y-504110D01*
X106558Y-504950D01*
X106088Y-505475D01*
X105540Y-505790D01*
X103581D01*
G01X105540D02*
X106715Y-508835D01*
G01X109725D02*
Y-502535D01*
X111291D01*
X111918Y-502850D01*
X112388Y-503270D01*
X112780Y-503900D01*
X113093Y-504635D01*
X113171Y-505685D01*
X113093Y-506735D01*
X112780Y-507470D01*
X112388Y-508100D01*
X111918Y-508520D01*
X111291Y-508835D01*
X109725D01*
G01X117748Y-509045D02*
X117591Y-508940D01*
Y-508730D01*
X117748Y-508625D01*
X117905Y-508730D01*
Y-508940D01*
X117748Y-509045D01*
G01X14048Y-498135D02*
X11528Y-497718D01*
X9323Y-496052D01*
X7433Y-493552D01*
X6173Y-490635D01*
X5543Y-487302D01*
Y-483968D01*
X6173Y-480635D01*
X7433Y-477718D01*
X9323Y-475219D01*
X11528Y-473552D01*
X14048Y-473135D01*
X16568Y-473552D01*
X18773Y-475219D01*
X20663Y-477718D01*
X21923Y-480635D01*
X22553Y-483968D01*
Y-487302D01*
X21923Y-490635D01*
X20663Y-493552D01*
X18773Y-496052D01*
X16568Y-497718D01*
X14048Y-498135D01*
G01X16568Y-491468D02*
X20348Y-498135D01*
G01X33893Y-481469D02*
Y-493135D01*
X35153Y-496052D01*
X37043Y-497718D01*
X39248Y-498135D01*
X41453Y-497718D01*
X43343Y-496052D01*
X44603Y-493135D01*
G01Y-498135D02*
Y-481469D01*
G01X70118Y-498135D02*
Y-481469D01*
G01Y-484385D02*
X68858Y-482719D01*
X66968Y-481885D01*
X64763Y-481469D01*
X62558Y-482302D01*
X60668Y-483968D01*
X59408Y-486469D01*
X58778Y-489802D01*
X59408Y-493135D01*
X60668Y-495636D01*
X62558Y-497302D01*
X64763Y-498135D01*
X66968Y-497718D01*
X68858Y-496469D01*
X70118Y-494802D01*
G01X84293Y-498135D02*
Y-481469D01*
G01Y-485635D02*
X85553Y-483552D01*
X87443Y-481885D01*
X89963Y-481469D01*
X92168Y-481885D01*
X94058Y-483552D01*
X95003Y-486469D01*
Y-498135D01*
G01X114848Y-473135D02*
Y-498135D01*
G01X110438Y-481469D02*
X119258D01*
G01X145718Y-498135D02*
Y-481469D01*
G01Y-484385D02*
X144458Y-482719D01*
X142568Y-481885D01*
X140363Y-481469D01*
X138158Y-482302D01*
X136268Y-483968D01*
X135008Y-486469D01*
X134378Y-489802D01*
X135008Y-493135D01*
X136268Y-495636D01*
X138158Y-497302D01*
X140363Y-498135D01*
X142568Y-497718D01*
X144458Y-496469D01*
X145718Y-494802D01*
G01X185398Y-477835D02*
Y-485835D01*
X189398D01*
G01X197198D02*
Y-480502D01*
G01Y-481435D02*
X196798Y-480902D01*
X196198Y-480635D01*
X195498Y-480502D01*
X194798Y-480768D01*
X194198Y-481302D01*
X193798Y-482102D01*
X193598Y-483168D01*
X193798Y-484235D01*
X194198Y-485035D01*
X194798Y-485568D01*
X195498Y-485835D01*
X196198Y-485702D01*
X196798Y-485302D01*
X197198Y-484769D01*
G01X201298Y-488235D02*
X201898Y-488502D01*
X202698Y-488235D01*
X203198Y-487702D01*
X203598Y-487035D01*
X204198Y-484902D01*
X205498Y-480502D01*
G01X202298D02*
X204198Y-484902D01*
G01X209898Y-482235D02*
X213098D01*
X212798Y-481302D01*
X212298Y-480768D01*
X211598Y-480502D01*
X210898Y-480635D01*
X210298Y-481035D01*
X209898Y-481968D01*
X209698Y-482769D01*
Y-483568D01*
X209898Y-484368D01*
X210398Y-485168D01*
X210998Y-485702D01*
X211698Y-485835D01*
X212398Y-485568D01*
X213098Y-484769D01*
G01X217998Y-485835D02*
Y-480502D01*
G01Y-481568D02*
X218498Y-481035D01*
X218998Y-480635D01*
X219698Y-480502D01*
X220198Y-480635D01*
X220798Y-481035D01*
G01X211398Y-535835D02*
Y-532235D01*
X209398Y-527835D01*
G01X213398D02*
X211398Y-532235D01*
G01X217698Y-530502D02*
Y-534235D01*
X218098Y-535168D01*
X218698Y-535702D01*
X219398Y-535835D01*
X220098Y-535702D01*
X220698Y-535168D01*
X221098Y-534235D01*
G01Y-535835D02*
Y-530502D01*
G01X225698Y-535835D02*
Y-530502D01*
G01Y-531835D02*
X226098Y-531168D01*
X226698Y-530635D01*
X227498Y-530502D01*
X228198Y-530635D01*
X228798Y-531168D01*
X229098Y-532102D01*
Y-535835D01*
G01X237198D02*
Y-530502D01*
G01Y-531435D02*
X236798Y-530902D01*
X236198Y-530635D01*
X235498Y-530502D01*
X234798Y-530768D01*
X234198Y-531302D01*
X233798Y-532102D01*
X233598Y-533168D01*
X233798Y-534235D01*
X234198Y-535035D01*
X234798Y-535568D01*
X235498Y-535835D01*
X236198Y-535702D01*
X236798Y-535302D01*
X237198Y-534769D01*
G01X216998Y-506835D02*
X218998D01*
Y-509235D01*
X218398Y-510035D01*
X217698Y-510568D01*
X216698Y-510835D01*
X215698Y-510568D01*
X214998Y-510035D01*
X214398Y-509235D01*
X213998Y-508302D01*
X213798Y-507235D01*
Y-506302D01*
X213998Y-505502D01*
X214398Y-504568D01*
X214998Y-503768D01*
X215598Y-503235D01*
X216398Y-502835D01*
X217098D01*
X217898Y-503102D01*
X218498Y-503635D01*
G01X222098Y-510835D02*
Y-502835D01*
X226698Y-510835D01*
Y-502835D01*
G01X230198Y-510835D02*
Y-502835D01*
X232198D01*
X232998Y-503235D01*
X233598Y-503768D01*
X234098Y-504568D01*
X234498Y-505502D01*
X234598Y-506835D01*
X234498Y-508168D01*
X234098Y-509102D01*
X233598Y-509902D01*
X232998Y-510435D01*
X232198Y-510835D01*
X230198D01*
G01X240398D02*
Y-502835D01*
X239198Y-504435D01*
G01Y-510835D02*
X241598D01*
G01X236698Y-484635D02*
X237298Y-485302D01*
X237998Y-485702D01*
X238898Y-485835D01*
X239798Y-485568D01*
X240498Y-485035D01*
X240998Y-484102D01*
X241098Y-483035D01*
X240898Y-481968D01*
X240398Y-481302D01*
X239698Y-480768D01*
X238998Y-480635D01*
X238298Y-480768D01*
X237398Y-481302D01*
X237698Y-477835D01*
X240398D01*
G01X311998Y-529168D02*
X312598Y-528368D01*
X313298Y-527968D01*
X314098Y-527835D01*
X315098Y-528102D01*
X315798Y-528768D01*
X315998Y-529568D01*
X315898Y-530369D01*
X315498Y-531035D01*
X313498Y-532368D01*
X312598Y-533302D01*
X311998Y-534635D01*
X311798Y-535835D01*
X315998D01*
G01X321898Y-527835D02*
X321098Y-528102D01*
X320498Y-528768D01*
X320098Y-529568D01*
X319798Y-530635D01*
X319698Y-531835D01*
X319798Y-533035D01*
X320098Y-534102D01*
X320498Y-534902D01*
X321098Y-535568D01*
X321898Y-535835D01*
X322698Y-535568D01*
X323298Y-534902D01*
X323698Y-534102D01*
X323998Y-533035D01*
X324098Y-531835D01*
X323998Y-530635D01*
X323698Y-529568D01*
X323298Y-528768D01*
X322698Y-528102D01*
X321898Y-527835D01*
G01X327998Y-529168D02*
X328598Y-528368D01*
X329298Y-527968D01*
X330098Y-527835D01*
X331098Y-528102D01*
X331798Y-528768D01*
X331998Y-529568D01*
X331898Y-530369D01*
X331498Y-531035D01*
X329498Y-532368D01*
X328598Y-533302D01*
X327998Y-534635D01*
X327798Y-535835D01*
X331998D01*
G01X335698Y-534235D02*
X336298Y-535168D01*
X337098Y-535702D01*
X337998Y-535835D01*
X338798Y-535702D01*
X339598Y-535035D01*
X340098Y-534235D01*
X340198Y-533435D01*
X339998Y-532502D01*
X339298Y-531835D01*
X338598Y-531568D01*
X337698D01*
G01X338598D02*
X339198Y-531168D01*
X339698Y-530502D01*
X339898Y-529702D01*
X339698Y-528902D01*
X339198Y-528235D01*
X338298Y-527835D01*
X337398Y-527968D01*
X336498Y-528502D01*
G01X344098Y-536102D02*
X347698Y-527835D01*
G01X353898D02*
X353098Y-528102D01*
X352498Y-528768D01*
X352098Y-529568D01*
X351798Y-530635D01*
X351698Y-531835D01*
X351798Y-533035D01*
X352098Y-534102D01*
X352498Y-534902D01*
X353098Y-535568D01*
X353898Y-535835D01*
X354698Y-535568D01*
X355298Y-534902D01*
X355698Y-534102D01*
X355998Y-533035D01*
X356098Y-531835D01*
X355998Y-530635D01*
X355698Y-529568D01*
X355298Y-528768D01*
X354698Y-528102D01*
X353898Y-527835D01*
G01X361898Y-535835D02*
Y-527835D01*
X360698Y-529435D01*
G01Y-535835D02*
X363098D01*
G01X368098Y-536102D02*
X371698Y-527835D01*
G01X377898D02*
X377098Y-528102D01*
X376498Y-528768D01*
X376098Y-529568D01*
X375798Y-530635D01*
X375698Y-531835D01*
X375798Y-533035D01*
X376098Y-534102D01*
X376498Y-534902D01*
X377098Y-535568D01*
X377898Y-535835D01*
X378698Y-535568D01*
X379298Y-534902D01*
X379698Y-534102D01*
X379998Y-533035D01*
X380098Y-531835D01*
X379998Y-530635D01*
X379698Y-529568D01*
X379298Y-528768D01*
X378698Y-528102D01*
X377898Y-527835D01*
G01X384198Y-534902D02*
X384898Y-535568D01*
X385698Y-535835D01*
X386498Y-535568D01*
X387198Y-534769D01*
X387698Y-533568D01*
X387898Y-532368D01*
Y-530902D01*
X387698Y-529702D01*
X387198Y-528635D01*
X386598Y-528102D01*
X385898Y-527835D01*
X385098Y-528102D01*
X384498Y-528635D01*
X384098Y-529435D01*
X383898Y-530502D01*
X384098Y-531435D01*
X384598Y-532368D01*
X385198Y-532902D01*
X385898Y-533035D01*
X386698Y-532769D01*
X387298Y-532102D01*
X387898Y-530902D01*
G01X311698Y-510835D02*
Y-502835D01*
X313698D01*
X314498Y-503235D01*
X315098Y-503768D01*
X315598Y-504568D01*
X315998Y-505502D01*
X316098Y-506835D01*
X315998Y-508168D01*
X315598Y-509102D01*
X315098Y-509902D01*
X314498Y-510435D01*
X313698Y-510835D01*
X311698D01*
G01X319398D02*
X321898Y-502835D01*
X324398Y-510835D01*
G01X323498Y-508035D02*
X320298D01*
G01X329898Y-502835D02*
X329098Y-503102D01*
X328498Y-503768D01*
X328098Y-504568D01*
X327798Y-505635D01*
X327698Y-506835D01*
X327798Y-508035D01*
X328098Y-509102D01*
X328498Y-509902D01*
X329098Y-510568D01*
X329898Y-510835D01*
X330698Y-510568D01*
X331298Y-509902D01*
X331698Y-509102D01*
X331998Y-508035D01*
X332098Y-506835D01*
X331998Y-505635D01*
X331698Y-504568D01*
X331298Y-503768D01*
X330698Y-503102D01*
X329898Y-502835D01*
G01X335998Y-510835D02*
Y-502835D01*
X339798D01*
G01X338398Y-506702D02*
X335998D01*
G01X345898Y-502835D02*
X345098Y-503102D01*
X344498Y-503768D01*
X344098Y-504568D01*
X343798Y-505635D01*
X343698Y-506835D01*
X343798Y-508035D01*
X344098Y-509102D01*
X344498Y-509902D01*
X345098Y-510568D01*
X345898Y-510835D01*
X346698Y-510568D01*
X347298Y-509902D01*
X347698Y-509102D01*
X347998Y-508035D01*
X348098Y-506835D01*
X347998Y-505635D01*
X347698Y-504568D01*
X347298Y-503768D01*
X346698Y-503102D01*
X345898Y-502835D01*
G01X353898D02*
Y-510835D01*
G01X351598Y-502835D02*
X356198D01*
G01X363898Y-510835D02*
X359898D01*
Y-502835D01*
X363898D01*
G01X362298Y-506702D02*
X359898D01*
G01X370698Y-506568D02*
X371098Y-506168D01*
X371398Y-505502D01*
X371598Y-504568D01*
X371398Y-503768D01*
X370998Y-503235D01*
X370298Y-502835D01*
X367598D01*
Y-510835D01*
X370898D01*
X371598Y-510302D01*
X371998Y-509502D01*
X372198Y-508568D01*
X371998Y-507635D01*
X371398Y-506835D01*
X370698Y-506568D01*
X367598D01*
G01X376698Y-502835D02*
X379098D01*
G01X377898D02*
Y-510835D01*
G01X376698D02*
X379098D01*
G01X383998D02*
Y-502835D01*
X387798D01*
G01X386398Y-506702D02*
X383998D01*
G01X393898Y-502835D02*
X393098Y-503102D01*
X392498Y-503768D01*
X392098Y-504568D01*
X391798Y-505635D01*
X391698Y-506835D01*
X391798Y-508035D01*
X392098Y-509102D01*
X392498Y-509902D01*
X393098Y-510568D01*
X393898Y-510835D01*
X394698Y-510568D01*
X395298Y-509902D01*
X395698Y-509102D01*
X395998Y-508035D01*
X396098Y-506835D01*
X395998Y-505635D01*
X395698Y-504568D01*
X395298Y-503768D01*
X394698Y-503102D01*
X393898Y-502835D01*
G01X329498Y-485835D02*
Y-477835D01*
X333298D01*
G01X331898Y-481702D02*
X329498D01*
G01X339398Y-477835D02*
X338598Y-478102D01*
X337998Y-478768D01*
X337598Y-479568D01*
X337298Y-480635D01*
X337198Y-481835D01*
X337298Y-483035D01*
X337598Y-484102D01*
X337998Y-484902D01*
X338598Y-485568D01*
X339398Y-485835D01*
X340198Y-485568D01*
X340798Y-484902D01*
X341198Y-484102D01*
X341498Y-483035D01*
X341598Y-481835D01*
X341498Y-480635D01*
X341198Y-479568D01*
X340798Y-478768D01*
X340198Y-478102D01*
X339398Y-477835D01*
G01X347398D02*
Y-485835D01*
G01X345098Y-477835D02*
X349698D01*
G01X352398Y-488502D02*
X358398D01*
G01X361898Y-482235D02*
X365098D01*
X364798Y-481302D01*
X364298Y-480768D01*
X363598Y-480502D01*
X362898Y-480635D01*
X362298Y-481035D01*
X361898Y-481968D01*
X361698Y-482769D01*
Y-483568D01*
X361898Y-484368D01*
X362398Y-485168D01*
X362998Y-485702D01*
X363698Y-485835D01*
X364398Y-485568D01*
X365098Y-484769D01*
G01X369898Y-480502D02*
X372898Y-485835D01*
G01Y-480502D02*
X369898Y-485835D01*
G01X377598Y-488502D02*
Y-480502D01*
G01Y-481702D02*
X378098Y-481035D01*
X378598Y-480635D01*
X379398Y-480502D01*
X380098Y-480635D01*
X380798Y-481302D01*
X381098Y-482235D01*
X381198Y-483168D01*
X381098Y-484102D01*
X380798Y-485035D01*
X380198Y-485568D01*
X379398Y-485835D01*
X378698Y-485702D01*
X377998Y-485302D01*
X377598Y-484769D01*
G01X389198Y-485835D02*
Y-480502D01*
G01Y-481435D02*
X388798Y-480902D01*
X388198Y-480635D01*
X387498Y-480502D01*
X386798Y-480768D01*
X386198Y-481302D01*
X385798Y-482102D01*
X385598Y-483168D01*
X385798Y-484235D01*
X386198Y-485035D01*
X386798Y-485568D01*
X387498Y-485835D01*
X388198Y-485702D01*
X388798Y-485302D01*
X389198Y-484769D01*
G01X393698Y-485835D02*
Y-480502D01*
G01Y-481835D02*
X394098Y-481168D01*
X394698Y-480635D01*
X395498Y-480502D01*
X396198Y-480635D01*
X396798Y-481168D01*
X397098Y-482102D01*
Y-485835D01*
G01X405198Y-477835D02*
Y-485835D01*
G01Y-484635D02*
X404798Y-485302D01*
X404198Y-485702D01*
X403498Y-485835D01*
X402698Y-485568D01*
X402098Y-484902D01*
X401698Y-484102D01*
X401598Y-483168D01*
X401698Y-482235D01*
X402098Y-481435D01*
X402698Y-480768D01*
X403498Y-480502D01*
X404198Y-480635D01*
X404698Y-480902D01*
X405198Y-481435D01*
G01X409898Y-482235D02*
X413098D01*
X412798Y-481302D01*
X412298Y-480768D01*
X411598Y-480502D01*
X410898Y-480635D01*
X410298Y-481035D01*
X409898Y-481968D01*
X409698Y-482769D01*
Y-483568D01*
X409898Y-484368D01*
X410398Y-485168D01*
X410998Y-485702D01*
X411698Y-485835D01*
X412398Y-485568D01*
X413098Y-484769D01*
G01X417998Y-485835D02*
Y-480502D01*
G01Y-481568D02*
X418498Y-481035D01*
X418998Y-480635D01*
X419698Y-480502D01*
X420198Y-480635D01*
X420798Y-481035D01*
G01X424398Y-488502D02*
X430398D01*
G01X433598Y-485835D02*
Y-477835D01*
G01Y-481835D02*
X434098Y-481035D01*
X434698Y-480635D01*
X435298Y-480502D01*
X436198Y-480768D01*
X436798Y-481302D01*
X437198Y-482235D01*
Y-483302D01*
X436998Y-484368D01*
X436598Y-485168D01*
X435898Y-485702D01*
X435298Y-485835D01*
X434698Y-485702D01*
X434098Y-485302D01*
X433598Y-484635D01*
G01X445198Y-477835D02*
Y-485835D01*
G01Y-484635D02*
X444798Y-485302D01*
X444198Y-485702D01*
X443498Y-485835D01*
X442698Y-485568D01*
X442098Y-484902D01*
X441698Y-484102D01*
X441598Y-483168D01*
X441698Y-482235D01*
X442098Y-481435D01*
X442698Y-480768D01*
X443498Y-480502D01*
X444198Y-480635D01*
X444698Y-480902D01*
X445198Y-481435D01*
G01X400398Y-538835D02*
Y-530835D01*
X399198Y-532435D01*
G01Y-538835D02*
X401598D01*
G01X406498Y-535502D02*
X407198Y-534568D01*
X407798Y-534035D01*
X408598Y-533768D01*
X409298Y-534035D01*
X409798Y-534568D01*
X410198Y-535368D01*
X410298Y-536302D01*
X410198Y-537102D01*
X409798Y-537902D01*
X409198Y-538568D01*
X408498Y-538835D01*
X407698Y-538568D01*
X406998Y-537769D01*
X406598Y-536568D01*
X406498Y-535235D01*
X406698Y-533502D01*
X406998Y-532568D01*
X407498Y-531635D01*
X408198Y-530968D01*
X408898Y-530835D01*
X409598Y-531102D01*
X410098Y-531768D01*
G01X416398Y-539102D02*
X416198Y-538968D01*
Y-538702D01*
X416398Y-538568D01*
X416598Y-538702D01*
Y-538968D01*
X416398Y-539102D01*
G01X422498Y-535502D02*
X423198Y-534568D01*
X423798Y-534035D01*
X424598Y-533768D01*
X425298Y-534035D01*
X425798Y-534568D01*
X426198Y-535368D01*
X426298Y-536302D01*
X426198Y-537102D01*
X425798Y-537902D01*
X425198Y-538568D01*
X424498Y-538835D01*
X423698Y-538568D01*
X422998Y-537769D01*
X422598Y-536568D01*
X422498Y-535235D01*
X422698Y-533502D01*
X422998Y-532568D01*
X423498Y-531635D01*
X424198Y-530968D01*
X424898Y-530835D01*
X425598Y-531102D01*
X426098Y-531768D01*
G01X445398Y-538835D02*
Y-530835D01*
X444198Y-532435D01*
G01Y-538835D02*
X446598D01*
G01X453198D02*
X453398Y-537102D01*
X453698Y-535635D01*
X454098Y-534302D01*
X454598Y-532835D01*
X455398Y-530835D01*
X451398D01*
G01X461398Y-539102D02*
X461198Y-538968D01*
Y-538702D01*
X461398Y-538568D01*
X461598Y-538702D01*
Y-538968D01*
X461398Y-539102D01*
G01X467498Y-532168D02*
X468098Y-531368D01*
X468798Y-530968D01*
X469598Y-530835D01*
X470598Y-531102D01*
X471298Y-531768D01*
X471498Y-532568D01*
X471398Y-533369D01*
X470998Y-534035D01*
X468998Y-535368D01*
X468098Y-536302D01*
X467498Y-537635D01*
X467298Y-538835D01*
X471498D01*
G01X465498Y-513835D02*
Y-505835D01*
X469298D01*
G01X467898Y-509702D02*
X465498D01*
M02*
